(kicad_pcb
	(version 20260206)
	(generator "pcbnew")
	(generator_version "10.0")
	(general
		(thickness 1.6)
		(legacy_teardrops no)
	)
	(paper "A4")
	(layers
		(0 "F.Cu" signal "TOP")
		(4 "In1.Cu" signal "L2GND")
		(6 "In2.Cu" signal "L3VCC")
		(2 "B.Cu" signal "BOTTOM")
		(9 "F.Adhes" user "F.Adhesive")
		(11 "B.Adhes" user "B.Adhesive")
		(13 "F.Paste" user "Package Geometry/Pastemask Top")
		(15 "B.Paste" user "Package Geometry/Pastemask Bottom")
		(5 "F.SilkS" user "Ref Des/Silkscreen Top")
		(7 "B.SilkS" user "Ref Des/Silkscreen Bottom")
		(1 "F.Mask" user "Board Geometry/Soldermask Top")
		(3 "B.Mask" user "Board Geometry/Soldermask Bottom")
		(17 "Dwgs.User" user "User.Drawings")
		(19 "Cmts.User" user "User.Comments")
		(21 "Eco1.User" user "User.Eco1")
		(23 "Eco2.User" user "User.Eco2")
		(25 "Edge.Cuts" user "Board Geometry/Outline")
		(27 "Margin" user)
		(31 "F.CrtYd" user "Package Geometry/Place Bound Top")
		(29 "B.CrtYd" user "Package Geometry/Place Bound Bottom")
		(35 "F.Fab" user "Ref Des/Assembly Top")
		(33 "B.Fab" user "Ref Des/Assembly Bottom")
	)
	(setup
		(pad_to_mask_clearance 0)
		(allow_soldermask_bridges_in_footprints no)
		(tenting
			(front yes)
			(back yes)
		)
		(covering
			(front no)
			(back no)
		)
		(plugging
			(front no)
			(back no)
		)
		(capping no)
		(filling no)
		(pcbplotparams
			(layerselection 0x00000000_00000000_55555555_5755f5ff)
			(plot_on_all_layers_selection 0x00000000_00000000_00000000_00000000)
			(disableapertmacros no)
			(usegerberextensions no)
			(usegerberattributes yes)
			(usegerberadvancedattributes yes)
			(creategerberjobfile yes)
			(dashed_line_dash_ratio 12)
			(dashed_line_gap_ratio 3)
			(svgprecision 4)
			(plotframeref no)
			(mode 1)
			(useauxorigin no)
			(pdf_front_fp_property_popups yes)
			(pdf_back_fp_property_popups yes)
			(pdf_metadata yes)
			(pdf_single_document no)
			(dxfpolygonmode yes)
			(dxfimperialunits yes)
			(dxfusepcbnewfont yes)
			(psnegative no)
			(psa4output no)
			(plot_black_and_white yes)
			(sketchpadsonfab no)
			(plotpadnumbers no)
			(hidednponfab no)
			(sketchdnponfab yes)
			(crossoutdnponfab yes)
			(subtractmaskfromsilk no)
			(outputformat 1)
			(mirror no)
			(drillshape 1)
			(scaleselection 1)
			(outputdirectory "")
		)
	)
	(footprint ""
		(layer "F.Cu")
		(at 28.2956 -361.0864 -90)
		(property "Reference" "PR16"
			(at 0 0 270)
			(layer "F.SilkS")
			(hide yes)
			(effects
				(font
					(size 1.27 1.27)
				)
			)
		)
		(property "Value" "1KR2F-3-GP"
			(at 0.064008 -3.993896 270)
			(unlocked yes)
			(layer "F.Fab")
			(hide yes)
			(effects
				(font
					(size 1.016 1.016)
					(thickness 0.1524)
				)
			)
		)
		(property "Device Type" "R402H16"
			(at 0.064008 -5.517896 270)
			(unlocked yes)
			(layer "F.Fab")
			(hide yes)
			(effects
				(font
					(size 1.016 1.016)
					(thickness 0.1524)
				)
			)
		)
		(duplicate_pad_numbers_are_jumpers no)
		(fp_line
			(start -0.508 -0.9398)
			(end -0.508 0.9398)
			(stroke
				(width 0.1524)
				(type default)
			)
			(layer "F.SilkS")
		)
		(fp_line
			(start 0.508 -0.9398)
			(end -0.508 -0.9398)
			(stroke
				(width 0.1524)
				(type default)
			)
			(layer "F.SilkS")
		)
		(fp_rect
			(start -0.508 0.9398)
			(end 0.508 -0.9398)
			(stroke
				(width 0)
				(type default)
			)
			(fill no)
			(layer "F.CrtYd")
		)
		(fp_rect
			(start -0.508 0.9398)
			(end 0.508 -0.9398)
			(stroke
				(width 0)
				(type default)
			)
			(fill no)
			(layer "F.Fab")
		)
		(pad "1" smd custom
			(at 0 -0.4445 270)
			(size 0.1397 0.1397)
			(layers "F.Cu" "F.Mask" "F.Paste")
			(net "ADM1276_EN")
			(options
				(clearance outline)
				(anchor circle)
			)
			(primitives
				(gr_poly
					(pts
						(arc
							(start -0.1778 -0.2794)
							(mid -0.249642 -0.249642)
							(end -0.2794 -0.1778)
						)
						(arc
							(start -0.2794 0.1778)
							(mid -0.249642 0.249642)
							(end -0.1778 0.2794)
						)
						(arc
							(start 0.1778 0.2794)
							(mid 0.249642 0.249642)
							(end 0.2794 0.1778)
						)
						(arc
							(start 0.2794 -0.1778)
							(mid 0.249642 -0.249642)
							(end 0.1778 -0.2794)
						)
					)
					(width 0)
					(fill yes)
				)
			)
		)
		(pad "2" smd custom
			(at 0 0.4445 270)
			(size 0.1397 0.1397)
			(layers "F.Cu" "F.Mask" "F.Paste")
			(net "GND")
			(options
				(clearance outline)
				(anchor circle)
			)
			(primitives
				(gr_poly
					(pts
						(arc
							(start -0.1778 -0.2794)
							(mid -0.249642 -0.249642)
							(end -0.2794 -0.1778)
						)
						(arc
							(start -0.2794 0.1778)
							(mid -0.249642 0.249642)
							(end -0.1778 0.2794)
						)
						(arc
							(start 0.1778 0.2794)
							(mid 0.249642 0.249642)
							(end 0.2794 0.1778)
						)
						(arc
							(start 0.2794 -0.1778)
							(mid 0.249642 -0.249642)
							(end 0.1778 -0.2794)
						)
					)
					(width 0)
					(fill yes)
				)
			)
		)
	)
	(footprint ""
		(layer "F.Cu")
		(at 31.75 -357.048816)
		(property "Reference" "Q49"
			(at 0 0 0)
			(layer "F.SilkS")
			(hide yes)
			(effects
				(font
					(size 1.27 1.27)
				)
			)
		)
		(property "Value" "2N7002-11-GP"
			(at 0.127 -8.9662 0)
			(unlocked yes)
			(layer "F.Fab")
			(hide yes)
			(effects
				(font
					(size 1.016 1.016)
					(thickness 0.1524)
				)
			)
		)
		(property "Device Type" "SOT23DGS2D4H44"
			(at 0.127 -10.4902 0)
			(unlocked yes)
			(layer "F.Fab")
			(hide yes)
			(effects
				(font
					(size 1.016 1.016)
					(thickness 0.1524)
				)
			)
		)
		(duplicate_pad_numbers_are_jumpers no)
		(fp_line
			(start -1.651 -1.778)
			(end -1.651 1.778)
			(stroke
				(width 0.1524)
				(type default)
			)
			(layer "F.SilkS")
		)
		(fp_line
			(start -1.651 1.778)
			(end 1.651 1.778)
			(stroke
				(width 0.1524)
				(type default)
			)
			(layer "F.SilkS")
		)
		(fp_line
			(start 1.651 -1.778)
			(end -1.651 -1.778)
			(stroke
				(width 0.1524)
				(type default)
			)
			(layer "F.SilkS")
		)
		(fp_line
			(start 1.651 1.778)
			(end 1.651 -1.778)
			(stroke
				(width 0.1524)
				(type default)
			)
			(layer "F.SilkS")
		)
		(fp_poly
			(pts
				(xy -1.778 1.8796) (xy -1.778 -1.8796) (xy 1.778 -1.8796) (xy 1.778 1.8796)
			)
			(stroke
				(width 0)
				(type default)
			)
			(fill no)
			(layer "F.CrtYd")
		)
		(fp_poly
			(pts
				(xy -1.778 1.8796) (xy -1.778 -1.8796) (xy 1.778 -1.8796) (xy 1.778 1.8796)
			)
			(stroke
				(width 0)
				(type default)
			)
			(fill no)
			(layer "F.Fab")
		)
		(pad "D" smd custom
			(at 0 -0.9525)
			(size 0.1905 0.1905)
			(layers "F.Cu" "F.Mask" "F.Paste")
			(net "ADM1276_EN")
			(options
				(clearance outline)
				(anchor circle)
			)
			(primitives
				(gr_poly
					(pts
						(arc
							(start -0.1778 0.5715)
							(mid -0.321484 0.511984)
							(end -0.381 0.3683)
						)
						(arc
							(start -0.381 -0.3683)
							(mid -0.321484 -0.511984)
							(end -0.1778 -0.5715)
						)
						(arc
							(start 0.1778 -0.5715)
							(mid 0.321484 -0.511984)
							(end 0.381 -0.3683)
						)
						(arc
							(start 0.381 0.3683)
							(mid 0.321484 0.511984)
							(end 0.1778 0.5715)
						)
					)
					(width 0)
					(fill yes)
				)
			)
		)
		(pad "G" smd custom
			(at -0.98425 0.9525)
			(size 0.1905 0.1905)
			(layers "F.Cu" "F.Mask" "F.Paste")
			(net "OTP_RETRY_G")
			(options
				(clearance outline)
				(anchor circle)
			)
			(primitives
				(gr_poly
					(pts
						(arc
							(start -0.1778 0.5715)
							(mid -0.321484 0.511984)
							(end -0.381 0.3683)
						)
						(arc
							(start -0.381 -0.3683)
							(mid -0.321484 -0.511984)
							(end -0.1778 -0.5715)
						)
						(arc
							(start 0.1778 -0.5715)
							(mid 0.321484 -0.511984)
							(end 0.381 -0.3683)
						)
						(arc
							(start 0.381 0.3683)
							(mid 0.321484 0.511984)
							(end 0.1778 0.5715)
						)
					)
					(width 0)
					(fill yes)
				)
			)
		)
		(pad "S" smd custom
			(at 0.98425 0.9525)
			(size 0.1905 0.1905)
			(layers "F.Cu" "F.Mask" "F.Paste")
			(net "GND")
			(options
				(clearance outline)
				(anchor circle)
			)
			(primitives
				(gr_poly
					(pts
						(arc
							(start -0.1778 0.5715)
							(mid -0.321484 0.511984)
							(end -0.381 0.3683)
						)
						(arc
							(start -0.381 -0.3683)
							(mid -0.321484 -0.511984)
							(end -0.1778 -0.5715)
						)
						(arc
							(start 0.1778 -0.5715)
							(mid 0.321484 -0.511984)
							(end 0.381 -0.3683)
						)
						(arc
							(start 0.381 0.3683)
							(mid 0.321484 0.511984)
							(end 0.1778 0.5715)
						)
					)
					(width 0)
					(fill yes)
				)
			)
		)
	)
	(footprint ""
		(layer "F.Cu")
		(at 17.6276 -290.703 -90)
		(property "Reference" "C43"
			(at 0 0 270)
			(layer "F.SilkS")
			(hide yes)
			(effects
				(font
					(size 1.27 1.27)
				)
			)
		)
		(property "Value" "SCD1U16V2KX-3GP"
			(at 1.1811 -2.7051 270)
			(unlocked yes)
			(layer "F.Fab")
			(hide yes)
			(effects
				(font
					(size 1.016 1.016)
					(thickness 0.1524)
				)
			)
		)
		(property "Device Type" "C402H22"
			(at 1.1811 -4.2291 270)
			(unlocked yes)
			(layer "F.Fab")
			(hide yes)
			(effects
				(font
					(size 1.016 1.016)
					(thickness 0.1524)
				)
			)
		)
		(duplicate_pad_numbers_are_jumpers no)
		(fp_rect
			(start -0.4318 0.9525)
			(end 0.4318 -0.9525)
			(stroke
				(width 0)
				(type default)
			)
			(fill no)
			(layer "F.CrtYd")
		)
		(fp_rect
			(start -0.4318 0.9525)
			(end 0.4318 -0.9525)
			(stroke
				(width 0)
				(type default)
			)
			(fill no)
			(layer "F.Fab")
		)
		(pad "1" smd custom
			(at 0 -0.4445 270)
			(size 0.1524 0.1524)
			(layers "F.Cu" "F.Mask" "F.Paste")
			(net "FAN_TACH3")
			(options
				(clearance outline)
				(anchor circle)
			)
			(primitives
				(gr_poly
					(pts
						(arc
							(start 0.3048 -0.2032)
							(mid 0.275042 -0.275042)
							(end 0.2032 -0.3048)
						)
						(arc
							(start -0.2032 -0.3048)
							(mid -0.275042 -0.275042)
							(end -0.3048 -0.2032)
						)
						(arc
							(start -0.3048 0.2032)
							(mid -0.275042 0.275042)
							(end -0.2032 0.3048)
						)
						(arc
							(start 0.2032 0.3048)
							(mid 0.275042 0.275042)
							(end 0.3048 0.2032)
						)
					)
					(width 0)
					(fill yes)
				)
			)
		)
		(pad "2" smd custom
			(at 0 0.4445 270)
			(size 0.1524 0.1524)
			(layers "F.Cu" "F.Mask" "F.Paste")
			(net "GND")
			(options
				(clearance outline)
				(anchor circle)
			)
			(primitives
				(gr_poly
					(pts
						(arc
							(start 0.3048 -0.2032)
							(mid 0.275042 -0.275042)
							(end 0.2032 -0.3048)
						)
						(arc
							(start -0.2032 -0.3048)
							(mid -0.275042 -0.275042)
							(end -0.3048 -0.2032)
						)
						(arc
							(start -0.3048 0.2032)
							(mid -0.275042 0.275042)
							(end -0.2032 0.3048)
						)
						(arc
							(start 0.2032 0.3048)
							(mid 0.275042 0.275042)
							(end 0.3048 0.2032)
						)
					)
					(width 0)
					(fill yes)
				)
			)
		)
	)
	(footprint ""
		(layer "F.Cu")
		(at 6.5786 -437.7436)
		(property "Reference" "R32"
			(at 0 0 0)
			(layer "F.SilkS")
			(hide yes)
			(effects
				(font
					(size 1.27 1.27)
				)
			)
		)
		(property "Value" "0R2J-2-GP"
			(at 0.064008 -3.993896 0)
			(unlocked yes)
			(layer "F.Fab")
			(hide yes)
			(effects
				(font
					(size 1.016 1.016)
					(thickness 0.1524)
				)
			)
		)
		(property "Device Type" "R402H16"
			(at 0.064008 -5.517896 0)
			(unlocked yes)
			(layer "F.Fab")
			(hide yes)
			(effects
				(font
					(size 1.016 1.016)
					(thickness 0.1524)
				)
			)
		)
		(duplicate_pad_numbers_are_jumpers no)
		(fp_line
			(start -0.508 -0.9398)
			(end -0.508 0.9398)
			(stroke
				(width 0.1524)
				(type default)
			)
			(layer "F.SilkS")
		)
		(fp_line
			(start 0.508 -0.9398)
			(end -0.508 -0.9398)
			(stroke
				(width 0.1524)
				(type default)
			)
			(layer "F.SilkS")
		)
		(fp_rect
			(start -0.508 0.9398)
			(end 0.508 -0.9398)
			(stroke
				(width 0)
				(type default)
			)
			(fill no)
			(layer "F.CrtYd")
		)
		(fp_rect
			(start -0.508 0.9398)
			(end 0.508 -0.9398)
			(stroke
				(width 0)
				(type default)
			)
			(fill no)
			(layer "F.Fab")
		)
		(pad "1" smd custom
			(at 0 -0.4445)
			(size 0.1397 0.1397)
			(layers "F.Cu" "F.Mask" "F.Paste")
			(net "LED_DR_LED0_K")
			(options
				(clearance outline)
				(anchor circle)
			)
			(primitives
				(gr_poly
					(pts
						(arc
							(start -0.1778 -0.2794)
							(mid -0.249642 -0.249642)
							(end -0.2794 -0.1778)
						)
						(arc
							(start -0.2794 0.1778)
							(mid -0.249642 0.249642)
							(end -0.1778 0.2794)
						)
						(arc
							(start 0.1778 0.2794)
							(mid 0.249642 0.249642)
							(end 0.2794 0.1778)
						)
						(arc
							(start 0.2794 -0.1778)
							(mid 0.249642 -0.249642)
							(end 0.1778 -0.2794)
						)
					)
					(width 0)
					(fill yes)
				)
			)
		)
		(pad "2" smd custom
			(at 0 0.4445)
			(size 0.1397 0.1397)
			(layers "F.Cu" "F.Mask" "F.Paste")
			(net "GND")
			(options
				(clearance outline)
				(anchor circle)
			)
			(primitives
				(gr_poly
					(pts
						(arc
							(start -0.1778 -0.2794)
							(mid -0.249642 -0.249642)
							(end -0.2794 -0.1778)
						)
						(arc
							(start -0.2794 0.1778)
							(mid -0.249642 0.249642)
							(end -0.1778 0.2794)
						)
						(arc
							(start 0.1778 0.2794)
							(mid 0.249642 0.249642)
							(end 0.2794 0.1778)
						)
						(arc
							(start 0.2794 -0.1778)
							(mid 0.249642 -0.249642)
							(end 0.1778 -0.2794)
						)
					)
					(width 0)
					(fill yes)
				)
			)
		)
	)
	(footprint ""
		(layer "F.Cu")
		(at 15.113 -56.134 -90)
		(property "Reference" "R361"
			(at 0 0 270)
			(layer "F.SilkS")
			(hide yes)
			(effects
				(font
					(size 1.27 1.27)
				)
			)
		)
		(property "Value" "100R2J-2-GP"
			(at 0.064008 -3.993896 270)
			(unlocked yes)
			(layer "F.Fab")
			(hide yes)
			(effects
				(font
					(size 1.016 1.016)
					(thickness 0.1524)
				)
			)
		)
		(property "Device Type" "R402H14"
			(at 0.064008 -5.517896 270)
			(unlocked yes)
			(layer "F.Fab")
			(hide yes)
			(effects
				(font
					(size 1.016 1.016)
					(thickness 0.1524)
				)
			)
		)
		(duplicate_pad_numbers_are_jumpers no)
		(fp_line
			(start -0.508 -0.9398)
			(end -0.508 0.9398)
			(stroke
				(width 0.1524)
				(type default)
			)
			(layer "F.SilkS")
		)
		(fp_line
			(start 0.508 -0.9398)
			(end -0.508 -0.9398)
			(stroke
				(width 0.1524)
				(type default)
			)
			(layer "F.SilkS")
		)
		(fp_rect
			(start -0.508 0.9398)
			(end 0.508 -0.9398)
			(stroke
				(width 0)
				(type default)
			)
			(fill no)
			(layer "F.CrtYd")
		)
		(fp_rect
			(start -0.508 0.9398)
			(end 0.508 -0.9398)
			(stroke
				(width 0)
				(type default)
			)
			(fill no)
			(layer "F.Fab")
		)
		(pad "1" smd custom
			(at 0 -0.4445 270)
			(size 0.1397 0.1397)
			(layers "F.Cu" "F.Mask" "F.Paste")
			(net "LOWER_TRAY_ID")
			(options
				(clearance outline)
				(anchor circle)
			)
			(primitives
				(gr_poly
					(pts
						(arc
							(start -0.1778 -0.2794)
							(mid -0.249642 -0.249642)
							(end -0.2794 -0.1778)
						)
						(arc
							(start -0.2794 0.1778)
							(mid -0.249642 0.249642)
							(end -0.1778 0.2794)
						)
						(arc
							(start 0.1778 0.2794)
							(mid 0.249642 0.249642)
							(end 0.2794 0.1778)
						)
						(arc
							(start 0.2794 -0.1778)
							(mid 0.249642 -0.249642)
							(end 0.1778 -0.2794)
						)
					)
					(width 0)
					(fill yes)
				)
			)
		)
		(pad "2" smd custom
			(at 0 0.4445 270)
			(size 0.1397 0.1397)
			(layers "F.Cu" "F.Mask" "F.Paste")
			(net "GND")
			(options
				(clearance outline)
				(anchor circle)
			)
			(primitives
				(gr_poly
					(pts
						(arc
							(start -0.1778 -0.2794)
							(mid -0.249642 -0.249642)
							(end -0.2794 -0.1778)
						)
						(arc
							(start -0.2794 0.1778)
							(mid -0.249642 0.249642)
							(end -0.1778 0.2794)
						)
						(arc
							(start 0.1778 0.2794)
							(mid 0.249642 0.249642)
							(end 0.2794 0.1778)
						)
						(arc
							(start 0.2794 -0.1778)
							(mid 0.249642 -0.249642)
							(end 0.1778 -0.2794)
						)
					)
					(width 0)
					(fill yes)
				)
			)
		)
	)
	(footprint ""
		(layer "F.Cu")
		(at 29.7942 -238.252 180)
		(property "Reference" "R40"
			(at 0 0 180)
			(layer "F.SilkS")
			(hide yes)
			(effects
				(font
					(size 1.27 1.27)
				)
			)
		)
		(property "Value" "4K7R2J-2-GP"
			(at 0.064008 -3.993896 180)
			(unlocked yes)
			(layer "F.Fab")
			(hide yes)
			(effects
				(font
					(size 1.016 1.016)
					(thickness 0.1524)
				)
			)
		)
		(property "Device Type" "R402H16"
			(at 0.064008 -5.517896 180)
			(unlocked yes)
			(layer "F.Fab")
			(hide yes)
			(effects
				(font
					(size 1.016 1.016)
					(thickness 0.1524)
				)
			)
		)
		(duplicate_pad_numbers_are_jumpers no)
		(fp_line
			(start 0.508 -0.9398)
			(end -0.508 -0.9398)
			(stroke
				(width 0.1524)
				(type default)
			)
			(layer "F.SilkS")
		)
		(fp_line
			(start -0.508 -0.9398)
			(end -0.508 0.9398)
			(stroke
				(width 0.1524)
				(type default)
			)
			(layer "F.SilkS")
		)
		(fp_rect
			(start -0.508 0.9398)
			(end 0.508 -0.9398)
			(stroke
				(width 0)
				(type default)
			)
			(fill no)
			(layer "F.CrtYd")
		)
		(fp_rect
			(start -0.508 0.9398)
			(end 0.508 -0.9398)
			(stroke
				(width 0)
				(type default)
			)
			(fill no)
			(layer "F.Fab")
		)
		(pad "1" smd custom
			(at 0 -0.4445 180)
			(size 0.1397 0.1397)
			(layers "F.Cu" "F.Mask" "F.Paste")
			(net "P3V3")
			(options
				(clearance outline)
				(anchor circle)
			)
			(primitives
				(gr_poly
					(pts
						(arc
							(start -0.1778 -0.2794)
							(mid -0.249642 -0.249642)
							(end -0.2794 -0.1778)
						)
						(arc
							(start -0.2794 0.1778)
							(mid -0.249642 0.249642)
							(end -0.1778 0.2794)
						)
						(arc
							(start 0.1778 0.2794)
							(mid 0.249642 0.249642)
							(end 0.2794 0.1778)
						)
						(arc
							(start 0.2794 -0.1778)
							(mid 0.249642 -0.249642)
							(end 0.1778 -0.2794)
						)
					)
					(width 0)
					(fill yes)
				)
			)
		)
		(pad "2" smd custom
			(at 0 0.4445 180)
			(size 0.1397 0.1397)
			(layers "F.Cu" "F.Mask" "F.Paste")
			(net "FCB_EEPROM_A1")
			(options
				(clearance outline)
				(anchor circle)
			)
			(primitives
				(gr_poly
					(pts
						(arc
							(start -0.1778 -0.2794)
							(mid -0.249642 -0.249642)
							(end -0.2794 -0.1778)
						)
						(arc
							(start -0.2794 0.1778)
							(mid -0.249642 0.249642)
							(end -0.1778 0.2794)
						)
						(arc
							(start 0.1778 0.2794)
							(mid 0.249642 0.249642)
							(end 0.2794 0.1778)
						)
						(arc
							(start 0.2794 -0.1778)
							(mid 0.249642 -0.249642)
							(end 0.1778 -0.2794)
						)
					)
					(width 0)
					(fill yes)
				)
			)
		)
	)
	(footprint ""
		(layer "F.Cu")
		(at 12.446 -394.081 -90)
		(property "Reference" "TC12"
			(at 0 0 270)
			(layer "F.SilkS")
			(hide yes)
			(effects
				(font
					(size 1.27 1.27)
				)
			)
		)
		(property "Value" "ST15U25VDM-1-GP"
			(at 0 -9.6012 270)
			(unlocked yes)
			(layer "F.Fab")
			(hide yes)
			(effects
				(font
					(size 1.016 1.016)
					(thickness 0.1524)
				)
			)
		)
		(property "Device Type" "CT7343H79"
			(at 0 -11.1252 270)
			(unlocked yes)
			(layer "F.Fab")
			(hide yes)
			(effects
				(font
					(size 1.016 1.016)
					(thickness 0.1524)
				)
			)
		)
		(duplicate_pad_numbers_are_jumpers no)
		(fp_line
			(start -2.286 4.8768)
			(end -2.286 2.032)
			(stroke
				(width 0.1524)
				(type default)
			)
			(layer "F.SilkS")
		)
		(fp_line
			(start 2.286 4.8768)
			(end -2.286 4.8768)
			(stroke
				(width 0.1524)
				(type default)
			)
			(layer "F.SilkS")
		)
		(fp_line
			(start 2.286 2.032)
			(end 2.286 4.8768)
			(stroke
				(width 0.1524)
				(type default)
			)
			(layer "F.SilkS")
		)
		(fp_line
			(start 2.286 -2.032)
			(end 2.286 -4.8768)
			(stroke
				(width 0.1524)
				(type default)
			)
			(layer "F.SilkS")
		)
		(fp_line
			(start 2.1082 -4.699)
			(end -2.1082 -4.699)
			(stroke
				(width 0.508)
				(type default)
			)
			(layer "F.SilkS")
		)
		(fp_line
			(start -2.286 -4.8768)
			(end -2.286 -2.032)
			(stroke
				(width 0.1524)
				(type default)
			)
			(layer "F.SilkS")
		)
		(fp_line
			(start 2.286 -4.8768)
			(end -2.286 -4.8768)
			(stroke
				(width 0.1524)
				(type default)
			)
			(layer "F.SilkS")
		)
		(fp_rect
			(start -2.1463 3.6449)
			(end 2.1463 -3.6449)
			(stroke
				(width 0)
				(type default)
			)
			(fill no)
			(layer "F.CrtYd")
		)
		(fp_poly
			(pts
				(xy -2.54 4.953) (xy -2.54 4.2926) (xy -3.81 4.2926) (xy -3.81 -4.2926) (xy -2.54 -4.2926) (xy -2.54 -4.953)
				(xy 2.54 -4.953) (xy 2.54 -4.2926) (xy 3.81 -4.2926) (xy 3.81 -1.6256) (xy 2.1463 -1.6256) (xy 2.1463 -3.6449)
				(xy -2.1463 -3.6449) (xy -2.1463 3.6449) (xy 2.1463 3.6449) (xy 2.1463 -1.6129) (xy 3.81 -1.6129)
				(xy 3.81 4.2926) (xy 2.54 4.2926) (xy 2.54 4.953)
			)
			(stroke
				(width 0)
				(type default)
			)
			(fill no)
			(layer "F.CrtYd")
		)
		(fp_rect
			(start -2.54 4.953)
			(end 2.54 -4.953)
			(stroke
				(width 0)
				(type default)
			)
			(fill no)
			(layer "F.Fab")
		)
		(fp_rect
			(start -3.81 4.2926)
			(end -2.54 -4.2926)
			(stroke
				(width 0)
				(type default)
			)
			(fill no)
			(layer "F.Fab")
		)
		(fp_rect
			(start 2.54 4.2926)
			(end 3.81 -4.2926)
			(stroke
				(width 0)
				(type default)
			)
			(fill no)
			(layer "F.Fab")
		)
		(pad "1" smd rect
			(at 0 -3.1496 270)
			(size 2.413 2.286)
			(layers "F.Cu" "F.Mask" "F.Paste")
			(net "P12V")
		)
		(pad "2" smd rect
			(at 0 3.1496 270)
			(size 2.413 2.286)
			(layers "F.Cu" "F.Mask" "F.Paste")
			(net "GND")
		)
		(zone
			(layer "F.Cu")
			(hatch none 0.5)
			(connect_pads
				(clearance 0)
			)
			(min_thickness 0.25)
			(keepout
				(tracks allowed)
				(vias not_allowed)
				(pads allowed)
				(copperpour not_allowed)
				(footprints allowed)
			)
			(placement
				(enabled no)
				(sheetname "")
			)
			(fill
				(thermal_gap 0.5)
				(thermal_bridge_width 0.5)
				(island_removal_mode 0)
			)
			(polygon
				(pts
					(xy 7.8486 -395.5923) (xy 7.8486 -392.5697) (xy 10.7442 -392.5697) (xy 11.0744 -392.5697) (xy 11.0744 -395.5923)
					(xy 10.7442 -395.5923)
				)
			)
		)
		(zone
			(layer "F.Cu")
			(hatch none 0.5)
			(connect_pads
				(clearance 0)
			)
			(min_thickness 0.25)
			(keepout
				(tracks allowed)
				(vias not_allowed)
				(pads allowed)
				(copperpour not_allowed)
				(footprints allowed)
			)
			(placement
				(enabled no)
				(sheetname "")
			)
			(fill
				(thermal_gap 0.5)
				(thermal_bridge_width 0.5)
				(island_removal_mode 0)
			)
			(polygon
				(pts
					(xy 14.1351 -392.5697) (xy 17.0434 -392.5697) (xy 17.0434 -395.5923) (xy 14.1478 -395.5923) (xy 13.8176 -395.5923)
					(xy 13.8176 -392.5697)
				)
			)
		)
	)
	(footprint ""
		(layer "F.Cu")
		(at 24.70531 -151.325834)
		(property "Reference" "R10"
			(at 0 0 0)
			(layer "F.SilkS")
			(hide yes)
			(effects
				(font
					(size 1.27 1.27)
				)
			)
		)
		(property "Value" "1MR2J-1-GP"
			(at 0.064008 -3.993896 0)
			(unlocked yes)
			(layer "F.Fab")
			(hide yes)
			(effects
				(font
					(size 1.016 1.016)
					(thickness 0.1524)
				)
			)
		)
		(property "Device Type" "R402H16"
			(at 0.064008 -5.517896 0)
			(unlocked yes)
			(layer "F.Fab")
			(hide yes)
			(effects
				(font
					(size 1.016 1.016)
					(thickness 0.1524)
				)
			)
		)
		(duplicate_pad_numbers_are_jumpers no)
		(fp_line
			(start -0.508 -0.9398)
			(end -0.508 0.9398)
			(stroke
				(width 0.1524)
				(type default)
			)
			(layer "F.SilkS")
		)
		(fp_line
			(start 0.508 -0.9398)
			(end -0.508 -0.9398)
			(stroke
				(width 0.1524)
				(type default)
			)
			(layer "F.SilkS")
		)
		(fp_rect
			(start -0.508 0.9398)
			(end 0.508 -0.9398)
			(stroke
				(width 0)
				(type default)
			)
			(fill no)
			(layer "F.CrtYd")
		)
		(fp_rect
			(start -0.508 0.9398)
			(end 0.508 -0.9398)
			(stroke
				(width 0)
				(type default)
			)
			(fill no)
			(layer "F.Fab")
		)
		(pad "1" smd custom
			(at 0 -0.4445)
			(size 0.1397 0.1397)
			(layers "F.Cu" "F.Mask" "F.Paste")
			(net "NCT7904_CASEOPEN")
			(options
				(clearance outline)
				(anchor circle)
			)
			(primitives
				(gr_poly
					(pts
						(arc
							(start -0.1778 -0.2794)
							(mid -0.249642 -0.249642)
							(end -0.2794 -0.1778)
						)
						(arc
							(start -0.2794 0.1778)
							(mid -0.249642 0.249642)
							(end -0.1778 0.2794)
						)
						(arc
							(start 0.1778 0.2794)
							(mid 0.249642 0.249642)
							(end 0.2794 0.1778)
						)
						(arc
							(start 0.2794 -0.1778)
							(mid 0.249642 -0.249642)
							(end 0.1778 -0.2794)
						)
					)
					(width 0)
					(fill yes)
				)
			)
		)
		(pad "2" smd custom
			(at 0 0.4445)
			(size 0.1397 0.1397)
			(layers "F.Cu" "F.Mask" "F.Paste")
			(net "NCT7904_3VSB")
			(options
				(clearance outline)
				(anchor circle)
			)
			(primitives
				(gr_poly
					(pts
						(arc
							(start -0.1778 -0.2794)
							(mid -0.249642 -0.249642)
							(end -0.2794 -0.1778)
						)
						(arc
							(start -0.2794 0.1778)
							(mid -0.249642 0.249642)
							(end -0.1778 0.2794)
						)
						(arc
							(start 0.1778 0.2794)
							(mid 0.249642 0.249642)
							(end 0.2794 0.1778)
						)
						(arc
							(start 0.2794 -0.1778)
							(mid 0.249642 -0.249642)
							(end 0.1778 -0.2794)
						)
					)
					(width 0)
					(fill yes)
				)
			)
		)
	)
	(footprint ""
		(layer "F.Cu")
		(at 14.8844 -47.5742 -90)
		(property "Reference" "R185"
			(at 0 0 270)
			(layer "F.SilkS")
			(hide yes)
			(effects
				(font
					(size 1.27 1.27)
				)
			)
		)
		(property "Value" "0R2J-2-GP"
			(at 0.064008 -3.993896 270)
			(unlocked yes)
			(layer "F.Fab")
			(hide yes)
			(effects
				(font
					(size 1.016 1.016)
					(thickness 0.1524)
				)
			)
		)
		(property "Device Type" "R402H16"
			(at 0.064008 -5.517896 270)
			(unlocked yes)
			(layer "F.Fab")
			(hide yes)
			(effects
				(font
					(size 1.016 1.016)
					(thickness 0.1524)
				)
			)
		)
		(duplicate_pad_numbers_are_jumpers no)
		(fp_line
			(start -0.508 -0.9398)
			(end -0.508 0.9398)
			(stroke
				(width 0.1524)
				(type default)
			)
			(layer "F.SilkS")
		)
		(fp_line
			(start 0.508 -0.9398)
			(end -0.508 -0.9398)
			(stroke
				(width 0.1524)
				(type default)
			)
			(layer "F.SilkS")
		)
		(fp_rect
			(start -0.508 0.9398)
			(end 0.508 -0.9398)
			(stroke
				(width 0)
				(type default)
			)
			(fill no)
			(layer "F.CrtYd")
		)
		(fp_rect
			(start -0.508 0.9398)
			(end 0.508 -0.9398)
			(stroke
				(width 0)
				(type default)
			)
			(fill no)
			(layer "F.Fab")
		)
		(pad "1" smd custom
			(at 0 -0.4445 270)
			(size 0.1397 0.1397)
			(layers "F.Cu" "F.Mask" "F.Paste")
			(net "SD_LATCH_RELEASE_L")
			(options
				(clearance outline)
				(anchor circle)
			)
			(primitives
				(gr_poly
					(pts
						(arc
							(start -0.1778 -0.2794)
							(mid -0.249642 -0.249642)
							(end -0.2794 -0.1778)
						)
						(arc
							(start -0.2794 0.1778)
							(mid -0.249642 0.249642)
							(end -0.1778 0.2794)
						)
						(arc
							(start 0.1778 0.2794)
							(mid 0.249642 0.249642)
							(end 0.2794 0.1778)
						)
						(arc
							(start 0.2794 -0.1778)
							(mid 0.249642 -0.249642)
							(end 0.1778 -0.2794)
						)
					)
					(width 0)
					(fill yes)
				)
			)
		)
		(pad "2" smd custom
			(at 0 0.4445 270)
			(size 0.1397 0.1397)
			(layers "F.Cu" "F.Mask" "F.Paste")
			(net "D_LATCH_PRE#")
			(options
				(clearance outline)
				(anchor circle)
			)
			(primitives
				(gr_poly
					(pts
						(arc
							(start -0.1778 -0.2794)
							(mid -0.249642 -0.249642)
							(end -0.2794 -0.1778)
						)
						(arc
							(start -0.2794 0.1778)
							(mid -0.249642 0.249642)
							(end -0.1778 0.2794)
						)
						(arc
							(start 0.1778 0.2794)
							(mid 0.249642 0.249642)
							(end 0.2794 0.1778)
						)
						(arc
							(start 0.2794 -0.1778)
							(mid 0.249642 -0.249642)
							(end 0.1778 -0.2794)
						)
					)
					(width 0)
					(fill yes)
				)
			)
		)
	)
	(footprint ""
		(layer "F.Cu")
		(at 38.989 -144.3482 180)
		(property "Reference" "PR113"
			(at 0 0 180)
			(layer "F.SilkS")
			(hide yes)
			(effects
				(font
					(size 1.27 1.27)
				)
			)
		)
		(property "Value" "6K81R2F-1-GP"
			(at 0.064008 -3.993896 180)
			(unlocked yes)
			(layer "F.Fab")
			(hide yes)
			(effects
				(font
					(size 1.016 1.016)
					(thickness 0.1524)
				)
			)
		)
		(property "Device Type" "R402H16"
			(at 0.064008 -5.517896 180)
			(unlocked yes)
			(layer "F.Fab")
			(hide yes)
			(effects
				(font
					(size 1.016 1.016)
					(thickness 0.1524)
				)
			)
		)
		(duplicate_pad_numbers_are_jumpers no)
		(fp_line
			(start 0.508 -0.9398)
			(end -0.508 -0.9398)
			(stroke
				(width 0.1524)
				(type default)
			)
			(layer "F.SilkS")
		)
		(fp_line
			(start -0.508 -0.9398)
			(end -0.508 0.9398)
			(stroke
				(width 0.1524)
				(type default)
			)
			(layer "F.SilkS")
		)
		(fp_rect
			(start -0.508 0.9398)
			(end 0.508 -0.9398)
			(stroke
				(width 0)
				(type default)
			)
			(fill no)
			(layer "F.CrtYd")
		)
		(fp_rect
			(start -0.508 0.9398)
			(end 0.508 -0.9398)
			(stroke
				(width 0)
				(type default)
			)
			(fill no)
			(layer "F.Fab")
		)
		(pad "1" smd custom
			(at 0 -0.4445 180)
			(size 0.1397 0.1397)
			(layers "F.Cu" "F.Mask" "F.Paste")
			(net "P12VL_2490_EN_2")
			(options
				(clearance outline)
				(anchor circle)
			)
			(primitives
				(gr_poly
					(pts
						(arc
							(start -0.1778 -0.2794)
							(mid -0.249642 -0.249642)
							(end -0.2794 -0.1778)
						)
						(arc
							(start -0.2794 0.1778)
							(mid -0.249642 0.249642)
							(end -0.1778 0.2794)
						)
						(arc
							(start 0.1778 0.2794)
							(mid 0.249642 0.249642)
							(end 0.2794 0.1778)
						)
						(arc
							(start 0.2794 -0.1778)
							(mid 0.249642 -0.249642)
							(end 0.1778 -0.2794)
						)
					)
					(width 0)
					(fill yes)
				)
			)
		)
		(pad "2" smd custom
			(at 0 0.4445 180)
			(size 0.1397 0.1397)
			(layers "F.Cu" "F.Mask" "F.Paste")
			(net "GND")
			(options
				(clearance outline)
				(anchor circle)
			)
			(primitives
				(gr_poly
					(pts
						(arc
							(start -0.1778 -0.2794)
							(mid -0.249642 -0.249642)
							(end -0.2794 -0.1778)
						)
						(arc
							(start -0.2794 0.1778)
							(mid -0.249642 0.249642)
							(end -0.1778 0.2794)
						)
						(arc
							(start 0.1778 0.2794)
							(mid 0.249642 0.249642)
							(end 0.2794 0.1778)
						)
						(arc
							(start 0.2794 -0.1778)
							(mid 0.249642 -0.249642)
							(end 0.1778 -0.2794)
						)
					)
					(width 0)
					(fill yes)
				)
			)
		)
	)
	(footprint ""
		(layer "F.Cu")
		(at 33.782 -381 180)
		(property "Reference" "PR23"
			(at 0 0 180)
			(layer "F.SilkS")
			(hide yes)
			(effects
				(font
					(size 1.27 1.27)
				)
			)
		)
		(property "Value" "10R2F-L-GP"
			(at 0.064008 -3.993896 180)
			(unlocked yes)
			(layer "F.Fab")
			(hide yes)
			(effects
				(font
					(size 1.016 1.016)
					(thickness 0.1524)
				)
			)
		)
		(property "Device Type" "R402H14"
			(at 0.064008 -5.517896 180)
			(unlocked yes)
			(layer "F.Fab")
			(hide yes)
			(effects
				(font
					(size 1.016 1.016)
					(thickness 0.1524)
				)
			)
		)
		(duplicate_pad_numbers_are_jumpers no)
		(fp_line
			(start 0.508 -0.9398)
			(end -0.508 -0.9398)
			(stroke
				(width 0.1524)
				(type default)
			)
			(layer "F.SilkS")
		)
		(fp_line
			(start -0.508 -0.9398)
			(end -0.508 0.9398)
			(stroke
				(width 0.1524)
				(type default)
			)
			(layer "F.SilkS")
		)
		(fp_rect
			(start -0.508 0.9398)
			(end 0.508 -0.9398)
			(stroke
				(width 0)
				(type default)
			)
			(fill no)
			(layer "F.CrtYd")
		)
		(fp_rect
			(start -0.508 0.9398)
			(end 0.508 -0.9398)
			(stroke
				(width 0)
				(type default)
			)
			(fill no)
			(layer "F.Fab")
		)
		(pad "1" smd custom
			(at 0 -0.4445 180)
			(size 0.1397 0.1397)
			(layers "F.Cu" "F.Mask" "F.Paste")
			(net "ADM1276_SENSE-")
			(options
				(clearance outline)
				(anchor circle)
			)
			(primitives
				(gr_poly
					(pts
						(arc
							(start -0.1778 -0.2794)
							(mid -0.249642 -0.249642)
							(end -0.2794 -0.1778)
						)
						(arc
							(start -0.2794 0.1778)
							(mid -0.249642 0.249642)
							(end -0.1778 0.2794)
						)
						(arc
							(start 0.1778 0.2794)
							(mid 0.249642 0.249642)
							(end 0.2794 0.1778)
						)
						(arc
							(start 0.2794 -0.1778)
							(mid 0.249642 -0.249642)
							(end 0.1778 -0.2794)
						)
					)
					(width 0)
					(fill yes)
				)
			)
		)
		(pad "2" smd custom
			(at 0 0.4445 180)
			(size 0.1397 0.1397)
			(layers "F.Cu" "F.Mask" "F.Paste")
			(net "SENSE-_R3")
			(options
				(clearance outline)
				(anchor circle)
			)
			(primitives
				(gr_poly
					(pts
						(arc
							(start -0.1778 -0.2794)
							(mid -0.249642 -0.249642)
							(end -0.2794 -0.1778)
						)
						(arc
							(start -0.2794 0.1778)
							(mid -0.249642 0.249642)
							(end -0.1778 0.2794)
						)
						(arc
							(start 0.1778 0.2794)
							(mid 0.249642 0.249642)
							(end 0.2794 0.1778)
						)
						(arc
							(start 0.2794 -0.1778)
							(mid 0.249642 -0.249642)
							(end 0.1778 -0.2794)
						)
					)
					(width 0)
					(fill yes)
				)
			)
		)
	)
	(footprint ""
		(layer "F.Cu")
		(at 32.766 -374.777 180)
		(property "Reference" "PR10"
			(at 0 0 180)
			(layer "F.SilkS")
			(hide yes)
			(effects
				(font
					(size 1.27 1.27)
				)
			)
		)
		(property "Value" "0R0402-PAD-2-GP"
			(at 0 -2.8702 180)
			(unlocked yes)
			(layer "F.Fab")
			(hide yes)
			(effects
				(font
					(size 1.016 1.016)
					(thickness 0.1524)
				)
			)
		)
		(property "Device Type" "0R0402-PAD-1"
			(at 0 -4.3942 180)
			(unlocked yes)
			(layer "F.Fab")
			(hide yes)
			(effects
				(font
					(size 1.016 1.016)
					(thickness 0.1524)
				)
			)
		)
		(duplicate_pad_numbers_are_jumpers no)
		(fp_line
			(start 0.508 -0.9398)
			(end -0.508 -0.9398)
			(stroke
				(width 0.1524)
				(type default)
			)
			(layer "F.SilkS")
		)
		(fp_line
			(start -0.508 -0.9398)
			(end -0.508 0.9398)
			(stroke
				(width 0.1524)
				(type default)
			)
			(layer "F.SilkS")
		)
		(fp_rect
			(start -0.508 0.9398)
			(end 0.508 -0.9398)
			(stroke
				(width 0)
				(type default)
			)
			(fill no)
			(layer "F.CrtYd")
		)
		(fp_rect
			(start -0.508 0.9398)
			(end 0.508 -0.9398)
			(stroke
				(width 0)
				(type default)
			)
			(fill no)
			(layer "F.Fab")
		)
		(pad "1" smd custom
			(at 0 -0.4445 180)
			(size 0.1397 0.1397)
			(layers "F.Cu" "F.Mask" "F.Paste")
			(net "ADM1276_GATE_DRV")
			(options
				(clearance outline)
				(anchor circle)
			)
			(primitives
				(gr_poly
					(pts
						(xy -0.2794 0.3683)
						(arc
							(start -0.2794 -0.2667)
							(mid -0.249642 -0.338542)
							(end -0.1778 -0.3683)
						)
						(arc
							(start 0.1778 -0.3683)
							(mid 0.249642 -0.338542)
							(end 0.2794 -0.2667)
						)
						(xy 0.2794 0.3683)
					)
					(width 0)
					(fill yes)
				)
			)
		)
		(pad "2" smd custom
			(at 0 0.4445 180)
			(size 0.1397 0.1397)
			(layers "F.Cu" "F.Mask" "F.Paste")
			(net "ADM1276_GATE")
			(options
				(clearance outline)
				(anchor circle)
			)
			(primitives
				(gr_poly
					(pts
						(arc
							(start -0.1778 0.3683)
							(mid -0.249642 0.338542)
							(end -0.2794 0.2667)
						)
						(xy -0.2794 -0.3683) (xy 0.2794 -0.3683)
						(arc
							(start 0.2794 0.2667)
							(mid 0.249642 0.338542)
							(end 0.1778 0.3683)
						)
					)
					(width 0)
					(fill yes)
				)
			)
		)
	)
	(footprint ""
		(layer "F.Cu")
		(at 13.97 -174.752 90)
		(property "Reference" "U11"
			(at 0 0 90)
			(layer "F.SilkS")
			(hide yes)
			(effects
				(font
					(size 1.27 1.27)
				)
			)
		)
		(property "Value" "74LVC1G32GW-1GP"
			(at -2.3368 -8.6868 90)
			(unlocked yes)
			(layer "F.Fab")
			(hide yes)
			(effects
				(font
					(size 1.016 1.016)
					(thickness 0.1524)
				)
			)
		)
		(property "Device Type" "SC70-5H44"
			(at -2.3114 -10.414 90)
			(unlocked yes)
			(layer "F.Fab")
			(hide yes)
			(effects
				(font
					(size 1.016 1.016)
					(thickness 0.1524)
				)
			)
		)
		(duplicate_pad_numbers_are_jumpers no)
		(fp_line
			(start 1.3843 -1.8034)
			(end 1.3843 -1.1176)
			(stroke
				(width 0.3302)
				(type default)
			)
			(layer "F.SilkS")
		)
		(fp_line
			(start 0.6604 -1.8034)
			(end 1.3843 -1.8034)
			(stroke
				(width 0.3302)
				(type default)
			)
			(layer "F.SilkS")
		)
		(fp_line
			(start 1.27 -1.7018)
			(end 1.27 1.7018)
			(stroke
				(width 0.1524)
				(type default)
			)
			(layer "F.SilkS")
		)
		(fp_line
			(start -1.27 -1.7018)
			(end 1.27 -1.7018)
			(stroke
				(width 0.1524)
				(type default)
			)
			(layer "F.SilkS")
		)
		(fp_line
			(start 1.27 1.7018)
			(end -1.27 1.7018)
			(stroke
				(width 0.1524)
				(type default)
			)
			(layer "F.SilkS")
		)
		(fp_line
			(start -1.27 1.7018)
			(end -1.27 -1.7018)
			(stroke
				(width 0.1524)
				(type default)
			)
			(layer "F.SilkS")
		)
		(fp_rect
			(start -1.524 1.9558)
			(end 1.524 -1.9558)
			(stroke
				(width 0)
				(type default)
			)
			(fill no)
			(layer "F.CrtYd")
		)
		(fp_poly
			(pts
				(xy -1.524 -1.9558) (xy 1.524 -1.9558) (xy 1.524 1.9558) (xy -1.524 1.9558)
			)
			(stroke
				(width 0)
				(type default)
			)
			(fill no)
			(layer "F.Fab")
		)
		(pad "1" smd rect
			(at 0.65024 -0.8255 90)
			(size 0.4064 1.2192)
			(layers "F.Cu" "F.Mask" "F.Paste")
			(net "SEB_PEER_2A_HB")
		)
		(pad "2" smd rect
			(at 0 -0.8255 90)
			(size 0.4064 1.2192)
			(layers "F.Cu" "F.Mask" "F.Paste")
			(net "SEB_PEER_2B_HB")
		)
		(pad "3" smd rect
			(at -0.65024 -0.8255 90)
			(size 0.4064 1.2192)
			(layers "F.Cu" "F.Mask" "F.Paste")
			(net "GND")
		)
		(pad "4" smd rect
			(at -0.65024 0.8255 90)
			(size 0.4064 1.2192)
			(layers "F.Cu" "F.Mask" "F.Paste")
			(net "SEB_PEER_2A_2B_HB_OUT")
		)
		(pad "5" smd rect
			(at 0.65024 0.8255 90)
			(size 0.4064 1.2192)
			(layers "F.Cu" "F.Mask" "F.Paste")
			(net "P3V3")
		)
	)
	(footprint ""
		(layer "F.Cu")
		(at 14.5796 -171.4754)
		(property "Reference" "R49"
			(at 0 0 0)
			(layer "F.SilkS")
			(hide yes)
			(effects
				(font
					(size 1.27 1.27)
				)
			)
		)
		(property "Value" "4K7R2F-GP"
			(at 0.064008 -3.993896 0)
			(unlocked yes)
			(layer "F.Fab")
			(hide yes)
			(effects
				(font
					(size 1.016 1.016)
					(thickness 0.1524)
				)
			)
		)
		(property "Device Type" "R402H16"
			(at 0.064008 -5.517896 0)
			(unlocked yes)
			(layer "F.Fab")
			(hide yes)
			(effects
				(font
					(size 1.016 1.016)
					(thickness 0.1524)
				)
			)
		)
		(duplicate_pad_numbers_are_jumpers no)
		(fp_line
			(start -0.508 -0.9398)
			(end -0.508 0.9398)
			(stroke
				(width 0.1524)
				(type default)
			)
			(layer "F.SilkS")
		)
		(fp_line
			(start 0.508 -0.9398)
			(end -0.508 -0.9398)
			(stroke
				(width 0.1524)
				(type default)
			)
			(layer "F.SilkS")
		)
		(fp_rect
			(start -0.508 0.9398)
			(end 0.508 -0.9398)
			(stroke
				(width 0)
				(type default)
			)
			(fill no)
			(layer "F.CrtYd")
		)
		(fp_rect
			(start -0.508 0.9398)
			(end 0.508 -0.9398)
			(stroke
				(width 0)
				(type default)
			)
			(fill no)
			(layer "F.Fab")
		)
		(pad "1" smd custom
			(at 0 -0.4445)
			(size 0.1397 0.1397)
			(layers "F.Cu" "F.Mask" "F.Paste")
			(net "P3V3")
			(options
				(clearance outline)
				(anchor circle)
			)
			(primitives
				(gr_poly
					(pts
						(arc
							(start -0.1778 -0.2794)
							(mid -0.249642 -0.249642)
							(end -0.2794 -0.1778)
						)
						(arc
							(start -0.2794 0.1778)
							(mid -0.249642 0.249642)
							(end -0.1778 0.2794)
						)
						(arc
							(start 0.1778 0.2794)
							(mid 0.249642 0.249642)
							(end 0.2794 0.1778)
						)
						(arc
							(start 0.2794 -0.1778)
							(mid 0.249642 -0.249642)
							(end 0.1778 -0.2794)
						)
					)
					(width 0)
					(fill yes)
				)
			)
		)
		(pad "2" smd custom
			(at 0 0.4445)
			(size 0.1397 0.1397)
			(layers "F.Cu" "F.Mask" "F.Paste")
			(net "SEB_PEER_1A_1B_HB_OUT")
			(options
				(clearance outline)
				(anchor circle)
			)
			(primitives
				(gr_poly
					(pts
						(arc
							(start -0.1778 -0.2794)
							(mid -0.249642 -0.249642)
							(end -0.2794 -0.1778)
						)
						(arc
							(start -0.2794 0.1778)
							(mid -0.249642 0.249642)
							(end -0.1778 0.2794)
						)
						(arc
							(start 0.1778 0.2794)
							(mid 0.249642 0.249642)
							(end 0.2794 0.1778)
						)
						(arc
							(start 0.2794 -0.1778)
							(mid 0.249642 -0.249642)
							(end 0.1778 -0.2794)
						)
					)
					(width 0)
					(fill yes)
				)
			)
		)
	)
	(footprint ""
		(layer "F.Cu")
		(at 45.500036 -294.999918)
		(property "Reference" "H6"
			(at 0 0 0)
			(layer "F.SilkS")
			(hide yes)
			(effects
				(font
					(size 1.27 1.27)
				)
			)
		)
		(property "Value" "HOLE315R138"
			(at 0 -7.0612 0)
			(unlocked yes)
			(layer "F.Fab")
			(hide yes)
			(effects
				(font
					(size 1.016 1.016)
					(thickness 0.1524)
				)
			)
		)
		(property "Device Type" "HOLE315R138"
			(at 0 -8.5852 0)
			(unlocked yes)
			(layer "F.Fab")
			(hide yes)
			(effects
				(font
					(size 1.016 1.016)
					(thickness 0.1524)
				)
			)
		)
		(duplicate_pad_numbers_are_jumpers no)
		(fp_poly
			(pts
				(xy 0 4.3053) (xy -0.13462 4.30276) (xy -0.27051 4.29641) (xy -0.40513 4.28625) (xy -0.53975 4.27101)
				(xy -0.6731 4.25196) (xy -0.80645 4.2291) (xy -0.9398 4.20116) (xy -1.07061 4.17068) (xy -1.20142 4.13385)
				(xy -1.33096 4.09448) (xy -1.45796 4.0513) (xy -1.58496 4.00304) (xy -1.70942 3.95097) (xy -1.83261 3.89509)
				(xy -1.95453 3.83667) (xy -2.07391 3.77317) (xy -2.19202 3.70586) (xy -2.30632 3.63474) (xy -2.41935 3.56108)
				(xy -2.53111 3.48361) (xy -2.63906 3.40233) (xy -2.74447 3.31724) (xy -2.84734 3.22961) (xy -2.94767 3.13817)
				(xy -3.04419 3.04419) (xy -3.13817 2.94767) (xy -3.22961 2.84734) (xy -3.31724 2.74447) (xy -3.40233 2.63906)
				(xy -3.48361 2.53111) (xy -3.56108 2.41935) (xy -3.63474 2.30632) (xy -3.70586 2.19202) (xy -3.77317 2.07391)
				(xy -3.83667 1.95453) (xy -3.89509 1.83261) (xy -3.95097 1.70942) (xy -4.00304 1.58496) (xy -4.0513 1.45796)
				(xy -4.09448 1.33096) (xy -4.13385 1.20142) (xy -4.17068 1.07061) (xy -4.20116 0.9398) (xy -4.2291 0.80645)
				(xy -4.25196 0.6731) (xy -4.27101 0.53975) (xy -4.28625 0.40513) (xy -4.29641 0.27051) (xy -4.30276 0.13462)
				(xy -4.3053 0) (xy -4.30276 -0.13462) (xy -4.29641 -0.27051) (xy -4.28625 -0.40513) (xy -4.27101 -0.53975)
				(xy -4.25196 -0.6731) (xy -4.2291 -0.80645) (xy -4.20116 -0.9398) (xy -4.17068 -1.07061) (xy -4.13385 -1.20142)
				(xy -4.09448 -1.33096) (xy -4.0513 -1.45796) (xy -4.00304 -1.58496) (xy -3.95097 -1.70942) (xy -3.89509 -1.83261)
				(xy -3.83667 -1.95453) (xy -3.77317 -2.07391) (xy -3.70586 -2.19202) (xy -3.63474 -2.30632) (xy -3.56108 -2.41935)
				(xy -3.48361 -2.53111) (xy -3.40233 -2.63906) (xy -3.31724 -2.74447) (xy -3.22961 -2.84734) (xy -3.13817 -2.94767)
				(xy -3.04419 -3.04419) (xy -2.94767 -3.13817) (xy -2.84734 -3.22961) (xy -2.74447 -3.31724) (xy -2.63906 -3.40233)
				(xy -2.53111 -3.48361) (xy -2.41935 -3.56108) (xy -2.30632 -3.63474) (xy -2.19202 -3.70586) (xy -2.07391 -3.77317)
				(xy -1.95453 -3.83667) (xy -1.83261 -3.89509) (xy -1.70942 -3.95097) (xy -1.58496 -4.00304) (xy -1.45796 -4.0513)
				(xy -1.33096 -4.09448) (xy -1.20142 -4.13385) (xy -1.07061 -4.17068) (xy -0.9398 -4.20116) (xy -0.80645 -4.2291)
				(xy -0.6731 -4.25196) (xy -0.53975 -4.27101) (xy -0.40513 -4.28625) (xy -0.27051 -4.29641) (xy -0.13462 -4.30276)
				(xy 0 -4.3053) (xy 0.13462 -4.30276) (xy 0.27051 -4.29641) (xy 0.40513 -4.28625) (xy 0.53975 -4.27101)
				(xy 0.6731 -4.25196) (xy 0.80645 -4.2291) (xy 0.9398 -4.20116) (xy 1.07061 -4.17068) (xy 1.20142 -4.13385)
				(xy 1.33096 -4.09448) (xy 1.45796 -4.0513) (xy 1.58496 -4.00304) (xy 1.70942 -3.95097) (xy 1.83261 -3.89509)
				(xy 1.95453 -3.83667) (xy 2.07391 -3.77317) (xy 2.19202 -3.70586) (xy 2.30632 -3.63474) (xy 2.41935 -3.56108)
				(xy 2.53111 -3.48361) (xy 2.63906 -3.40233) (xy 2.74447 -3.31724) (xy 2.84734 -3.22961) (xy 2.94767 -3.13817)
				(xy 3.04419 -3.04419) (xy 3.13817 -2.94767) (xy 3.22961 -2.84734) (xy 3.31724 -2.74447) (xy 3.40233 -2.63906)
				(xy 3.48361 -2.53111) (xy 3.56108 -2.41935) (xy 3.63474 -2.30632) (xy 3.70586 -2.19202) (xy 3.77317 -2.07391)
				(xy 3.83667 -1.95453) (xy 3.89509 -1.83261) (xy 3.95097 -1.70942) (xy 4.00304 -1.58496) (xy 4.0513 -1.45796)
				(xy 4.09448 -1.33096) (xy 4.13385 -1.20142) (xy 4.17068 -1.07061) (xy 4.20116 -0.9398) (xy 4.2291 -0.80645)
				(xy 4.25196 -0.6731) (xy 4.27101 -0.53975) (xy 4.28625 -0.40513) (xy 4.29641 -0.27051) (xy 4.30276 -0.13462)
				(xy 4.3053 0) (xy 4.30276 0.13462) (xy 4.29641 0.27051) (xy 4.28625 0.40513) (xy 4.27101 0.53975)
				(xy 4.25196 0.6731) (xy 4.2291 0.80645) (xy 4.20116 0.9398) (xy 4.17068 1.07061) (xy 4.13385 1.20142)
				(xy 4.09448 1.33096) (xy 4.0513 1.45796) (xy 4.00304 1.58496) (xy 3.95097 1.70942) (xy 3.89509 1.83261)
				(xy 3.83667 1.95453) (xy 3.77317 2.07391) (xy 3.70586 2.19202) (xy 3.63474 2.30632) (xy 3.56108 2.41935)
				(xy 3.48361 2.53111) (xy 3.40233 2.63906) (xy 3.31724 2.74447) (xy 3.22961 2.84734) (xy 3.13817 2.94767)
				(xy 3.04419 3.04419) (xy 2.94767 3.13817) (xy 2.84734 3.22961) (xy 2.74447 3.31724) (xy 2.63906 3.40233)
				(xy 2.53111 3.48361) (xy 2.41935 3.56108) (xy 2.30632 3.63474) (xy 2.19202 3.70586) (xy 2.07391 3.77317)
				(xy 1.95453 3.83667) (xy 1.83261 3.89509) (xy 1.70942 3.95097) (xy 1.58496 4.00304) (xy 1.45796 4.0513)
				(xy 1.33096 4.09448) (xy 1.20142 4.13385) (xy 1.07061 4.17068) (xy 0.9398 4.20116) (xy 0.80645 4.2291)
				(xy 0.6731 4.25196) (xy 0.53975 4.27101) (xy 0.40513 4.28625) (xy 0.27051 4.29641) (xy 0.13462 4.30276)
			)
			(stroke
				(width 0)
				(type default)
			)
			(fill no)
			(layer "F.CrtYd")
		)
		(fp_poly
			(pts
				(xy 0 4.3053) (xy -0.13462 4.30276) (xy -0.27051 4.29641) (xy -0.40513 4.28625) (xy -0.53975 4.27101)
				(xy -0.6731 4.25196) (xy -0.80645 4.2291) (xy -0.9398 4.20116) (xy -1.07061 4.17068) (xy -1.20142 4.13385)
				(xy -1.33096 4.09448) (xy -1.45796 4.0513) (xy -1.58496 4.00304) (xy -1.70942 3.95097) (xy -1.83261 3.89509)
				(xy -1.95453 3.83667) (xy -2.07391 3.77317) (xy -2.19202 3.70586) (xy -2.30632 3.63474) (xy -2.41935 3.56108)
				(xy -2.53111 3.48361) (xy -2.63906 3.40233) (xy -2.74447 3.31724) (xy -2.84734 3.22961) (xy -2.94767 3.13817)
				(xy -3.04419 3.04419) (xy -3.13817 2.94767) (xy -3.22961 2.84734) (xy -3.31724 2.74447) (xy -3.40233 2.63906)
				(xy -3.48361 2.53111) (xy -3.56108 2.41935) (xy -3.63474 2.30632) (xy -3.70586 2.19202) (xy -3.77317 2.07391)
				(xy -3.83667 1.95453) (xy -3.89509 1.83261) (xy -3.95097 1.70942) (xy -4.00304 1.58496) (xy -4.0513 1.45796)
				(xy -4.09448 1.33096) (xy -4.13385 1.20142) (xy -4.17068 1.07061) (xy -4.20116 0.9398) (xy -4.2291 0.80645)
				(xy -4.25196 0.6731) (xy -4.27101 0.53975) (xy -4.28625 0.40513) (xy -4.29641 0.27051) (xy -4.30276 0.13462)
				(xy -4.3053 0) (xy -4.30276 -0.13462) (xy -4.29641 -0.27051) (xy -4.28625 -0.40513) (xy -4.27101 -0.53975)
				(xy -4.25196 -0.6731) (xy -4.2291 -0.80645) (xy -4.20116 -0.9398) (xy -4.17068 -1.07061) (xy -4.13385 -1.20142)
				(xy -4.09448 -1.33096) (xy -4.0513 -1.45796) (xy -4.00304 -1.58496) (xy -3.95097 -1.70942) (xy -3.89509 -1.83261)
				(xy -3.83667 -1.95453) (xy -3.77317 -2.07391) (xy -3.70586 -2.19202) (xy -3.63474 -2.30632) (xy -3.56108 -2.41935)
				(xy -3.48361 -2.53111) (xy -3.40233 -2.63906) (xy -3.31724 -2.74447) (xy -3.22961 -2.84734) (xy -3.13817 -2.94767)
				(xy -3.04419 -3.04419) (xy -2.94767 -3.13817) (xy -2.84734 -3.22961) (xy -2.74447 -3.31724) (xy -2.63906 -3.40233)
				(xy -2.53111 -3.48361) (xy -2.41935 -3.56108) (xy -2.30632 -3.63474) (xy -2.19202 -3.70586) (xy -2.07391 -3.77317)
				(xy -1.95453 -3.83667) (xy -1.83261 -3.89509) (xy -1.70942 -3.95097) (xy -1.58496 -4.00304) (xy -1.45796 -4.0513)
				(xy -1.33096 -4.09448) (xy -1.20142 -4.13385) (xy -1.07061 -4.17068) (xy -0.9398 -4.20116) (xy -0.80645 -4.2291)
				(xy -0.6731 -4.25196) (xy -0.53975 -4.27101) (xy -0.40513 -4.28625) (xy -0.27051 -4.29641) (xy -0.13462 -4.30276)
				(xy 0 -4.3053) (xy 0.13462 -4.30276) (xy 0.27051 -4.29641) (xy 0.40513 -4.28625) (xy 0.53975 -4.27101)
				(xy 0.6731 -4.25196) (xy 0.80645 -4.2291) (xy 0.9398 -4.20116) (xy 1.07061 -4.17068) (xy 1.20142 -4.13385)
				(xy 1.33096 -4.09448) (xy 1.45796 -4.0513) (xy 1.58496 -4.00304) (xy 1.70942 -3.95097) (xy 1.83261 -3.89509)
				(xy 1.95453 -3.83667) (xy 2.07391 -3.77317) (xy 2.19202 -3.70586) (xy 2.30632 -3.63474) (xy 2.41935 -3.56108)
				(xy 2.53111 -3.48361) (xy 2.63906 -3.40233) (xy 2.74447 -3.31724) (xy 2.84734 -3.22961) (xy 2.94767 -3.13817)
				(xy 3.04419 -3.04419) (xy 3.13817 -2.94767) (xy 3.22961 -2.84734) (xy 3.31724 -2.74447) (xy 3.40233 -2.63906)
				(xy 3.48361 -2.53111) (xy 3.56108 -2.41935) (xy 3.63474 -2.30632) (xy 3.70586 -2.19202) (xy 3.77317 -2.07391)
				(xy 3.83667 -1.95453) (xy 3.89509 -1.83261) (xy 3.95097 -1.70942) (xy 4.00304 -1.58496) (xy 4.0513 -1.45796)
				(xy 4.09448 -1.33096) (xy 4.13385 -1.20142) (xy 4.17068 -1.07061) (xy 4.20116 -0.9398) (xy 4.2291 -0.80645)
				(xy 4.25196 -0.6731) (xy 4.27101 -0.53975) (xy 4.28625 -0.40513) (xy 4.29641 -0.27051) (xy 4.30276 -0.13462)
				(xy 4.3053 0) (xy 4.30276 0.13462) (xy 4.29641 0.27051) (xy 4.28625 0.40513) (xy 4.27101 0.53975)
				(xy 4.25196 0.6731) (xy 4.2291 0.80645) (xy 4.20116 0.9398) (xy 4.17068 1.07061) (xy 4.13385 1.20142)
				(xy 4.09448 1.33096) (xy 4.0513 1.45796) (xy 4.00304 1.58496) (xy 3.95097 1.70942) (xy 3.89509 1.83261)
				(xy 3.83667 1.95453) (xy 3.77317 2.07391) (xy 3.70586 2.19202) (xy 3.63474 2.30632) (xy 3.56108 2.41935)
				(xy 3.48361 2.53111) (xy 3.40233 2.63906) (xy 3.31724 2.74447) (xy 3.22961 2.84734) (xy 3.13817 2.94767)
				(xy 3.04419 3.04419) (xy 2.94767 3.13817) (xy 2.84734 3.22961) (xy 2.74447 3.31724) (xy 2.63906 3.40233)
				(xy 2.53111 3.48361) (xy 2.41935 3.56108) (xy 2.30632 3.63474) (xy 2.19202 3.70586) (xy 2.07391 3.77317)
				(xy 1.95453 3.83667) (xy 1.83261 3.89509) (xy 1.70942 3.95097) (xy 1.58496 4.00304) (xy 1.45796 4.0513)
				(xy 1.33096 4.09448) (xy 1.20142 4.13385) (xy 1.07061 4.17068) (xy 0.9398 4.20116) (xy 0.80645 4.2291)
				(xy 0.6731 4.25196) (xy 0.53975 4.27101) (xy 0.40513 4.28625) (xy 0.27051 4.29641) (xy 0.13462 4.30276)
			)
			(stroke
				(width 0)
				(type default)
			)
			(fill no)
			(layer "F.Fab")
		)
		(pad "1" thru_hole circle
			(at 0 0)
			(size 8.001 8.001)
			(drill 3.5052)
			(layers "*.Cu" "*.Mask")
			(remove_unused_layers no)
			(net "GND")
			(clearance -1.7399)
			(thermal_gap 0.3048)
			(padstack
				(mode front_inner_back)
				(layer "Inner"
					(shape circle)
					(size 3.9116 3.9116)
					(clearance 0.3048)
				)
				(layer "B.Cu"
					(shape circle)
					(size 8.001 8.001)
					(clearance -1.7399)
				)
			)
		)
	)
	(footprint ""
		(layer "F.Cu")
		(at 40.386 -370.332 -90)
		(property "Reference" "PR48"
			(at 0 0 270)
			(layer "F.SilkS")
			(hide yes)
			(effects
				(font
					(size 1.27 1.27)
				)
			)
		)
		(property "Value" "5K1R2F-2-GP"
			(at 0.064008 -3.993896 270)
			(unlocked yes)
			(layer "F.Fab")
			(hide yes)
			(effects
				(font
					(size 1.016 1.016)
					(thickness 0.1524)
				)
			)
		)
		(property "Device Type" "R402H16"
			(at 0.064008 -5.517896 270)
			(unlocked yes)
			(layer "F.Fab")
			(hide yes)
			(effects
				(font
					(size 1.016 1.016)
					(thickness 0.1524)
				)
			)
		)
		(duplicate_pad_numbers_are_jumpers no)
		(fp_line
			(start -0.508 -0.9398)
			(end -0.508 0.9398)
			(stroke
				(width 0.1524)
				(type default)
			)
			(layer "F.SilkS")
		)
		(fp_line
			(start 0.508 -0.9398)
			(end -0.508 -0.9398)
			(stroke
				(width 0.1524)
				(type default)
			)
			(layer "F.SilkS")
		)
		(fp_rect
			(start -0.508 0.9398)
			(end 0.508 -0.9398)
			(stroke
				(width 0)
				(type default)
			)
			(fill no)
			(layer "F.CrtYd")
		)
		(fp_rect
			(start -0.508 0.9398)
			(end 0.508 -0.9398)
			(stroke
				(width 0)
				(type default)
			)
			(fill no)
			(layer "F.Fab")
		)
		(pad "1" smd custom
			(at 0 -0.4445 270)
			(size 0.1397 0.1397)
			(layers "F.Cu" "F.Mask" "F.Paste")
			(net "ADM1276_EN_NET")
			(options
				(clearance outline)
				(anchor circle)
			)
			(primitives
				(gr_poly
					(pts
						(arc
							(start -0.1778 -0.2794)
							(mid -0.249642 -0.249642)
							(end -0.2794 -0.1778)
						)
						(arc
							(start -0.2794 0.1778)
							(mid -0.249642 0.249642)
							(end -0.1778 0.2794)
						)
						(arc
							(start 0.1778 0.2794)
							(mid 0.249642 0.249642)
							(end 0.2794 0.1778)
						)
						(arc
							(start 0.2794 -0.1778)
							(mid 0.249642 -0.249642)
							(end 0.1778 -0.2794)
						)
					)
					(width 0)
					(fill yes)
				)
			)
		)
		(pad "2" smd custom
			(at 0 0.4445 270)
			(size 0.1397 0.1397)
			(layers "F.Cu" "F.Mask" "F.Paste")
			(net "ADM1276_LATCH_B")
			(options
				(clearance outline)
				(anchor circle)
			)
			(primitives
				(gr_poly
					(pts
						(arc
							(start -0.1778 -0.2794)
							(mid -0.249642 -0.249642)
							(end -0.2794 -0.1778)
						)
						(arc
							(start -0.2794 0.1778)
							(mid -0.249642 0.249642)
							(end -0.1778 0.2794)
						)
						(arc
							(start 0.1778 0.2794)
							(mid 0.249642 0.249642)
							(end 0.2794 0.1778)
						)
						(arc
							(start 0.2794 -0.1778)
							(mid 0.249642 -0.249642)
							(end 0.1778 -0.2794)
						)
					)
					(width 0)
					(fill yes)
				)
			)
		)
	)
	(footprint ""
		(layer "F.Cu")
		(at 18.237708 -13.905738)
		(property "Reference" "C29"
			(at 0 0 0)
			(layer "F.SilkS")
			(hide yes)
			(effects
				(font
					(size 1.27 1.27)
				)
			)
		)
		(property "Value" "SCD1U16V2KX-3GP"
			(at 1.1811 -2.7051 0)
			(unlocked yes)
			(layer "F.Fab")
			(hide yes)
			(effects
				(font
					(size 1.016 1.016)
					(thickness 0.1524)
				)
			)
		)
		(property "Device Type" "C402H22"
			(at 1.1811 -4.2291 0)
			(unlocked yes)
			(layer "F.Fab")
			(hide yes)
			(effects
				(font
					(size 1.016 1.016)
					(thickness 0.1524)
				)
			)
		)
		(duplicate_pad_numbers_are_jumpers no)
		(fp_rect
			(start -0.4318 0.9525)
			(end 0.4318 -0.9525)
			(stroke
				(width 0)
				(type default)
			)
			(fill no)
			(layer "F.CrtYd")
		)
		(fp_rect
			(start -0.4318 0.9525)
			(end 0.4318 -0.9525)
			(stroke
				(width 0)
				(type default)
			)
			(fill no)
			(layer "F.Fab")
		)
		(pad "1" smd custom
			(at 0 -0.4445)
			(size 0.1524 0.1524)
			(layers "F.Cu" "F.Mask" "F.Paste")
			(net "FAN_TACH11")
			(options
				(clearance outline)
				(anchor circle)
			)
			(primitives
				(gr_poly
					(pts
						(arc
							(start 0.3048 -0.2032)
							(mid 0.275042 -0.275042)
							(end 0.2032 -0.3048)
						)
						(arc
							(start -0.2032 -0.3048)
							(mid -0.275042 -0.275042)
							(end -0.3048 -0.2032)
						)
						(arc
							(start -0.3048 0.2032)
							(mid -0.275042 0.275042)
							(end -0.2032 0.3048)
						)
						(arc
							(start 0.2032 0.3048)
							(mid 0.275042 0.275042)
							(end 0.3048 0.2032)
						)
					)
					(width 0)
					(fill yes)
				)
			)
		)
		(pad "2" smd custom
			(at 0 0.4445)
			(size 0.1524 0.1524)
			(layers "F.Cu" "F.Mask" "F.Paste")
			(net "GND")
			(options
				(clearance outline)
				(anchor circle)
			)
			(primitives
				(gr_poly
					(pts
						(arc
							(start 0.3048 -0.2032)
							(mid 0.275042 -0.275042)
							(end 0.2032 -0.3048)
						)
						(arc
							(start -0.2032 -0.3048)
							(mid -0.275042 -0.275042)
							(end -0.3048 -0.2032)
						)
						(arc
							(start -0.3048 0.2032)
							(mid -0.275042 0.275042)
							(end -0.2032 0.3048)
						)
						(arc
							(start 0.2032 0.3048)
							(mid 0.275042 0.275042)
							(end 0.3048 0.2032)
						)
					)
					(width 0)
					(fill yes)
				)
			)
		)
	)
	(footprint ""
		(layer "F.Cu")
		(at 23.749 -375.285 180)
		(property "Reference" "PR37"
			(at 0 0 180)
			(layer "F.SilkS")
			(hide yes)
			(effects
				(font
					(size 1.27 1.27)
				)
			)
		)
		(property "Value" "4K99R2F-L-GP"
			(at 0.064008 -3.993896 180)
			(unlocked yes)
			(layer "F.Fab")
			(hide yes)
			(effects
				(font
					(size 1.016 1.016)
					(thickness 0.1524)
				)
			)
		)
		(property "Device Type" "R402H16"
			(at 0.064008 -5.517896 180)
			(unlocked yes)
			(layer "F.Fab")
			(hide yes)
			(effects
				(font
					(size 1.016 1.016)
					(thickness 0.1524)
				)
			)
		)
		(duplicate_pad_numbers_are_jumpers no)
		(fp_line
			(start 0.508 -0.9398)
			(end -0.508 -0.9398)
			(stroke
				(width 0.1524)
				(type default)
			)
			(layer "F.SilkS")
		)
		(fp_line
			(start -0.508 -0.9398)
			(end -0.508 0.9398)
			(stroke
				(width 0.1524)
				(type default)
			)
			(layer "F.SilkS")
		)
		(fp_rect
			(start -0.508 0.9398)
			(end 0.508 -0.9398)
			(stroke
				(width 0)
				(type default)
			)
			(fill no)
			(layer "F.CrtYd")
		)
		(fp_rect
			(start -0.508 0.9398)
			(end 0.508 -0.9398)
			(stroke
				(width 0)
				(type default)
			)
			(fill no)
			(layer "F.Fab")
		)
		(pad "1" smd custom
			(at 0 -0.4445 180)
			(size 0.1397 0.1397)
			(layers "F.Cu" "F.Mask" "F.Paste")
			(net "ADM1276_UV")
			(options
				(clearance outline)
				(anchor circle)
			)
			(primitives
				(gr_poly
					(pts
						(arc
							(start -0.1778 -0.2794)
							(mid -0.249642 -0.249642)
							(end -0.2794 -0.1778)
						)
						(arc
							(start -0.2794 0.1778)
							(mid -0.249642 0.249642)
							(end -0.1778 0.2794)
						)
						(arc
							(start 0.1778 0.2794)
							(mid 0.249642 0.249642)
							(end 0.2794 0.1778)
						)
						(arc
							(start 0.2794 -0.1778)
							(mid 0.249642 -0.249642)
							(end 0.1778 -0.2794)
						)
					)
					(width 0)
					(fill yes)
				)
			)
		)
		(pad "2" smd custom
			(at 0 0.4445 180)
			(size 0.1397 0.1397)
			(layers "F.Cu" "F.Mask" "F.Paste")
			(net "GND")
			(options
				(clearance outline)
				(anchor circle)
			)
			(primitives
				(gr_poly
					(pts
						(arc
							(start -0.1778 -0.2794)
							(mid -0.249642 -0.249642)
							(end -0.2794 -0.1778)
						)
						(arc
							(start -0.2794 0.1778)
							(mid -0.249642 0.249642)
							(end -0.1778 0.2794)
						)
						(arc
							(start 0.1778 0.2794)
							(mid 0.249642 0.249642)
							(end 0.2794 0.1778)
						)
						(arc
							(start 0.2794 -0.1778)
							(mid 0.249642 -0.249642)
							(end 0.1778 -0.2794)
						)
					)
					(width 0)
					(fill yes)
				)
			)
		)
	)
	(footprint ""
		(layer "F.Cu")
		(at 40.2844 -366.319816)
		(property "Reference" "D18"
			(at 0 0 0)
			(layer "F.SilkS")
			(hide yes)
			(effects
				(font
					(size 1.27 1.27)
				)
			)
		)
		(property "Value" "CH751H-40PT-1GP"
			(at -0.1016 -4.4958 0)
			(unlocked yes)
			(layer "F.Fab")
			(hide yes)
			(effects
				(font
					(size 1.016 1.016)
					(thickness 0.1524)
				)
			)
		)
		(property "Device Type" "SOD80CAKH36"
			(at -0.1016 -6.0198 0)
			(unlocked yes)
			(layer "F.Fab")
			(hide yes)
			(effects
				(font
					(size 1.016 1.016)
					(thickness 0.1524)
				)
			)
		)
		(duplicate_pad_numbers_are_jumpers no)
		(fp_line
			(start -0.8128 -1.8796)
			(end -0.8128 1.8796)
			(stroke
				(width 0.1524)
				(type default)
			)
			(layer "F.SilkS")
		)
		(fp_line
			(start -0.8128 1.8796)
			(end 0.8128 1.8796)
			(stroke
				(width 0.1524)
				(type default)
			)
			(layer "F.SilkS")
		)
		(fp_line
			(start -0.6858 2.0066)
			(end 0.6858 2.0066)
			(stroke
				(width 0.4064)
				(type default)
			)
			(layer "F.SilkS")
		)
		(fp_line
			(start 0.8128 -1.8796)
			(end -0.8128 -1.8796)
			(stroke
				(width 0.1524)
				(type default)
			)
			(layer "F.SilkS")
		)
		(fp_line
			(start 0.8128 1.8796)
			(end 0.8128 -1.8796)
			(stroke
				(width 0.1524)
				(type default)
			)
			(layer "F.SilkS")
		)
		(fp_rect
			(start -0.889 2.2098)
			(end 0.889 -1.9558)
			(stroke
				(width 0)
				(type default)
			)
			(fill no)
			(layer "F.CrtYd")
		)
		(fp_rect
			(start -0.889 2.2098)
			(end 0.889 -1.9558)
			(stroke
				(width 0)
				(type default)
			)
			(fill no)
			(layer "F.Fab")
		)
		(pad "A" smd rect
			(at 0 -1.0668)
			(size 0.762 1.1684)
			(layers "F.Cu" "F.Mask" "F.Paste")
			(net "TEMP_ALM#_REVERSE")
		)
		(pad "K" smd rect
			(at 0 1.0668)
			(size 0.762 1.1684)
			(layers "F.Cu" "F.Mask" "F.Paste")
			(net "TEMP_ALM#_REVERSE_R")
		)
	)
	(footprint ""
		(layer "F.Cu")
		(at 39.5224 -134.7978)
		(property "Reference" "PR97"
			(at 0 0 0)
			(layer "F.SilkS")
			(hide yes)
			(effects
				(font
					(size 1.27 1.27)
				)
			)
		)
		(property "Value" "0R2J-2-GP"
			(at 0.064008 -3.993896 0)
			(unlocked yes)
			(layer "F.Fab")
			(hide yes)
			(effects
				(font
					(size 1.016 1.016)
					(thickness 0.1524)
				)
			)
		)
		(property "Device Type" "R402H16"
			(at 0.064008 -5.517896 0)
			(unlocked yes)
			(layer "F.Fab")
			(hide yes)
			(effects
				(font
					(size 1.016 1.016)
					(thickness 0.1524)
				)
			)
		)
		(duplicate_pad_numbers_are_jumpers no)
		(fp_line
			(start -0.508 -0.9398)
			(end -0.508 0.9398)
			(stroke
				(width 0.1524)
				(type default)
			)
			(layer "F.SilkS")
		)
		(fp_line
			(start 0.508 -0.9398)
			(end -0.508 -0.9398)
			(stroke
				(width 0.1524)
				(type default)
			)
			(layer "F.SilkS")
		)
		(fp_rect
			(start -0.508 0.9398)
			(end 0.508 -0.9398)
			(stroke
				(width 0)
				(type default)
			)
			(fill no)
			(layer "F.CrtYd")
		)
		(fp_rect
			(start -0.508 0.9398)
			(end 0.508 -0.9398)
			(stroke
				(width 0)
				(type default)
			)
			(fill no)
			(layer "F.Fab")
		)
		(pad "1" smd custom
			(at 0 -0.4445)
			(size 0.1397 0.1397)
			(layers "F.Cu" "F.Mask" "F.Paste")
			(net "P12VL_2490_SENSE")
			(options
				(clearance outline)
				(anchor circle)
			)
			(primitives
				(gr_poly
					(pts
						(arc
							(start -0.1778 -0.2794)
							(mid -0.249642 -0.249642)
							(end -0.2794 -0.1778)
						)
						(arc
							(start -0.2794 0.1778)
							(mid -0.249642 0.249642)
							(end -0.1778 0.2794)
						)
						(arc
							(start 0.1778 0.2794)
							(mid 0.249642 0.249642)
							(end 0.2794 0.1778)
						)
						(arc
							(start 0.2794 -0.1778)
							(mid 0.249642 -0.249642)
							(end 0.1778 -0.2794)
						)
					)
					(width 0)
					(fill yes)
				)
			)
		)
		(pad "2" smd custom
			(at 0 0.4445)
			(size 0.1397 0.1397)
			(layers "F.Cu" "F.Mask" "F.Paste")
			(net "P12VL_NET")
			(options
				(clearance outline)
				(anchor circle)
			)
			(primitives
				(gr_poly
					(pts
						(arc
							(start -0.1778 -0.2794)
							(mid -0.249642 -0.249642)
							(end -0.2794 -0.1778)
						)
						(arc
							(start -0.2794 0.1778)
							(mid -0.249642 0.249642)
							(end -0.1778 0.2794)
						)
						(arc
							(start 0.1778 0.2794)
							(mid 0.249642 0.249642)
							(end 0.2794 0.1778)
						)
						(arc
							(start 0.2794 -0.1778)
							(mid 0.249642 -0.249642)
							(end 0.1778 -0.2794)
						)
					)
					(width 0)
					(fill yes)
				)
			)
		)
	)
	(footprint ""
		(layer "F.Cu")
		(at 21.7678 -219.8878 90)
		(property "Reference" "R135"
			(at 0 0 90)
			(layer "F.SilkS")
			(hide yes)
			(effects
				(font
					(size 1.27 1.27)
				)
			)
		)
		(property "Value" "4K7R2F-GP"
			(at 0.064008 -3.993896 90)
			(unlocked yes)
			(layer "F.Fab")
			(hide yes)
			(effects
				(font
					(size 1.016 1.016)
					(thickness 0.1524)
				)
			)
		)
		(property "Device Type" "R402H16"
			(at 0.064008 -5.517896 90)
			(unlocked yes)
			(layer "F.Fab")
			(hide yes)
			(effects
				(font
					(size 1.016 1.016)
					(thickness 0.1524)
				)
			)
		)
		(duplicate_pad_numbers_are_jumpers no)
		(fp_line
			(start 0.508 -0.9398)
			(end -0.508 -0.9398)
			(stroke
				(width 0.1524)
				(type default)
			)
			(layer "F.SilkS")
		)
		(fp_line
			(start -0.508 -0.9398)
			(end -0.508 0.9398)
			(stroke
				(width 0.1524)
				(type default)
			)
			(layer "F.SilkS")
		)
		(fp_rect
			(start -0.508 0.9398)
			(end 0.508 -0.9398)
			(stroke
				(width 0)
				(type default)
			)
			(fill no)
			(layer "F.CrtYd")
		)
		(fp_rect
			(start -0.508 0.9398)
			(end 0.508 -0.9398)
			(stroke
				(width 0)
				(type default)
			)
			(fill no)
			(layer "F.Fab")
		)
		(pad "1" smd custom
			(at 0 -0.4445 90)
			(size 0.1397 0.1397)
			(layers "F.Cu" "F.Mask" "F.Paste")
			(net "P3V3")
			(options
				(clearance outline)
				(anchor circle)
			)
			(primitives
				(gr_poly
					(pts
						(arc
							(start -0.1778 -0.2794)
							(mid -0.249642 -0.249642)
							(end -0.2794 -0.1778)
						)
						(arc
							(start -0.2794 0.1778)
							(mid -0.249642 0.249642)
							(end -0.1778 0.2794)
						)
						(arc
							(start 0.1778 0.2794)
							(mid 0.249642 0.249642)
							(end 0.2794 0.1778)
						)
						(arc
							(start 0.2794 -0.1778)
							(mid 0.249642 -0.249642)
							(end 0.1778 -0.2794)
						)
					)
					(width 0)
					(fill yes)
				)
			)
		)
		(pad "2" smd custom
			(at 0 0.4445 90)
			(size 0.1397 0.1397)
			(layers "F.Cu" "F.Mask" "F.Paste")
			(net "PWM_OUT_FAN1")
			(options
				(clearance outline)
				(anchor circle)
			)
			(primitives
				(gr_poly
					(pts
						(arc
							(start -0.1778 -0.2794)
							(mid -0.249642 -0.249642)
							(end -0.2794 -0.1778)
						)
						(arc
							(start -0.2794 0.1778)
							(mid -0.249642 0.249642)
							(end -0.1778 0.2794)
						)
						(arc
							(start 0.1778 0.2794)
							(mid 0.249642 0.249642)
							(end 0.2794 0.1778)
						)
						(arc
							(start 0.2794 -0.1778)
							(mid 0.249642 -0.249642)
							(end 0.1778 -0.2794)
						)
					)
					(width 0)
					(fill yes)
				)
			)
		)
	)
	(footprint ""
		(layer "F.Cu")
		(at 5.1054 -437.0578 90)
		(property "Reference" "R121"
			(at 0 0 90)
			(layer "F.SilkS")
			(hide yes)
			(effects
				(font
					(size 1.27 1.27)
				)
			)
		)
		(property "Value" "2KR2F-3-GP"
			(at 0.064008 -3.993896 90)
			(unlocked yes)
			(layer "F.Fab")
			(hide yes)
			(effects
				(font
					(size 1.016 1.016)
					(thickness 0.1524)
				)
			)
		)
		(property "Device Type" "R402H16"
			(at 0.064008 -5.517896 90)
			(unlocked yes)
			(layer "F.Fab")
			(hide yes)
			(effects
				(font
					(size 1.016 1.016)
					(thickness 0.1524)
				)
			)
		)
		(duplicate_pad_numbers_are_jumpers no)
		(fp_line
			(start 0.508 -0.9398)
			(end -0.508 -0.9398)
			(stroke
				(width 0.1524)
				(type default)
			)
			(layer "F.SilkS")
		)
		(fp_line
			(start -0.508 -0.9398)
			(end -0.508 0.9398)
			(stroke
				(width 0.1524)
				(type default)
			)
			(layer "F.SilkS")
		)
		(fp_rect
			(start -0.508 0.9398)
			(end 0.508 -0.9398)
			(stroke
				(width 0)
				(type default)
			)
			(fill no)
			(layer "F.CrtYd")
		)
		(fp_rect
			(start -0.508 0.9398)
			(end 0.508 -0.9398)
			(stroke
				(width 0)
				(type default)
			)
			(fill no)
			(layer "F.Fab")
		)
		(pad "1" smd custom
			(at 0 -0.4445 90)
			(size 0.1397 0.1397)
			(layers "F.Cu" "F.Mask" "F.Paste")
			(net "LED_DR_LED0")
			(options
				(clearance outline)
				(anchor circle)
			)
			(primitives
				(gr_poly
					(pts
						(arc
							(start -0.1778 -0.2794)
							(mid -0.249642 -0.249642)
							(end -0.2794 -0.1778)
						)
						(arc
							(start -0.2794 0.1778)
							(mid -0.249642 0.249642)
							(end -0.1778 0.2794)
						)
						(arc
							(start 0.1778 0.2794)
							(mid 0.249642 0.249642)
							(end 0.2794 0.1778)
						)
						(arc
							(start 0.2794 -0.1778)
							(mid 0.249642 -0.249642)
							(end 0.1778 -0.2794)
						)
					)
					(width 0)
					(fill yes)
				)
			)
		)
		(pad "2" smd custom
			(at 0 0.4445 90)
			(size 0.1397 0.1397)
			(layers "F.Cu" "F.Mask" "F.Paste")
			(net "LED_DR_LED0_B")
			(options
				(clearance outline)
				(anchor circle)
			)
			(primitives
				(gr_poly
					(pts
						(arc
							(start -0.1778 -0.2794)
							(mid -0.249642 -0.249642)
							(end -0.2794 -0.1778)
						)
						(arc
							(start -0.2794 0.1778)
							(mid -0.249642 0.249642)
							(end -0.1778 0.2794)
						)
						(arc
							(start 0.1778 0.2794)
							(mid 0.249642 0.249642)
							(end 0.2794 0.1778)
						)
						(arc
							(start 0.2794 -0.1778)
							(mid 0.249642 -0.249642)
							(end 0.1778 -0.2794)
						)
					)
					(width 0)
					(fill yes)
				)
			)
		)
	)
	(footprint ""
		(layer "F.Cu")
		(at 25.8826 -166.1414 180)
		(property "Reference" "TP5"
			(at 0 0 180)
			(layer "F.SilkS")
			(hide yes)
			(effects
				(font
					(size 1.27 1.27)
				)
			)
		)
		(property "Value" "TPAD32-GP"
			(at 0 -3.166364 180)
			(unlocked yes)
			(layer "F.Fab")
			(hide yes)
			(effects
				(font
					(size 1.016 1.016)
					(thickness 0.1524)
				)
			)
		)
		(property "Device Type" "TPAD32"
			(at 0 -4.690618 180)
			(unlocked yes)
			(layer "F.Fab")
			(hide yes)
			(effects
				(font
					(size 1.016 1.016)
					(thickness 0.1524)
				)
			)
		)
		(duplicate_pad_numbers_are_jumpers no)
		(fp_poly
			(pts
				(arc
					(start -0.7112 0)
					(mid 0.7112 0)
					(end -0.7112 0)
				)
			)
			(stroke
				(width 0)
				(type default)
			)
			(fill no)
			(layer "F.CrtYd")
		)
		(fp_poly
			(pts
				(arc
					(start -0.7112 0)
					(mid 0.7112 0)
					(end -0.7112 0)
				)
			)
			(stroke
				(width 0)
				(type default)
			)
			(fill no)
			(layer "F.Fab")
		)
		(pad "1" smd circle
			(at 0 0 180)
			(size 0.8128 0.8128)
			(layers "F.Cu" "F.Mask" "F.Paste")
			(net "NCT7904D_PWM4")
		)
	)
	(footprint ""
		(layer "F.Cu")
		(at 41.8084 -155.0162 180)
		(property "Reference" "C4"
			(at 0 0 180)
			(layer "F.SilkS")
			(hide yes)
			(effects
				(font
					(size 1.27 1.27)
				)
			)
		)
		(property "Value" "SCD1U16V2KX-3GP"
			(at 1.1811 -2.7051 180)
			(unlocked yes)
			(layer "F.Fab")
			(hide yes)
			(effects
				(font
					(size 1.016 1.016)
					(thickness 0.1524)
				)
			)
		)
		(property "Device Type" "C402H22"
			(at 1.1811 -4.2291 180)
			(unlocked yes)
			(layer "F.Fab")
			(hide yes)
			(effects
				(font
					(size 1.016 1.016)
					(thickness 0.1524)
				)
			)
		)
		(duplicate_pad_numbers_are_jumpers no)
		(fp_rect
			(start -0.4318 0.9525)
			(end 0.4318 -0.9525)
			(stroke
				(width 0)
				(type default)
			)
			(fill no)
			(layer "F.CrtYd")
		)
		(fp_rect
			(start -0.4318 0.9525)
			(end 0.4318 -0.9525)
			(stroke
				(width 0)
				(type default)
			)
			(fill no)
			(layer "F.Fab")
		)
		(pad "1" smd custom
			(at 0 -0.4445 180)
			(size 0.1524 0.1524)
			(layers "F.Cu" "F.Mask" "F.Paste")
			(net "NCT7904_3VSB")
			(options
				(clearance outline)
				(anchor circle)
			)
			(primitives
				(gr_poly
					(pts
						(arc
							(start 0.3048 -0.2032)
							(mid 0.275042 -0.275042)
							(end 0.2032 -0.3048)
						)
						(arc
							(start -0.2032 -0.3048)
							(mid -0.275042 -0.275042)
							(end -0.3048 -0.2032)
						)
						(arc
							(start -0.3048 0.2032)
							(mid -0.275042 0.275042)
							(end -0.2032 0.3048)
						)
						(arc
							(start 0.2032 0.3048)
							(mid 0.275042 0.275042)
							(end 0.3048 0.2032)
						)
					)
					(width 0)
					(fill yes)
				)
			)
		)
		(pad "2" smd custom
			(at 0 0.4445 180)
			(size 0.1524 0.1524)
			(layers "F.Cu" "F.Mask" "F.Paste")
			(net "GND")
			(options
				(clearance outline)
				(anchor circle)
			)
			(primitives
				(gr_poly
					(pts
						(arc
							(start 0.3048 -0.2032)
							(mid 0.275042 -0.275042)
							(end 0.2032 -0.3048)
						)
						(arc
							(start -0.2032 -0.3048)
							(mid -0.275042 -0.275042)
							(end -0.3048 -0.2032)
						)
						(arc
							(start -0.3048 0.2032)
							(mid -0.275042 0.275042)
							(end -0.2032 0.3048)
						)
						(arc
							(start 0.2032 0.3048)
							(mid 0.275042 0.275042)
							(end 0.3048 0.2032)
						)
					)
					(width 0)
					(fill yes)
				)
			)
		)
	)
	(footprint ""
		(layer "F.Cu")
		(at 23.368 -369.697 -90)
		(property "Reference" "PC4"
			(at 0 0 270)
			(layer "F.SilkS")
			(hide yes)
			(effects
				(font
					(size 1.27 1.27)
				)
			)
		)
		(property "Value" "SC1U25V3KX-1-GP"
			(at 0 -2.8194 270)
			(unlocked yes)
			(layer "F.Fab")
			(hide yes)
			(effects
				(font
					(size 1.016 1.016)
					(thickness 0.1524)
				)
			)
		)
		(property "Device Type" "C603H36"
			(at 0 -4.3434 270)
			(unlocked yes)
			(layer "F.Fab")
			(hide yes)
			(effects
				(font
					(size 1.016 1.016)
					(thickness 0.1524)
				)
			)
		)
		(duplicate_pad_numbers_are_jumpers no)
		(fp_line
			(start 0.508 0)
			(end -0.508 0)
			(stroke
				(width 0.2032)
				(type default)
			)
			(layer "F.SilkS")
		)
		(fp_rect
			(start -0.5842 1.3335)
			(end 0.5842 -1.3335)
			(stroke
				(width 0)
				(type default)
			)
			(fill no)
			(layer "F.CrtYd")
		)
		(fp_rect
			(start -0.5842 1.3335)
			(end 0.5842 -1.3335)
			(stroke
				(width 0)
				(type default)
			)
			(fill no)
			(layer "F.Fab")
		)
		(pad "1" smd custom
			(at 0 -0.762 270)
			(size 0.2159 0.2159)
			(layers "F.Cu" "F.Mask" "F.Paste")
			(net "ADM1276_VCAP")
			(options
				(clearance outline)
				(anchor circle)
			)
			(primitives
				(gr_poly
					(pts
						(arc
							(start -0.3302 -0.4318)
							(mid -0.402042 -0.402042)
							(end -0.4318 -0.3302)
						)
						(arc
							(start -0.4318 0.3302)
							(mid -0.402042 0.402042)
							(end -0.3302 0.4318)
						)
						(arc
							(start 0.3302 0.4318)
							(mid 0.402042 0.402042)
							(end 0.4318 0.3302)
						)
						(arc
							(start 0.4318 -0.3302)
							(mid 0.402042 -0.402042)
							(end 0.3302 -0.4318)
						)
					)
					(width 0)
					(fill yes)
				)
			)
		)
		(pad "2" smd custom
			(at 0 0.762 270)
			(size 0.2159 0.2159)
			(layers "F.Cu" "F.Mask" "F.Paste")
			(net "GND")
			(options
				(clearance outline)
				(anchor circle)
			)
			(primitives
				(gr_poly
					(pts
						(arc
							(start -0.3302 -0.4318)
							(mid -0.402042 -0.402042)
							(end -0.4318 -0.3302)
						)
						(arc
							(start -0.4318 0.3302)
							(mid -0.402042 0.402042)
							(end -0.3302 0.4318)
						)
						(arc
							(start 0.3302 0.4318)
							(mid 0.402042 0.402042)
							(end 0.4318 0.3302)
						)
						(arc
							(start 0.4318 -0.3302)
							(mid 0.402042 -0.402042)
							(end 0.3302 -0.4318)
						)
					)
					(width 0)
					(fill yes)
				)
			)
		)
	)
	(footprint ""
		(layer "F.Cu")
		(at 13.923518 -230.153972 180)
		(property "Reference" "Q5"
			(at 0 0 180)
			(layer "F.SilkS")
			(hide yes)
			(effects
				(font
					(size 1.27 1.27)
				)
			)
		)
		(property "Value" "PMBS3904-1-GP"
			(at 0 -9.0932 180)
			(unlocked yes)
			(layer "F.Fab")
			(hide yes)
			(effects
				(font
					(size 1.016 1.016)
					(thickness 0.1524)
				)
			)
		)
		(property "Device Type" "SOT-23-10H44"
			(at 0 -10.6172 180)
			(unlocked yes)
			(layer "F.Fab")
			(hide yes)
			(effects
				(font
					(size 1.016 1.016)
					(thickness 0.1524)
				)
			)
		)
		(duplicate_pad_numbers_are_jumpers no)
		(fp_line
			(start 1.651 1.778)
			(end 1.651 -1.778)
			(stroke
				(width 0.1524)
				(type default)
			)
			(layer "F.SilkS")
		)
		(fp_line
			(start 1.651 -1.778)
			(end -1.651 -1.778)
			(stroke
				(width 0.1524)
				(type default)
			)
			(layer "F.SilkS")
		)
		(fp_line
			(start -0.635 1.8796)
			(end -1.7526 1.8796)
			(stroke
				(width 0.3302)
				(type default)
			)
			(layer "F.SilkS")
		)
		(fp_line
			(start -0.71628 2.15265)
			(end -1.26492 2.15265)
			(stroke
				(width 0.0127)
				(type default)
			)
			(layer "F.SilkS")
		)
		(fp_line
			(start -0.719074 2.145538)
			(end -1.265936 2.14122)
			(stroke
				(width 0.0127)
				(type default)
			)
			(layer "F.SilkS")
		)
		(fp_line
			(start -0.9906 1.86309)
			(end -0.701294 2.15265)
			(stroke
				(width 0.0127)
				(type default)
			)
			(layer "F.SilkS")
		)
		(fp_line
			(start -0.994156 1.8669)
			(end -0.987044 1.8669)
			(stroke
				(width 0.0127)
				(type default)
			)
			(layer "F.SilkS")
		)
		(fp_line
			(start -1.003808 1.876552)
			(end -0.977646 1.876552)
			(stroke
				(width 0.0127)
				(type default)
			)
			(layer "F.SilkS")
		)
		(fp_line
			(start -1.013206 1.88595)
			(end -0.967994 1.88595)
			(stroke
				(width 0.0127)
				(type default)
			)
			(layer "F.SilkS")
		)
		(fp_line
			(start -1.022858 1.895602)
			(end -0.958596 1.895602)
			(stroke
				(width 0.0127)
				(type default)
			)
			(layer "F.SilkS")
		)
		(fp_line
			(start -1.032256 1.905)
			(end -0.948944 1.905)
			(stroke
				(width 0.0127)
				(type default)
			)
			(layer "F.SilkS")
		)
		(fp_line
			(start -1.041908 1.914652)
			(end -0.939546 1.914652)
			(stroke
				(width 0.0127)
				(type default)
			)
			(layer "F.SilkS")
		)
		(fp_line
			(start -1.051306 1.92405)
			(end -0.929894 1.92405)
			(stroke
				(width 0.0127)
				(type default)
			)
			(layer "F.SilkS")
		)
		(fp_line
			(start -1.060958 1.933702)
			(end -0.920496 1.933702)
			(stroke
				(width 0.0127)
				(type default)
			)
			(layer "F.SilkS")
		)
		(fp_line
			(start -1.070356 1.9431)
			(end -0.910844 1.9431)
			(stroke
				(width 0.0127)
				(type default)
			)
			(layer "F.SilkS")
		)
		(fp_line
			(start -1.080008 1.952752)
			(end -0.901446 1.952752)
			(stroke
				(width 0.0127)
				(type default)
			)
			(layer "F.SilkS")
		)
		(fp_line
			(start -1.089406 1.96215)
			(end -0.891794 1.96215)
			(stroke
				(width 0.0127)
				(type default)
			)
			(layer "F.SilkS")
		)
		(fp_line
			(start -1.099058 1.971802)
			(end -0.882396 1.971802)
			(stroke
				(width 0.0127)
				(type default)
			)
			(layer "F.SilkS")
		)
		(fp_line
			(start -1.108456 1.9812)
			(end -0.872744 1.9812)
			(stroke
				(width 0.0127)
				(type default)
			)
			(layer "F.SilkS")
		)
		(fp_line
			(start -1.118108 1.990852)
			(end -0.863346 1.990852)
			(stroke
				(width 0.0127)
				(type default)
			)
			(layer "F.SilkS")
		)
		(fp_line
			(start -1.127506 2.00025)
			(end -0.853694 2.00025)
			(stroke
				(width 0.0127)
				(type default)
			)
			(layer "F.SilkS")
		)
		(fp_line
			(start -1.137158 2.009902)
			(end -0.844296 2.009902)
			(stroke
				(width 0.0127)
				(type default)
			)
			(layer "F.SilkS")
		)
		(fp_line
			(start -1.146556 2.0193)
			(end -0.834644 2.0193)
			(stroke
				(width 0.0127)
				(type default)
			)
			(layer "F.SilkS")
		)
		(fp_line
			(start -1.156208 2.028952)
			(end -0.825246 2.028952)
			(stroke
				(width 0.0127)
				(type default)
			)
			(layer "F.SilkS")
		)
		(fp_line
			(start -1.165606 2.03835)
			(end -0.815594 2.03835)
			(stroke
				(width 0.0127)
				(type default)
			)
			(layer "F.SilkS")
		)
		(fp_line
			(start -1.175258 2.048002)
			(end -0.806196 2.048002)
			(stroke
				(width 0.0127)
				(type default)
			)
			(layer "F.SilkS")
		)
		(fp_line
			(start -1.184656 2.0574)
			(end -0.796544 2.0574)
			(stroke
				(width 0.0127)
				(type default)
			)
			(layer "F.SilkS")
		)
		(fp_line
			(start -1.194308 2.067052)
			(end -0.787146 2.067052)
			(stroke
				(width 0.0127)
				(type default)
			)
			(layer "F.SilkS")
		)
		(fp_line
			(start -1.203706 2.07645)
			(end -0.777494 2.07645)
			(stroke
				(width 0.0127)
				(type default)
			)
			(layer "F.SilkS")
		)
		(fp_line
			(start -1.213358 2.086102)
			(end -0.768096 2.086102)
			(stroke
				(width 0.0127)
				(type default)
			)
			(layer "F.SilkS")
		)
		(fp_line
			(start -1.222756 2.0955)
			(end -0.758444 2.0955)
			(stroke
				(width 0.0127)
				(type default)
			)
			(layer "F.SilkS")
		)
		(fp_line
			(start -1.232408 2.105152)
			(end -0.749046 2.105152)
			(stroke
				(width 0.0127)
				(type default)
			)
			(layer "F.SilkS")
		)
		(fp_line
			(start -1.241806 2.11455)
			(end -0.739394 2.11455)
			(stroke
				(width 0.0127)
				(type default)
			)
			(layer "F.SilkS")
		)
		(fp_line
			(start -1.251458 2.124202)
			(end -0.729996 2.124202)
			(stroke
				(width 0.0127)
				(type default)
			)
			(layer "F.SilkS")
		)
		(fp_line
			(start -1.260856 2.1336)
			(end -0.720344 2.1336)
			(stroke
				(width 0.0127)
				(type default)
			)
			(layer "F.SilkS")
		)
		(fp_line
			(start -1.279144 2.15265)
			(end -0.701294 2.15265)
			(stroke
				(width 0.0127)
				(type default)
			)
			(layer "F.SilkS")
		)
		(fp_line
			(start -1.279398 2.152142)
			(end -0.9906 1.86309)
			(stroke
				(width 0.0127)
				(type default)
			)
			(layer "F.SilkS")
		)
		(fp_line
			(start -1.651 1.778)
			(end 1.651 1.778)
			(stroke
				(width 0.1524)
				(type default)
			)
			(layer "F.SilkS")
		)
		(fp_line
			(start -1.651 -1.778)
			(end -1.651 1.778)
			(stroke
				(width 0.1524)
				(type default)
			)
			(layer "F.SilkS")
		)
		(fp_line
			(start -1.7526 1.8796)
			(end -1.7526 0.9906)
			(stroke
				(width 0.3302)
				(type default)
			)
			(layer "F.SilkS")
		)
		(fp_poly
			(pts
				(xy -1.285748 2.159) (xy -1.285748 1.8796) (xy -1.778 1.8796) (xy -1.778 -1.8796) (xy 1.778 -1.8796)
				(xy 1.778 1.8796) (xy -0.694944 1.8796) (xy -0.694944 2.159)
			)
			(stroke
				(width 0)
				(type default)
			)
			(fill no)
			(layer "F.CrtYd")
		)
		(fp_poly
			(pts
				(xy -1.285748 2.159) (xy -1.285748 1.8796) (xy -1.778 1.8796) (xy -1.778 -1.8796) (xy 1.778 -1.8796)
				(xy 1.778 1.8796) (xy -0.694944 1.8796) (xy -0.694944 2.159)
			)
			(stroke
				(width 0)
				(type default)
			)
			(fill no)
			(layer "F.Fab")
		)
		(pad "1" smd rect
			(at -0.98425 0.9525 180)
			(size 0.762 1.143)
			(layers "F.Cu" "F.Mask" "F.Paste")
			(net "LED_DR_LED3_B")
		)
		(pad "2" smd rect
			(at 0.98425 0.9525 180)
			(size 0.762 1.143)
			(layers "F.Cu" "F.Mask" "F.Paste")
			(net "GND")
		)
		(pad "3" smd rect
			(at 0 -0.9525 180)
			(size 0.762 1.143)
			(layers "F.Cu" "F.Mask" "F.Paste")
			(net "LED_DR_LED3_BLUE")
		)
	)
	(footprint ""
		(layer "F.Cu")
		(at 43.3324 -134.8232)
		(property "Reference" "PR96"
			(at 0 0 0)
			(layer "F.SilkS")
			(hide yes)
			(effects
				(font
					(size 1.27 1.27)
				)
			)
		)
		(property "Value" "0R2J-2-GP"
			(at 0.064008 -3.993896 0)
			(unlocked yes)
			(layer "F.Fab")
			(hide yes)
			(effects
				(font
					(size 1.016 1.016)
					(thickness 0.1524)
				)
			)
		)
		(property "Device Type" "R402H16"
			(at 0.064008 -5.517896 0)
			(unlocked yes)
			(layer "F.Fab")
			(hide yes)
			(effects
				(font
					(size 1.016 1.016)
					(thickness 0.1524)
				)
			)
		)
		(duplicate_pad_numbers_are_jumpers no)
		(fp_line
			(start -0.508 -0.9398)
			(end -0.508 0.9398)
			(stroke
				(width 0.1524)
				(type default)
			)
			(layer "F.SilkS")
		)
		(fp_line
			(start 0.508 -0.9398)
			(end -0.508 -0.9398)
			(stroke
				(width 0.1524)
				(type default)
			)
			(layer "F.SilkS")
		)
		(fp_rect
			(start -0.508 0.9398)
			(end 0.508 -0.9398)
			(stroke
				(width 0)
				(type default)
			)
			(fill no)
			(layer "F.CrtYd")
		)
		(fp_rect
			(start -0.508 0.9398)
			(end 0.508 -0.9398)
			(stroke
				(width 0)
				(type default)
			)
			(fill no)
			(layer "F.Fab")
		)
		(pad "1" smd custom
			(at 0 -0.4445)
			(size 0.1397 0.1397)
			(layers "F.Cu" "F.Mask" "F.Paste")
			(net "P12VL_2490_VCC")
			(options
				(clearance outline)
				(anchor circle)
			)
			(primitives
				(gr_poly
					(pts
						(arc
							(start -0.1778 -0.2794)
							(mid -0.249642 -0.249642)
							(end -0.2794 -0.1778)
						)
						(arc
							(start -0.2794 0.1778)
							(mid -0.249642 0.249642)
							(end -0.1778 0.2794)
						)
						(arc
							(start 0.1778 0.2794)
							(mid 0.249642 0.249642)
							(end 0.2794 0.1778)
						)
						(arc
							(start 0.2794 -0.1778)
							(mid 0.249642 -0.249642)
							(end 0.1778 -0.2794)
						)
					)
					(width 0)
					(fill yes)
				)
			)
		)
		(pad "2" smd custom
			(at 0 0.4445)
			(size 0.1397 0.1397)
			(layers "F.Cu" "F.Mask" "F.Paste")
			(net "P12V")
			(options
				(clearance outline)
				(anchor circle)
			)
			(primitives
				(gr_poly
					(pts
						(arc
							(start -0.1778 -0.2794)
							(mid -0.249642 -0.249642)
							(end -0.2794 -0.1778)
						)
						(arc
							(start -0.2794 0.1778)
							(mid -0.249642 0.249642)
							(end -0.1778 0.2794)
						)
						(arc
							(start 0.1778 0.2794)
							(mid 0.249642 0.249642)
							(end 0.2794 0.1778)
						)
						(arc
							(start 0.2794 -0.1778)
							(mid 0.249642 -0.249642)
							(end 0.1778 -0.2794)
						)
					)
					(width 0)
					(fill yes)
				)
			)
		)
	)
	(footprint ""
		(layer "F.Cu")
		(at 46.863 -416.814 90)
		(property "Reference" "PC8"
			(at 0 0 90)
			(layer "F.SilkS")
			(hide yes)
			(effects
				(font
					(size 1.27 1.27)
				)
			)
		)
		(property "Value" "SC1U25V5KX-1GP"
			(at -0.0762 -6.1214 90)
			(unlocked yes)
			(layer "F.Fab")
			(hide yes)
			(effects
				(font
					(size 1.016 1.016)
					(thickness 0.1524)
				)
			)
		)
		(property "Device Type" "C805H58"
			(at -0.0762 -8.1534 90)
			(unlocked yes)
			(layer "F.Fab")
			(hide yes)
			(effects
				(font
					(size 1.016 1.016)
					(thickness 0.1524)
				)
			)
		)
		(duplicate_pad_numbers_are_jumpers no)
		(fp_line
			(start 0.635 0)
			(end -0.635 0)
			(stroke
				(width 0.508)
				(type default)
			)
			(layer "F.SilkS")
		)
		(fp_rect
			(start -0.9652 1.778)
			(end 0.9652 -1.778)
			(stroke
				(width 0)
				(type default)
			)
			(fill no)
			(layer "F.CrtYd")
		)
		(fp_poly
			(pts
				(xy -0.9652 -1.778) (xy 0.9652 -1.778) (xy 0.9652 1.778) (xy -0.9652 1.778)
			)
			(stroke
				(width 0)
				(type default)
			)
			(fill no)
			(layer "F.Fab")
		)
		(pad "1" smd rect
			(at 0 -0.9652 90)
			(size 1.397 1.143)
			(layers "F.Cu" "F.Mask" "F.Paste")
			(net "P12V_AUX")
		)
		(pad "2" smd rect
			(at 0 0.9652 90)
			(size 1.397 1.143)
			(layers "F.Cu" "F.Mask" "F.Paste")
			(net "GND")
		)
	)
	(footprint ""
		(layer "F.Cu")
		(at 21.844 -202.7936 -90)
		(property "Reference" "TC15"
			(at 0 0 270)
			(layer "F.SilkS")
			(hide yes)
			(effects
				(font
					(size 1.27 1.27)
				)
			)
		)
		(property "Value" "ST15U25VDM-1-GP"
			(at 0 -9.6012 270)
			(unlocked yes)
			(layer "F.Fab")
			(hide yes)
			(effects
				(font
					(size 1.016 1.016)
					(thickness 0.1524)
				)
			)
		)
		(property "Device Type" "CT7343H79"
			(at 0 -11.1252 270)
			(unlocked yes)
			(layer "F.Fab")
			(hide yes)
			(effects
				(font
					(size 1.016 1.016)
					(thickness 0.1524)
				)
			)
		)
		(duplicate_pad_numbers_are_jumpers no)
		(fp_line
			(start -2.286 4.8768)
			(end -2.286 2.032)
			(stroke
				(width 0.1524)
				(type default)
			)
			(layer "F.SilkS")
		)
		(fp_line
			(start 2.286 4.8768)
			(end -2.286 4.8768)
			(stroke
				(width 0.1524)
				(type default)
			)
			(layer "F.SilkS")
		)
		(fp_line
			(start 2.286 2.032)
			(end 2.286 4.8768)
			(stroke
				(width 0.1524)
				(type default)
			)
			(layer "F.SilkS")
		)
		(fp_line
			(start 2.286 -2.032)
			(end 2.286 -4.8768)
			(stroke
				(width 0.1524)
				(type default)
			)
			(layer "F.SilkS")
		)
		(fp_line
			(start 2.1082 -4.699)
			(end -2.1082 -4.699)
			(stroke
				(width 0.508)
				(type default)
			)
			(layer "F.SilkS")
		)
		(fp_line
			(start -2.286 -4.8768)
			(end -2.286 -2.032)
			(stroke
				(width 0.1524)
				(type default)
			)
			(layer "F.SilkS")
		)
		(fp_line
			(start 2.286 -4.8768)
			(end -2.286 -4.8768)
			(stroke
				(width 0.1524)
				(type default)
			)
			(layer "F.SilkS")
		)
		(fp_rect
			(start -2.1463 3.6449)
			(end 2.1463 -3.6449)
			(stroke
				(width 0)
				(type default)
			)
			(fill no)
			(layer "F.CrtYd")
		)
		(fp_poly
			(pts
				(xy -2.54 4.953) (xy -2.54 4.2926) (xy -3.81 4.2926) (xy -3.81 -4.2926) (xy -2.54 -4.2926) (xy -2.54 -4.953)
				(xy 2.54 -4.953) (xy 2.54 -4.2926) (xy 3.81 -4.2926) (xy 3.81 -1.6256) (xy 2.1463 -1.6256) (xy 2.1463 -3.6449)
				(xy -2.1463 -3.6449) (xy -2.1463 3.6449) (xy 2.1463 3.6449) (xy 2.1463 -1.6129) (xy 3.81 -1.6129)
				(xy 3.81 4.2926) (xy 2.54 4.2926) (xy 2.54 4.953)
			)
			(stroke
				(width 0)
				(type default)
			)
			(fill no)
			(layer "F.CrtYd")
		)
		(fp_rect
			(start -2.54 4.953)
			(end 2.54 -4.953)
			(stroke
				(width 0)
				(type default)
			)
			(fill no)
			(layer "F.Fab")
		)
		(fp_rect
			(start -3.81 4.2926)
			(end -2.54 -4.2926)
			(stroke
				(width 0)
				(type default)
			)
			(fill no)
			(layer "F.Fab")
		)
		(fp_rect
			(start 2.54 4.2926)
			(end 3.81 -4.2926)
			(stroke
				(width 0)
				(type default)
			)
			(fill no)
			(layer "F.Fab")
		)
		(pad "1" smd rect
			(at 0 -3.1496 270)
			(size 2.413 2.286)
			(layers "F.Cu" "F.Mask" "F.Paste")
			(net "P12V")
		)
		(pad "2" smd rect
			(at 0 3.1496 270)
			(size 2.413 2.286)
			(layers "F.Cu" "F.Mask" "F.Paste")
			(net "GND")
		)
		(zone
			(layer "F.Cu")
			(hatch none 0.5)
			(connect_pads
				(clearance 0)
			)
			(min_thickness 0.25)
			(keepout
				(tracks allowed)
				(vias not_allowed)
				(pads allowed)
				(copperpour not_allowed)
				(footprints allowed)
			)
			(placement
				(enabled no)
				(sheetname "")
			)
			(fill
				(thermal_gap 0.5)
				(thermal_bridge_width 0.5)
				(island_removal_mode 0)
			)
			(polygon
				(pts
					(xy 17.2466 -204.3049) (xy 17.2466 -201.2823) (xy 20.1422 -201.2823) (xy 20.4724 -201.2823) (xy 20.4724 -204.3049)
					(xy 20.1422 -204.3049)
				)
			)
		)
		(zone
			(layer "F.Cu")
			(hatch none 0.5)
			(connect_pads
				(clearance 0)
			)
			(min_thickness 0.25)
			(keepout
				(tracks allowed)
				(vias not_allowed)
				(pads allowed)
				(copperpour not_allowed)
				(footprints allowed)
			)
			(placement
				(enabled no)
				(sheetname "")
			)
			(fill
				(thermal_gap 0.5)
				(thermal_bridge_width 0.5)
				(island_removal_mode 0)
			)
			(polygon
				(pts
					(xy 23.5331 -201.2823) (xy 26.4414 -201.2823) (xy 26.4414 -204.3049) (xy 23.5458 -204.3049) (xy 23.2156 -204.3049)
					(xy 23.2156 -201.2823)
				)
			)
		)
	)
	(footprint ""
		(layer "F.Cu")
		(at 37.1602 -246.5324)
		(property "Reference" "U6"
			(at 0 0 0)
			(layer "F.SilkS")
			(hide yes)
			(effects
				(font
					(size 1.27 1.27)
				)
			)
		)
		(property "Value" "PCA9551PW-T-2GP-U"
			(at 0.127 -12.573 0)
			(unlocked yes)
			(layer "F.Fab")
			(hide yes)
			(effects
				(font
					(size 1.016 1.016)
					(thickness 0.1524)
				)
			)
		)
		(property "Device Type" "TSOIC16H44"
			(at 0.1016 -14.5796 0)
			(unlocked yes)
			(layer "F.Fab")
			(hide yes)
			(effects
				(font
					(size 1.016 1.016)
					(thickness 0.1524)
				)
			)
		)
		(duplicate_pad_numbers_are_jumpers no)
		(fp_line
			(start -3.0988 -1.778)
			(end -3.0988 1.778)
			(stroke
				(width 0.1524)
				(type default)
			)
			(layer "F.SilkS")
		)
		(fp_line
			(start -3.0988 -1.778)
			(end 2.3622 -1.778)
			(stroke
				(width 0.1524)
				(type default)
			)
			(layer "F.SilkS")
		)
		(fp_line
			(start -2.921 3.81)
			(end -2.921 1.778)
			(stroke
				(width 0.508)
				(type default)
			)
			(layer "F.SilkS")
		)
		(fp_line
			(start -2.54 0)
			(end -3.0988 -0.5588)
			(stroke
				(width 0.1524)
				(type default)
			)
			(layer "F.SilkS")
		)
		(fp_line
			(start -2.54 0)
			(end -3.0988 0.5588)
			(stroke
				(width 0.1524)
				(type default)
			)
			(layer "F.SilkS")
		)
		(fp_line
			(start 2.3622 -1.778)
			(end 2.3622 1.778)
			(stroke
				(width 0.1524)
				(type default)
			)
			(layer "F.SilkS")
		)
		(fp_line
			(start 2.3622 1.778)
			(end -2.921 1.778)
			(stroke
				(width 0.1524)
				(type default)
			)
			(layer "F.SilkS")
		)
		(fp_poly
			(pts
				(xy -2.4638 -1.778) (xy -2.4638 1.778) (xy 2.3622 1.778) (xy 2.3622 -1.778)
			)
			(stroke
				(width 0)
				(type default)
			)
			(fill yes)
			(layer "F.SilkS")
		)
		(fp_rect
			(start -3.175 4.064)
			(end 3.175 -4.064)
			(stroke
				(width 0)
				(type default)
			)
			(fill no)
			(layer "F.CrtYd")
		)
		(fp_poly
			(pts
				(xy -3.175 -4.064) (xy 3.175 -4.064) (xy 3.175 4.064) (xy -3.175 4.064)
			)
			(stroke
				(width 0)
				(type default)
			)
			(fill no)
			(layer "F.Fab")
		)
		(pad "1" smd rect
			(at -2.27584 2.8194)
			(size 0.3556 1.524)
			(layers "F.Cu" "F.Mask" "F.Paste")
			(net "LED_DRV_A0")
		)
		(pad "2" smd rect
			(at -1.6256 2.8194)
			(size 0.3556 1.524)
			(layers "F.Cu" "F.Mask" "F.Paste")
			(net "LED_DRV_A1")
		)
		(pad "3" smd rect
			(at -0.97536 2.8194)
			(size 0.3556 1.524)
			(layers "F.Cu" "F.Mask" "F.Paste")
			(net "LED_DRV_A2")
		)
		(pad "4" smd rect
			(at -0.32512 2.8194)
			(size 0.3556 1.524)
			(layers "F.Cu" "F.Mask" "F.Paste")
			(net "LED_DR_LED0")
		)
		(pad "5" smd rect
			(at 0.32512 2.8194)
			(size 0.3556 1.524)
			(layers "F.Cu" "F.Mask" "F.Paste")
			(net "LED_DR_LED1")
		)
		(pad "6" smd rect
			(at 0.97536 2.8194)
			(size 0.3556 1.524)
			(layers "F.Cu" "F.Mask" "F.Paste")
			(net "LED_DR_LED2")
		)
		(pad "7" smd rect
			(at 1.6256 2.8194)
			(size 0.3556 1.524)
			(layers "F.Cu" "F.Mask" "F.Paste")
			(net "LED_DR_LED3")
		)
		(pad "8" smd rect
			(at 2.27584 2.8194)
			(size 0.3556 1.524)
			(layers "F.Cu" "F.Mask" "F.Paste")
			(net "GND")
		)
		(pad "9" smd rect
			(at 2.27584 -2.8194)
			(size 0.3556 1.524)
			(layers "F.Cu" "F.Mask" "F.Paste")
			(net "LED_DR_LED4")
		)
		(pad "10" smd rect
			(at 1.6256 -2.8194)
			(size 0.3556 1.524)
			(layers "F.Cu" "F.Mask" "F.Paste")
			(net "LED_DR_LED5")
		)
		(pad "11" smd rect
			(at 0.97536 -2.8194)
			(size 0.3556 1.524)
			(layers "F.Cu" "F.Mask" "F.Paste")
			(net "LED_DR_LED6_RESERVE")
		)
		(pad "12" smd rect
			(at 0.32512 -2.8194)
			(size 0.3556 1.524)
			(layers "F.Cu" "F.Mask" "F.Paste")
			(net "LED_DR_LED7_RESERVE")
		)
		(pad "13" smd rect
			(at -0.32512 -2.8194)
			(size 0.3556 1.524)
			(layers "F.Cu" "F.Mask" "F.Paste")
			(net "LED_DRV_RST")
		)
		(pad "14" smd rect
			(at -0.97536 -2.8194)
			(size 0.3556 1.524)
			(layers "F.Cu" "F.Mask" "F.Paste")
			(net "I2C_C_SCL_LEDDRV")
		)
		(pad "15" smd rect
			(at -1.6256 -2.8194)
			(size 0.3556 1.524)
			(layers "F.Cu" "F.Mask" "F.Paste")
			(net "I2C_C_SDA_LEDDRV")
		)
		(pad "16" smd rect
			(at -2.27584 -2.8194)
			(size 0.3556 1.524)
			(layers "F.Cu" "F.Mask" "F.Paste")
			(net "P3V3")
		)
	)
	(footprint ""
		(layer "F.Cu")
		(at 26.15438 -376.08256 -90)
		(property "Reference" "PC2"
			(at 0 0 270)
			(layer "F.SilkS")
			(hide yes)
			(effects
				(font
					(size 1.27 1.27)
				)
			)
		)
		(property "Value" "SC10U25V5KX-GP"
			(at -0.0762 -6.1214 270)
			(unlocked yes)
			(layer "F.Fab")
			(hide yes)
			(effects
				(font
					(size 1.016 1.016)
					(thickness 0.1524)
				)
			)
		)
		(property "Device Type" "C805H56"
			(at -0.0762 -8.1534 270)
			(unlocked yes)
			(layer "F.Fab")
			(hide yes)
			(effects
				(font
					(size 1.016 1.016)
					(thickness 0.1524)
				)
			)
		)
		(duplicate_pad_numbers_are_jumpers no)
		(fp_line
			(start 0.635 0)
			(end -0.635 0)
			(stroke
				(width 0.508)
				(type default)
			)
			(layer "F.SilkS")
		)
		(fp_rect
			(start -0.9652 1.778)
			(end 0.9652 -1.778)
			(stroke
				(width 0)
				(type default)
			)
			(fill no)
			(layer "F.CrtYd")
		)
		(fp_poly
			(pts
				(xy -0.9652 -1.778) (xy 0.9652 -1.778) (xy 0.9652 1.778) (xy -0.9652 1.778)
			)
			(stroke
				(width 0)
				(type default)
			)
			(fill no)
			(layer "F.Fab")
		)
		(pad "1" smd rect
			(at 0 -0.9652 270)
			(size 1.397 1.143)
			(layers "F.Cu" "F.Mask" "F.Paste")
			(net "ADM1276_VCC")
		)
		(pad "2" smd rect
			(at 0 0.9652 270)
			(size 1.397 1.143)
			(layers "F.Cu" "F.Mask" "F.Paste")
			(net "GND")
		)
	)
	(footprint ""
		(layer "F.Cu")
		(at 28.702 -194.0814 90)
		(property "Reference" "C41"
			(at 0 0 90)
			(layer "F.SilkS")
			(hide yes)
			(effects
				(font
					(size 1.27 1.27)
				)
			)
		)
		(property "Value" "SCD1U50V3KX-GP"
			(at 0 -2.8194 90)
			(unlocked yes)
			(layer "F.Fab")
			(hide yes)
			(effects
				(font
					(size 1.016 1.016)
					(thickness 0.1524)
				)
			)
		)
		(property "Device Type" "C603H36"
			(at 0 -4.3434 90)
			(unlocked yes)
			(layer "F.Fab")
			(hide yes)
			(effects
				(font
					(size 1.016 1.016)
					(thickness 0.1524)
				)
			)
		)
		(duplicate_pad_numbers_are_jumpers no)
		(fp_line
			(start 0.508 0)
			(end -0.508 0)
			(stroke
				(width 0.2032)
				(type default)
			)
			(layer "F.SilkS")
		)
		(fp_rect
			(start -0.5842 1.3335)
			(end 0.5842 -1.3335)
			(stroke
				(width 0)
				(type default)
			)
			(fill no)
			(layer "F.CrtYd")
		)
		(fp_rect
			(start -0.5842 1.3335)
			(end 0.5842 -1.3335)
			(stroke
				(width 0)
				(type default)
			)
			(fill no)
			(layer "F.Fab")
		)
		(pad "1" smd custom
			(at 0 -0.762 90)
			(size 0.2159 0.2159)
			(layers "F.Cu" "F.Mask" "F.Paste")
			(net "P12V")
			(options
				(clearance outline)
				(anchor circle)
			)
			(primitives
				(gr_poly
					(pts
						(arc
							(start -0.3302 -0.4318)
							(mid -0.402042 -0.402042)
							(end -0.4318 -0.3302)
						)
						(arc
							(start -0.4318 0.3302)
							(mid -0.402042 0.402042)
							(end -0.3302 0.4318)
						)
						(arc
							(start 0.3302 0.4318)
							(mid 0.402042 0.402042)
							(end 0.4318 0.3302)
						)
						(arc
							(start 0.4318 -0.3302)
							(mid 0.402042 -0.402042)
							(end 0.3302 -0.4318)
						)
					)
					(width 0)
					(fill yes)
				)
			)
		)
		(pad "2" smd custom
			(at 0 0.762 90)
			(size 0.2159 0.2159)
			(layers "F.Cu" "F.Mask" "F.Paste")
			(net "GND")
			(options
				(clearance outline)
				(anchor circle)
			)
			(primitives
				(gr_poly
					(pts
						(arc
							(start -0.3302 -0.4318)
							(mid -0.402042 -0.402042)
							(end -0.4318 -0.3302)
						)
						(arc
							(start -0.4318 0.3302)
							(mid -0.402042 0.402042)
							(end -0.3302 0.4318)
						)
						(arc
							(start 0.3302 0.4318)
							(mid 0.402042 0.402042)
							(end 0.4318 0.3302)
						)
						(arc
							(start 0.4318 -0.3302)
							(mid 0.402042 -0.402042)
							(end 0.3302 -0.4318)
						)
					)
					(width 0)
					(fill yes)
				)
			)
		)
	)
	(footprint ""
		(layer "F.Cu")
		(at 12.5984 -146.1008)
		(property "Reference" "R74"
			(at 0 0 0)
			(layer "F.SilkS")
			(hide yes)
			(effects
				(font
					(size 1.27 1.27)
				)
			)
		)
		(property "Value" "10KR2F-2-GP"
			(at 0.064008 -3.993896 0)
			(unlocked yes)
			(layer "F.Fab")
			(hide yes)
			(effects
				(font
					(size 1.016 1.016)
					(thickness 0.1524)
				)
			)
		)
		(property "Device Type" "R402H16"
			(at 0.064008 -5.517896 0)
			(unlocked yes)
			(layer "F.Fab")
			(hide yes)
			(effects
				(font
					(size 1.016 1.016)
					(thickness 0.1524)
				)
			)
		)
		(duplicate_pad_numbers_are_jumpers no)
		(fp_line
			(start -0.508 -0.9398)
			(end -0.508 0.9398)
			(stroke
				(width 0.1524)
				(type default)
			)
			(layer "F.SilkS")
		)
		(fp_line
			(start 0.508 -0.9398)
			(end -0.508 -0.9398)
			(stroke
				(width 0.1524)
				(type default)
			)
			(layer "F.SilkS")
		)
		(fp_rect
			(start -0.508 0.9398)
			(end 0.508 -0.9398)
			(stroke
				(width 0)
				(type default)
			)
			(fill no)
			(layer "F.CrtYd")
		)
		(fp_rect
			(start -0.508 0.9398)
			(end 0.508 -0.9398)
			(stroke
				(width 0)
				(type default)
			)
			(fill no)
			(layer "F.Fab")
		)
		(pad "1" smd custom
			(at 0 -0.4445)
			(size 0.1397 0.1397)
			(layers "F.Cu" "F.Mask" "F.Paste")
			(net "FANIN_10")
			(options
				(clearance outline)
				(anchor circle)
			)
			(primitives
				(gr_poly
					(pts
						(arc
							(start -0.1778 -0.2794)
							(mid -0.249642 -0.249642)
							(end -0.2794 -0.1778)
						)
						(arc
							(start -0.2794 0.1778)
							(mid -0.249642 0.249642)
							(end -0.1778 0.2794)
						)
						(arc
							(start 0.1778 0.2794)
							(mid 0.249642 0.249642)
							(end 0.2794 0.1778)
						)
						(arc
							(start 0.2794 -0.1778)
							(mid 0.249642 -0.249642)
							(end 0.1778 -0.2794)
						)
					)
					(width 0)
					(fill yes)
				)
			)
		)
		(pad "2" smd custom
			(at 0 0.4445)
			(size 0.1397 0.1397)
			(layers "F.Cu" "F.Mask" "F.Paste")
			(net "GND")
			(options
				(clearance outline)
				(anchor circle)
			)
			(primitives
				(gr_poly
					(pts
						(arc
							(start -0.1778 -0.2794)
							(mid -0.249642 -0.249642)
							(end -0.2794 -0.1778)
						)
						(arc
							(start -0.2794 0.1778)
							(mid -0.249642 0.249642)
							(end -0.1778 0.2794)
						)
						(arc
							(start 0.1778 0.2794)
							(mid 0.249642 0.249642)
							(end 0.2794 0.1778)
						)
						(arc
							(start 0.2794 -0.1778)
							(mid 0.249642 -0.249642)
							(end 0.1778 -0.2794)
						)
					)
					(width 0)
					(fill yes)
				)
			)
		)
	)
	(footprint ""
		(layer "F.Cu")
		(at 27.305 -378.079)
		(property "Reference" "PR2"
			(at 0 0 0)
			(layer "F.SilkS")
			(hide yes)
			(effects
				(font
					(size 1.27 1.27)
				)
			)
		)
		(property "Value" "10R2F-L-GP"
			(at 0.064008 -3.993896 0)
			(unlocked yes)
			(layer "F.Fab")
			(hide yes)
			(effects
				(font
					(size 1.016 1.016)
					(thickness 0.1524)
				)
			)
		)
		(property "Device Type" "R402H14"
			(at 0.064008 -5.517896 0)
			(unlocked yes)
			(layer "F.Fab")
			(hide yes)
			(effects
				(font
					(size 1.016 1.016)
					(thickness 0.1524)
				)
			)
		)
		(duplicate_pad_numbers_are_jumpers no)
		(fp_line
			(start -0.508 -0.9398)
			(end -0.508 0.9398)
			(stroke
				(width 0.1524)
				(type default)
			)
			(layer "F.SilkS")
		)
		(fp_line
			(start 0.508 -0.9398)
			(end -0.508 -0.9398)
			(stroke
				(width 0.1524)
				(type default)
			)
			(layer "F.SilkS")
		)
		(fp_rect
			(start -0.508 0.9398)
			(end 0.508 -0.9398)
			(stroke
				(width 0)
				(type default)
			)
			(fill no)
			(layer "F.CrtYd")
		)
		(fp_rect
			(start -0.508 0.9398)
			(end 0.508 -0.9398)
			(stroke
				(width 0)
				(type default)
			)
			(fill no)
			(layer "F.Fab")
		)
		(pad "1" smd custom
			(at 0 -0.4445)
			(size 0.1397 0.1397)
			(layers "F.Cu" "F.Mask" "F.Paste")
			(net "P12V_AUX")
			(options
				(clearance outline)
				(anchor circle)
			)
			(primitives
				(gr_poly
					(pts
						(arc
							(start -0.1778 -0.2794)
							(mid -0.249642 -0.249642)
							(end -0.2794 -0.1778)
						)
						(arc
							(start -0.2794 0.1778)
							(mid -0.249642 0.249642)
							(end -0.1778 0.2794)
						)
						(arc
							(start 0.1778 0.2794)
							(mid 0.249642 0.249642)
							(end 0.2794 0.1778)
						)
						(arc
							(start 0.2794 -0.1778)
							(mid 0.249642 -0.249642)
							(end 0.1778 -0.2794)
						)
					)
					(width 0)
					(fill yes)
				)
			)
		)
		(pad "2" smd custom
			(at 0 0.4445)
			(size 0.1397 0.1397)
			(layers "F.Cu" "F.Mask" "F.Paste")
			(net "ADM1276_VCC")
			(options
				(clearance outline)
				(anchor circle)
			)
			(primitives
				(gr_poly
					(pts
						(arc
							(start -0.1778 -0.2794)
							(mid -0.249642 -0.249642)
							(end -0.2794 -0.1778)
						)
						(arc
							(start -0.2794 0.1778)
							(mid -0.249642 0.249642)
							(end -0.1778 0.2794)
						)
						(arc
							(start 0.1778 0.2794)
							(mid 0.249642 0.249642)
							(end 0.2794 0.1778)
						)
						(arc
							(start 0.2794 -0.1778)
							(mid 0.249642 -0.249642)
							(end 0.1778 -0.2794)
						)
					)
					(width 0)
					(fill yes)
				)
			)
		)
	)
	(footprint ""
		(layer "F.Cu")
		(at 18.7452 -250.5964 -90)
		(property "Reference" "PR53"
			(at 0 0 270)
			(layer "F.SilkS")
			(hide yes)
			(effects
				(font
					(size 1.27 1.27)
				)
			)
		)
		(property "Value" "10KR3J-L1-GP"
			(at -0.0254 -2.5146 270)
			(unlocked yes)
			(layer "F.Fab")
			(hide yes)
			(effects
				(font
					(size 1.016 1.016)
					(thickness 0.1524)
				)
			)
		)
		(property "Device Type" "R603H22"
			(at -0.0254 -4.0386 270)
			(unlocked yes)
			(layer "F.Fab")
			(hide yes)
			(effects
				(font
					(size 1.016 1.016)
					(thickness 0.1524)
				)
			)
		)
		(duplicate_pad_numbers_are_jumpers no)
		(fp_line
			(start -0.4826 0)
			(end -0.2032 0)
			(stroke
				(width 0.2032)
				(type default)
			)
			(layer "F.SilkS")
		)
		(fp_line
			(start 0.2032 0)
			(end 0.4826 0)
			(stroke
				(width 0.2032)
				(type default)
			)
			(layer "F.SilkS")
		)
		(fp_rect
			(start -0.5842 1.3335)
			(end 0.5842 -1.3335)
			(stroke
				(width 0)
				(type default)
			)
			(fill no)
			(layer "F.CrtYd")
		)
		(fp_rect
			(start -0.5842 1.3335)
			(end 0.5842 -1.3335)
			(stroke
				(width 0)
				(type default)
			)
			(fill no)
			(layer "F.Fab")
		)
		(pad "1" smd custom
			(at 0 -0.762 270)
			(size 0.2159 0.2159)
			(layers "F.Cu" "F.Mask" "F.Paste")
			(net "P3V3_EN")
			(options
				(clearance outline)
				(anchor circle)
			)
			(primitives
				(gr_poly
					(pts
						(arc
							(start -0.3302 -0.4318)
							(mid -0.402042 -0.402042)
							(end -0.4318 -0.3302)
						)
						(arc
							(start -0.4318 0.3302)
							(mid -0.402042 0.402042)
							(end -0.3302 0.4318)
						)
						(arc
							(start 0.3302 0.4318)
							(mid 0.402042 0.402042)
							(end 0.4318 0.3302)
						)
						(arc
							(start 0.4318 -0.3302)
							(mid 0.402042 -0.402042)
							(end 0.3302 -0.4318)
						)
					)
					(width 0)
					(fill yes)
				)
			)
		)
		(pad "2" smd custom
			(at 0 0.762 270)
			(size 0.2159 0.2159)
			(layers "F.Cu" "F.Mask" "F.Paste")
			(net "GND")
			(options
				(clearance outline)
				(anchor circle)
			)
			(primitives
				(gr_poly
					(pts
						(arc
							(start -0.3302 -0.4318)
							(mid -0.402042 -0.402042)
							(end -0.4318 -0.3302)
						)
						(arc
							(start -0.4318 0.3302)
							(mid -0.402042 0.402042)
							(end -0.3302 0.4318)
						)
						(arc
							(start 0.3302 0.4318)
							(mid 0.402042 0.402042)
							(end 0.4318 0.3302)
						)
						(arc
							(start 0.4318 -0.3302)
							(mid 0.402042 -0.402042)
							(end 0.3302 -0.4318)
						)
					)
					(width 0)
					(fill yes)
				)
			)
		)
	)
	(footprint ""
		(layer "F.Cu")
		(at 34.739834 -139.324334 90)
		(property "Reference" "TP24"
			(at 0 0 90)
			(layer "F.SilkS")
			(hide yes)
			(effects
				(font
					(size 1.27 1.27)
				)
			)
		)
		(property "Value" "TPAD32-GP"
			(at 0 -3.166364 90)
			(unlocked yes)
			(layer "F.Fab")
			(hide yes)
			(effects
				(font
					(size 1.016 1.016)
					(thickness 0.1524)
				)
			)
		)
		(property "Device Type" "TPAD32"
			(at 0 -4.690618 90)
			(unlocked yes)
			(layer "F.Fab")
			(hide yes)
			(effects
				(font
					(size 1.016 1.016)
					(thickness 0.1524)
				)
			)
		)
		(duplicate_pad_numbers_are_jumpers no)
		(fp_poly
			(pts
				(arc
					(start 0 0.7112)
					(mid 0 -0.7112)
					(end 0 0.7112)
				)
			)
			(stroke
				(width 0)
				(type default)
			)
			(fill no)
			(layer "F.CrtYd")
		)
		(fp_poly
			(pts
				(arc
					(start 0 0.7112)
					(mid 0 -0.7112)
					(end 0 0.7112)
				)
			)
			(stroke
				(width 0)
				(type default)
			)
			(fill no)
			(layer "F.Fab")
		)
		(pad "1" smd circle
			(at 0 0 90)
			(size 0.8128 0.8128)
			(layers "F.Cu" "F.Mask" "F.Paste")
			(net "P12VL_2490_PG")
		)
	)
	(footprint ""
		(layer "F.Cu")
		(at 43.8404 -394.1064 90)
		(property "Reference" "TC10"
			(at 0 0 90)
			(layer "F.SilkS")
			(hide yes)
			(effects
				(font
					(size 1.27 1.27)
				)
			)
		)
		(property "Value" "ST68U16VDM-1-GP"
			(at 0 -9.6012 90)
			(unlocked yes)
			(layer "F.Fab")
			(hide yes)
			(effects
				(font
					(size 1.016 1.016)
					(thickness 0.1524)
				)
			)
		)
		(property "Device Type" "CT7343H79"
			(at 0 -11.1252 90)
			(unlocked yes)
			(layer "F.Fab")
			(hide yes)
			(effects
				(font
					(size 1.016 1.016)
					(thickness 0.1524)
				)
			)
		)
		(duplicate_pad_numbers_are_jumpers no)
		(fp_line
			(start 2.286 -4.8768)
			(end -2.286 -4.8768)
			(stroke
				(width 0.1524)
				(type default)
			)
			(layer "F.SilkS")
		)
		(fp_line
			(start -2.286 -4.8768)
			(end -2.286 -2.032)
			(stroke
				(width 0.1524)
				(type default)
			)
			(layer "F.SilkS")
		)
		(fp_line
			(start 2.1082 -4.699)
			(end -2.1082 -4.699)
			(stroke
				(width 0.508)
				(type default)
			)
			(layer "F.SilkS")
		)
		(fp_line
			(start 2.286 -2.032)
			(end 2.286 -4.8768)
			(stroke
				(width 0.1524)
				(type default)
			)
			(layer "F.SilkS")
		)
		(fp_line
			(start 2.286 2.032)
			(end 2.286 4.8768)
			(stroke
				(width 0.1524)
				(type default)
			)
			(layer "F.SilkS")
		)
		(fp_line
			(start 2.286 4.8768)
			(end -2.286 4.8768)
			(stroke
				(width 0.1524)
				(type default)
			)
			(layer "F.SilkS")
		)
		(fp_line
			(start -2.286 4.8768)
			(end -2.286 2.032)
			(stroke
				(width 0.1524)
				(type default)
			)
			(layer "F.SilkS")
		)
		(fp_rect
			(start -2.1463 3.6449)
			(end 2.1463 -3.6449)
			(stroke
				(width 0)
				(type default)
			)
			(fill no)
			(layer "F.CrtYd")
		)
		(fp_poly
			(pts
				(xy -2.54 4.953) (xy -2.54 4.2926) (xy -3.81 4.2926) (xy -3.81 -4.2926) (xy -2.54 -4.2926) (xy -2.54 -4.953)
				(xy 2.54 -4.953) (xy 2.54 -4.2926) (xy 3.81 -4.2926) (xy 3.81 -1.6256) (xy 2.1463 -1.6256) (xy 2.1463 -3.6449)
				(xy -2.1463 -3.6449) (xy -2.1463 3.6449) (xy 2.1463 3.6449) (xy 2.1463 -1.6129) (xy 3.81 -1.6129)
				(xy 3.81 4.2926) (xy 2.54 4.2926) (xy 2.54 4.953)
			)
			(stroke
				(width 0)
				(type default)
			)
			(fill no)
			(layer "F.CrtYd")
		)
		(fp_rect
			(start 2.54 4.2926)
			(end 3.81 -4.2926)
			(stroke
				(width 0)
				(type default)
			)
			(fill no)
			(layer "F.Fab")
		)
		(fp_rect
			(start -3.81 4.2926)
			(end -2.54 -4.2926)
			(stroke
				(width 0)
				(type default)
			)
			(fill no)
			(layer "F.Fab")
		)
		(fp_rect
			(start -2.54 4.953)
			(end 2.54 -4.953)
			(stroke
				(width 0)
				(type default)
			)
			(fill no)
			(layer "F.Fab")
		)
		(pad "1" smd rect
			(at 0 -3.1496 90)
			(size 2.413 2.286)
			(layers "F.Cu" "F.Mask" "F.Paste")
			(net "P12V")
		)
		(pad "2" smd rect
			(at 0 3.1496 90)
			(size 2.413 2.286)
			(layers "F.Cu" "F.Mask" "F.Paste")
			(net "GND")
		)
		(zone
			(layer "F.Cu")
			(hatch none 0.5)
			(connect_pads
				(clearance 0)
			)
			(min_thickness 0.25)
			(keepout
				(tracks allowed)
				(vias not_allowed)
				(pads allowed)
				(copperpour not_allowed)
				(footprints allowed)
			)
			(placement
				(enabled no)
				(sheetname "")
			)
			(fill
				(thermal_gap 0.5)
				(thermal_bridge_width 0.5)
				(island_removal_mode 0)
			)
			(polygon
				(pts
					(xy 42.1513 -395.6177) (xy 39.243 -395.6177) (xy 39.243 -392.5951) (xy 42.1386 -392.5951) (xy 42.4688 -392.5951)
					(xy 42.4688 -395.6177)
				)
			)
		)
		(zone
			(layer "F.Cu")
			(hatch none 0.5)
			(connect_pads
				(clearance 0)
			)
			(min_thickness 0.25)
			(keepout
				(tracks allowed)
				(vias not_allowed)
				(pads allowed)
				(copperpour not_allowed)
				(footprints allowed)
			)
			(placement
				(enabled no)
				(sheetname "")
			)
			(fill
				(thermal_gap 0.5)
				(thermal_bridge_width 0.5)
				(island_removal_mode 0)
			)
			(polygon
				(pts
					(xy 48.4378 -392.5951) (xy 48.4378 -395.6177) (xy 45.5422 -395.6177) (xy 45.212 -395.6177) (xy 45.212 -392.5951)
					(xy 45.5422 -392.5951)
				)
			)
		)
	)
	(footprint ""
		(layer "F.Cu")
		(at 45.466 -179.451)
		(property "Reference" "TP21"
			(at 0 0 0)
			(layer "F.SilkS")
			(hide yes)
			(effects
				(font
					(size 1.27 1.27)
				)
			)
		)
		(property "Value" "TPAD32-GP"
			(at 0 -3.166364 0)
			(unlocked yes)
			(layer "F.Fab")
			(hide yes)
			(effects
				(font
					(size 1.016 1.016)
					(thickness 0.1524)
				)
			)
		)
		(property "Device Type" "TPAD32"
			(at 0 -4.690618 0)
			(unlocked yes)
			(layer "F.Fab")
			(hide yes)
			(effects
				(font
					(size 1.016 1.016)
					(thickness 0.1524)
				)
			)
		)
		(duplicate_pad_numbers_are_jumpers no)
		(fp_poly
			(pts
				(arc
					(start 0.7112 0)
					(mid -0.7112 0)
					(end 0.7112 0)
				)
			)
			(stroke
				(width 0)
				(type default)
			)
			(fill no)
			(layer "F.CrtYd")
		)
		(fp_poly
			(pts
				(arc
					(start 0.7112 0)
					(mid -0.7112 0)
					(end 0.7112 0)
				)
			)
			(stroke
				(width 0)
				(type default)
			)
			(fill no)
			(layer "F.Fab")
		)
		(pad "1" smd circle
			(at 0 0)
			(size 0.8128 0.8128)
			(layers "F.Cu" "F.Mask" "F.Paste")
			(net "D_LATCH_Q#")
		)
	)
	(footprint ""
		(layer "F.Cu")
		(at 10.5664 -447.2686)
		(property "Reference" "D12"
			(at 0 0 0)
			(layer "F.SilkS")
			(hide yes)
			(effects
				(font
					(size 1.27 1.27)
				)
			)
		)
		(property "Value" "BAS16H-GP"
			(at 0 -5.5372 0)
			(unlocked yes)
			(layer "F.Fab")
			(hide yes)
			(effects
				(font
					(size 1.016 1.016)
					(thickness 0.1524)
				)
			)
		)
		(property "Device Type" "SOD123AKH48"
			(at 0 -7.0612 0)
			(unlocked yes)
			(layer "F.Fab")
			(hide yes)
			(effects
				(font
					(size 1.016 1.016)
					(thickness 0.1524)
				)
			)
		)
		(duplicate_pad_numbers_are_jumpers no)
		(fp_line
			(start -1.016 -2.667)
			(end -1.016 2.667)
			(stroke
				(width 0.1524)
				(type default)
			)
			(layer "F.SilkS")
		)
		(fp_line
			(start -1.016 2.667)
			(end 1.016 2.667)
			(stroke
				(width 0.1524)
				(type default)
			)
			(layer "F.SilkS")
		)
		(fp_line
			(start 0.889 2.921)
			(end -0.889 2.921)
			(stroke
				(width 0.508)
				(type default)
			)
			(layer "F.SilkS")
		)
		(fp_line
			(start 1.016 -2.667)
			(end -1.016 -2.667)
			(stroke
				(width 0.1524)
				(type default)
			)
			(layer "F.SilkS")
		)
		(fp_line
			(start 1.016 2.667)
			(end 1.016 -2.667)
			(stroke
				(width 0.1524)
				(type default)
			)
			(layer "F.SilkS")
		)
		(fp_rect
			(start -1.143 3.175)
			(end 1.143 -2.794)
			(stroke
				(width 0)
				(type default)
			)
			(fill no)
			(layer "F.CrtYd")
		)
		(fp_poly
			(pts
				(xy -1.143 -2.794) (xy 1.143 -2.794) (xy 1.143 3.175) (xy -1.143 3.175)
			)
			(stroke
				(width 0)
				(type default)
			)
			(fill no)
			(layer "F.Fab")
		)
		(pad "A" smd rect
			(at 0 -1.6891)
			(size 0.889 1.397)
			(layers "F.Cu" "F.Mask" "F.Paste")
			(net "FAN_TACH2")
		)
		(pad "K" smd rect
			(at 0 1.6891)
			(size 0.889 1.397)
			(layers "F.Cu" "F.Mask" "F.Paste")
			(net "P12V")
		)
	)
	(footprint ""
		(layer "F.Cu")
		(at 14.5034 -248.1834)
		(property "Reference" "PR57"
			(at 0 0 0)
			(layer "F.SilkS")
			(hide yes)
			(effects
				(font
					(size 1.27 1.27)
				)
			)
		)
		(property "Value" "0R0603-PAD-2-GP"
			(at -0.0254 -2.3622 0)
			(unlocked yes)
			(layer "F.Fab")
			(hide yes)
			(effects
				(font
					(size 1.016 1.016)
					(thickness 0.1524)
				)
			)
		)
		(property "Device Type" "0R0603-PAD-1"
			(at -0.0254 -3.8862 0)
			(unlocked yes)
			(layer "F.Fab")
			(hide yes)
			(effects
				(font
					(size 1.016 1.016)
					(thickness 0.1524)
				)
			)
		)
		(duplicate_pad_numbers_are_jumpers no)
		(fp_line
			(start -0.6604 -1.3716)
			(end -0.6604 1.3716)
			(stroke
				(width 0.1524)
				(type default)
			)
			(layer "F.SilkS")
		)
		(fp_line
			(start 0.6604 -1.3716)
			(end -0.6604 -1.3716)
			(stroke
				(width 0.1524)
				(type default)
			)
			(layer "F.SilkS")
		)
		(fp_rect
			(start -0.6604 1.3716)
			(end 0.6604 -1.3716)
			(stroke
				(width 0)
				(type default)
			)
			(fill no)
			(layer "F.CrtYd")
		)
		(fp_rect
			(start -0.6604 1.3716)
			(end 0.6604 -1.3716)
			(stroke
				(width 0)
				(type default)
			)
			(fill no)
			(layer "F.Fab")
		)
		(pad "1" smd custom
			(at 0 -0.8509)
			(size 0.2159 0.2159)
			(layers "F.Cu" "F.Mask" "F.Paste")
			(net "P12V")
			(options
				(clearance outline)
				(anchor circle)
			)
			(primitives
				(gr_poly
					(pts
						(arc
							(start 0.4318 0.4826)
							(mid 0.402042 0.554442)
							(end 0.3302 0.5842)
						)
						(arc
							(start -0.3302 0.5842)
							(mid -0.402042 0.554442)
							(end -0.4318 0.4826)
						)
						(arc
							(start -0.4318 -0.4826)
							(mid -0.402042 -0.554442)
							(end -0.3302 -0.5842)
						)
						(arc
							(start 0.3302 -0.5842)
							(mid 0.402042 -0.554442)
							(end 0.4318 -0.4826)
						)
					)
					(width 0)
					(fill yes)
				)
			)
		)
		(pad "2" smd custom
			(at 0 0.6731)
			(size 0.2159 0.2159)
			(layers "F.Cu" "F.Mask" "F.Paste")
			(net "P3V3_IN")
			(options
				(clearance outline)
				(anchor circle)
			)
			(primitives
				(gr_poly
					(pts
						(arc
							(start -0.3302 0.5842)
							(mid -0.402042 0.554442)
							(end -0.4318 0.4826)
						)
						(arc
							(start -0.4318 -0.4826)
							(mid -0.402042 -0.554442)
							(end -0.3302 -0.5842)
						)
						(arc
							(start 0.3302 -0.5842)
							(mid 0.402042 -0.554442)
							(end 0.4318 -0.4826)
						)
						(arc
							(start 0.4318 0.4826)
							(mid 0.402042 0.554442)
							(end 0.3302 0.5842)
						)
					)
					(width 0)
					(fill yes)
				)
			)
		)
	)
	(footprint ""
		(layer "F.Cu")
		(at 4.040124 -193.339974 -90)
		(property "Reference" "CN4"
			(at 0 0 270)
			(layer "F.SilkS")
			(hide yes)
			(effects
				(font
					(size 1.27 1.27)
				)
			)
		)
		(property "Value" "JWT-CON5-42-GP"
			(at -7.8105 2.9591 270)
			(unlocked yes)
			(layer "F.Fab")
			(hide yes)
			(effects
				(font
					(size 1.016 1.016)
					(thickness 0.1524)
				)
			)
		)
		(property "Device Type" "A2541WR0-1TX5PA-6T-0E"
			(at -7.8105 1.4351 270)
			(unlocked yes)
			(layer "F.Fab")
			(hide yes)
			(effects
				(font
					(size 1.016 1.016)
					(thickness 0.1524)
				)
			)
		)
		(duplicate_pad_numbers_are_jumpers no)
		(fp_line
			(start -6.604 10.287)
			(end 6.604 10.287)
			(stroke
				(width 0.1524)
				(type default)
			)
			(layer "F.SilkS")
		)
		(fp_line
			(start 6.604 10.287)
			(end 6.604 -0.9652)
			(stroke
				(width 0.1524)
				(type default)
			)
			(layer "F.SilkS")
		)
		(fp_line
			(start -6.604 -0.9652)
			(end -6.604 10.287)
			(stroke
				(width 0.1524)
				(type default)
			)
			(layer "F.SilkS")
		)
		(fp_line
			(start 6.604 -0.9652)
			(end -6.604 -0.9652)
			(stroke
				(width 0.1524)
				(type default)
			)
			(layer "F.SilkS")
		)
		(fp_line
			(start -6.731 -1.0922)
			(end -6.731 0.1778)
			(stroke
				(width 0.4064)
				(type default)
			)
			(layer "F.SilkS")
		)
		(fp_line
			(start -5.461 -1.0922)
			(end -6.731 -1.0922)
			(stroke
				(width 0.4064)
				(type default)
			)
			(layer "F.SilkS")
		)
		(fp_circle
			(center -5.08 0)
			(end -5.08 -1.0668)
			(stroke
				(width 0.3048)
				(type default)
			)
			(fill no)
			(layer "F.SilkS")
		)
		(fp_circle
			(center -2.54 0)
			(end -2.54 -1.0668)
			(stroke
				(width 0.3048)
				(type default)
			)
			(fill no)
			(layer "F.SilkS")
		)
		(fp_circle
			(center 0 0)
			(end 0 -1.0668)
			(stroke
				(width 0.3048)
				(type default)
			)
			(fill no)
			(layer "F.SilkS")
		)
		(fp_circle
			(center 2.54 0)
			(end 2.54 -1.0668)
			(stroke
				(width 0.3048)
				(type default)
			)
			(fill no)
			(layer "F.SilkS")
		)
		(fp_circle
			(center 5.08 0)
			(end 5.08 -1.0668)
			(stroke
				(width 0.3048)
				(type default)
			)
			(fill no)
			(layer "F.SilkS")
		)
		(fp_rect
			(start -6.35 10.033)
			(end 6.35 -0.3302)
			(stroke
				(width 0)
				(type default)
			)
			(fill no)
			(layer "F.CrtYd")
		)
		(fp_poly
			(pts
				(xy -6.35 -0.3302) (xy 6.858 -0.3302) (xy 6.858 -1.2192) (xy -6.858 -1.2192) (xy -6.858 10.541)
				(xy 6.858 10.541) (xy 6.858 -0.3175) (xy 6.35 -0.3175) (xy 6.35 10.033) (xy -6.35 10.033)
			)
			(stroke
				(width 0)
				(type default)
			)
			(fill no)
			(layer "F.CrtYd")
		)
		(fp_rect
			(start -6.858 10.541)
			(end 6.858 -1.2192)
			(stroke
				(width 0)
				(type default)
			)
			(fill no)
			(layer "F.Fab")
		)
		(pad "1" thru_hole circle
			(at -5.08 0 270)
			(size 1.4224 1.4224)
			(drill 1.016)
			(layers "*.Cu" "*.Mask")
			(remove_unused_layers no)
			(net "GND")
			(clearance 0.1524)
			(thermal_gap 0.1524)
		)
		(pad "2" thru_hole circle
			(at -2.54 0 270)
			(size 1.4224 1.4224)
			(drill 1.016)
			(layers "*.Cu" "*.Mask")
			(remove_unused_layers no)
			(net "P12V_FAN4")
			(clearance 0.1524)
			(thermal_gap 0.1524)
		)
		(pad "3" thru_hole circle
			(at 0 0 270)
			(size 1.4224 1.4224)
			(drill 1.016)
			(layers "*.Cu" "*.Mask")
			(remove_unused_layers no)
			(net "FAN_TACH8")
			(clearance 0.1524)
			(thermal_gap 0.1524)
		)
		(pad "4" thru_hole circle
			(at 2.54 0 270)
			(size 1.4224 1.4224)
			(drill 1.016)
			(layers "*.Cu" "*.Mask")
			(remove_unused_layers no)
			(net "PWM_OUT_FAN4_NET")
			(clearance 0.1524)
			(thermal_gap 0.1524)
		)
		(pad "5" thru_hole circle
			(at 5.08 0 270)
			(size 1.4224 1.4224)
			(drill 1.016)
			(layers "*.Cu" "*.Mask")
			(remove_unused_layers no)
			(net "FAN_TACH7")
			(clearance 0.1524)
			(thermal_gap 0.1524)
		)
	)
	(footprint ""
		(layer "F.Cu")
		(at 30.36189 -159.849566 180)
		(property "Reference" "U1"
			(at 0 0 180)
			(layer "F.SilkS")
			(hide yes)
			(effects
				(font
					(size 1.27 1.27)
				)
			)
		)
		(property "Value" "NCT7904D-GP"
			(at -4.064 -8.5852 180)
			(unlocked yes)
			(layer "F.Fab")
			(hide yes)
			(effects
				(font
					(size 1.016 1.016)
					(thickness 0.1524)
				)
			)
		)
		(property "Device Type" "LQFP48H63"
			(at -4.064 -10.3632 180)
			(unlocked yes)
			(layer "F.Fab")
			(hide yes)
			(effects
				(font
					(size 1.016 1.016)
					(thickness 0.1524)
				)
			)
		)
		(duplicate_pad_numbers_are_jumpers no)
		(fp_line
			(start 5.5118 5.5118)
			(end 5.5118 3.0226)
			(stroke
				(width 0.1524)
				(type default)
			)
			(layer "F.SilkS")
		)
		(fp_line
			(start 5.5118 -3.0734)
			(end 5.4864 -3.0734)
			(stroke
				(width 0.1524)
				(type default)
			)
			(layer "F.SilkS")
		)
		(fp_line
			(start 5.5118 -5.5118)
			(end 5.5118 -3.0734)
			(stroke
				(width 0.1524)
				(type default)
			)
			(layer "F.SilkS")
		)
		(fp_line
			(start 5.4864 -3.0734)
			(end 3.048 -5.5118)
			(stroke
				(width 0.1524)
				(type default)
			)
			(layer "F.SilkS")
		)
		(fp_line
			(start 5.1562 1.24968)
			(end 5.9182 1.24968)
			(stroke
				(width 0.1524)
				(type default)
			)
			(layer "F.SilkS")
		)
		(fp_line
			(start 5.1562 -1.24968)
			(end 5.6642 -1.24968)
			(stroke
				(width 0.1524)
				(type default)
			)
			(layer "F.SilkS")
		)
		(fp_line
			(start 3.048 -5.5118)
			(end 5.5118 -5.5118)
			(stroke
				(width 0.1524)
				(type default)
			)
			(layer "F.SilkS")
		)
		(fp_line
			(start 2.9718 5.5118)
			(end 5.5118 5.5118)
			(stroke
				(width 0.1524)
				(type default)
			)
			(layer "F.SilkS")
		)
		(fp_line
			(start 2.25044 5.1562)
			(end 2.25044 5.6642)
			(stroke
				(width 0.1524)
				(type default)
			)
			(layer "F.SilkS")
		)
		(fp_line
			(start 0.75057 -5.1562)
			(end 0.75057 -5.6642)
			(stroke
				(width 0.1524)
				(type default)
			)
			(layer "F.SilkS")
		)
		(fp_line
			(start -0.25019 5.1562)
			(end -0.25019 5.9182)
			(stroke
				(width 0.1524)
				(type default)
			)
			(layer "F.SilkS")
		)
		(fp_line
			(start -1.75006 -5.1562)
			(end -1.75006 -5.9182)
			(stroke
				(width 0.1524)
				(type default)
			)
			(layer "F.SilkS")
		)
		(fp_line
			(start -2.74955 5.1562)
			(end -2.74955 5.6642)
			(stroke
				(width 0.1524)
				(type default)
			)
			(layer "F.SilkS")
		)
		(fp_line
			(start -3.0988 -5.5118)
			(end -5.5118 -5.5118)
			(stroke
				(width 0.1524)
				(type default)
			)
			(layer "F.SilkS")
		)
		(fp_line
			(start -5.1562 0.75057)
			(end -5.9182 0.75057)
			(stroke
				(width 0.1524)
				(type default)
			)
			(layer "F.SilkS")
		)
		(fp_line
			(start -5.1562 -1.75006)
			(end -5.6642 -1.75006)
			(stroke
				(width 0.1524)
				(type default)
			)
			(layer "F.SilkS")
		)
		(fp_line
			(start -5.5118 5.5118)
			(end -2.9972 5.5118)
			(stroke
				(width 0.1524)
				(type default)
			)
			(layer "F.SilkS")
		)
		(fp_line
			(start -5.5118 2.9718)
			(end -5.5118 5.5118)
			(stroke
				(width 0.1524)
				(type default)
			)
			(layer "F.SilkS")
		)
		(fp_line
			(start -5.5118 -5.5118)
			(end -5.5118 -2.9464)
			(stroke
				(width 0.1524)
				(type default)
			)
			(layer "F.SilkS")
		)
		(fp_poly
			(pts
				(xy 5.5118 -3.048) (xy 3.048 -5.5118) (xy 5.5118 -5.5118)
			)
			(stroke
				(width 0)
				(type default)
			)
			(fill no)
			(layer "F.SilkS")
		)
		(fp_poly
			(pts
				(xy 3.0734 -5.5118) (xy 5.5118 -5.5118) (xy 5.5118 -3.1496) (xy 5.4356 -3.1496)
			)
			(stroke
				(width 0)
				(type default)
			)
			(fill yes)
			(layer "F.SilkS")
		)
		(fp_rect
			(start -5.5118 5.5118)
			(end 5.5118 -5.5118)
			(stroke
				(width 0)
				(type default)
			)
			(fill no)
			(layer "F.CrtYd")
		)
		(fp_rect
			(start -5.5118 5.5118)
			(end 5.5118 -5.5118)
			(stroke
				(width 0)
				(type default)
			)
			(fill no)
			(layer "F.Fab")
		)
		(pad "1" smd rect
			(at 2.74955 -4.2418 180)
			(size 0.3048 1.524)
			(layers "F.Cu" "F.Mask" "F.Paste")
			(net "NCT7904_VREF")
		)
		(pad "2" smd rect
			(at 2.25044 -4.2418 180)
			(size 0.3048 1.524)
			(layers "F.Cu" "F.Mask" "F.Paste")
			(net "NCT7904_D1+")
		)
		(pad "3" smd rect
			(at 1.75006 -4.2418 180)
			(size 0.3048 1.524)
			(layers "F.Cu" "F.Mask" "F.Paste")
			(net "NCT7904_D1-")
		)
		(pad "4" smd rect
			(at 1.24968 -4.2418 180)
			(size 0.3048 1.524)
			(layers "F.Cu" "F.Mask" "F.Paste")
			(net "NCT7904_D2+")
		)
		(pad "5" smd rect
			(at 0.75057 -4.2418 180)
			(size 0.3048 1.524)
			(layers "F.Cu" "F.Mask" "F.Paste")
			(net "NCT7904_D2-")
		)
		(pad "6" smd rect
			(at 0.25019 -4.2418 180)
			(size 0.3048 1.524)
			(layers "F.Cu" "F.Mask" "F.Paste")
			(net "NCT7904_VSEN6")
		)
		(pad "7" smd rect
			(at -0.25019 -4.2418 180)
			(size 0.3048 1.524)
			(layers "F.Cu" "F.Mask" "F.Paste")
			(net "NCT7904_VSEN7")
		)
		(pad "8" smd rect
			(at -0.75057 -4.2418 180)
			(size 0.3048 1.524)
			(layers "F.Cu" "F.Mask" "F.Paste")
			(net "NCT7904_VSEN8")
		)
		(pad "9" smd rect
			(at -1.24968 -4.2418 180)
			(size 0.3048 1.524)
			(layers "F.Cu" "F.Mask" "F.Paste")
			(net "NCT7904_VSEN9")
		)
		(pad "10" smd rect
			(at -1.75006 -4.2418 180)
			(size 0.3048 1.524)
			(layers "F.Cu" "F.Mask" "F.Paste")
			(net "NCT7904_VSEN10")
		)
		(pad "11" smd rect
			(at -2.25044 -4.2418 180)
			(size 0.3048 1.524)
			(layers "F.Cu" "F.Mask" "F.Paste")
			(net "NCT7904_VSEN11")
		)
		(pad "12" smd rect
			(at -2.74955 -4.2418 180)
			(size 0.3048 1.524)
			(layers "F.Cu" "F.Mask" "F.Paste")
			(net "NCT7904_VSEN12")
		)
		(pad "13" smd rect
			(at -4.2418 -2.74955 180)
			(size 1.524 0.3048)
			(layers "F.Cu" "F.Mask" "F.Paste")
			(net "NCT7904_VSEN13")
		)
		(pad "14" smd rect
			(at -4.2418 -2.25044 180)
			(size 1.524 0.3048)
			(layers "F.Cu" "F.Mask" "F.Paste")
			(net "NCT7904_VSEN14")
		)
		(pad "15" smd rect
			(at -4.2418 -1.75006 180)
			(size 1.524 0.3048)
			(layers "F.Cu" "F.Mask" "F.Paste")
			(net "NCT7904_3VDD")
		)
		(pad "16" smd rect
			(at -4.2418 -1.24968 180)
			(size 1.524 0.3048)
			(layers "F.Cu" "F.Mask" "F.Paste")
			(net "NCT7904_3VSB")
		)
		(pad "17" smd rect
			(at -4.2418 -0.75057 180)
			(size 1.524 0.3048)
			(layers "F.Cu" "F.Mask" "F.Paste")
			(net "NCT7904_SMI")
		)
		(pad "18" smd rect
			(at -4.2418 -0.25019 180)
			(size 1.524 0.3048)
			(layers "F.Cu" "F.Mask" "F.Paste")
			(net "NCT7904_PROCHOT")
		)
		(pad "19" smd rect
			(at -4.2418 0.25019 180)
			(size 1.524 0.3048)
			(layers "F.Cu" "F.Mask" "F.Paste")
			(net "NCT7904_VSEN1")
		)
		(pad "20" smd rect
			(at -4.2418 0.75057 180)
			(size 1.524 0.3048)
			(layers "F.Cu" "F.Mask" "F.Paste")
			(net "NCT7904_PECI")
		)
		(pad "21" smd rect
			(at -4.2418 1.24968 180)
			(size 1.524 0.3048)
			(layers "F.Cu" "F.Mask" "F.Paste")
			(net "NCT7904_THERMTRIP")
		)
		(pad "22" smd rect
			(at -4.2418 1.75006 180)
			(size 1.524 0.3048)
			(layers "F.Cu" "F.Mask" "F.Paste")
			(net "NCT7904_CLKIN")
		)
		(pad "23" smd rect
			(at -4.2418 2.25044 180)
			(size 1.524 0.3048)
			(layers "F.Cu" "F.Mask" "F.Paste")
			(net "I2C_C_SCL_NCT7904")
		)
		(pad "24" smd rect
			(at -4.2418 2.74955 180)
			(size 1.524 0.3048)
			(layers "F.Cu" "F.Mask" "F.Paste")
			(net "I2C_C_SDA_NCT7904")
		)
		(pad "25" smd rect
			(at -2.74955 4.2418 180)
			(size 0.3048 1.524)
			(layers "F.Cu" "F.Mask" "F.Paste")
			(net "FANIN_1")
		)
		(pad "26" smd rect
			(at -2.25044 4.2418 180)
			(size 0.3048 1.524)
			(layers "F.Cu" "F.Mask" "F.Paste")
			(net "FANIN_2")
		)
		(pad "27" smd rect
			(at -1.75006 4.2418 180)
			(size 0.3048 1.524)
			(layers "F.Cu" "F.Mask" "F.Paste")
			(net "NCT7904_ADR")
		)
		(pad "28" smd rect
			(at -1.24968 4.2418 180)
			(size 0.3048 1.524)
			(layers "F.Cu" "F.Mask" "F.Paste")
			(net "NCT7904_RSTOUT")
		)
		(pad "29" smd rect
			(at -0.75057 4.2418 180)
			(size 0.3048 1.524)
			(layers "F.Cu" "F.Mask" "F.Paste")
			(net "FANIN_11")
		)
		(pad "30" smd rect
			(at -0.25019 4.2418 180)
			(size 0.3048 1.524)
			(layers "F.Cu" "F.Mask" "F.Paste")
			(net "NCT7904D_PWM1")
		)
		(pad "31" smd rect
			(at 0.25019 4.2418 180)
			(size 0.3048 1.524)
			(layers "F.Cu" "F.Mask" "F.Paste")
			(net "FANIN_12")
		)
		(pad "32" smd rect
			(at 0.75057 4.2418 180)
			(size 0.3048 1.524)
			(layers "F.Cu" "F.Mask" "F.Paste")
			(net "NCT7904D_PWM2")
		)
		(pad "33" smd rect
			(at 1.24968 4.2418 180)
			(size 0.3048 1.524)
			(layers "F.Cu" "F.Mask" "F.Paste")
			(net "FANIN_9")
		)
		(pad "34" smd rect
			(at 1.75006 4.2418 180)
			(size 0.3048 1.524)
			(layers "F.Cu" "F.Mask" "F.Paste")
			(net "NCT7904D_PWM3")
		)
		(pad "35" smd rect
			(at 2.25044 4.2418 180)
			(size 0.3048 1.524)
			(layers "F.Cu" "F.Mask" "F.Paste")
			(net "FANIN_10")
		)
		(pad "36" smd rect
			(at 2.74955 4.2418 180)
			(size 0.3048 1.524)
			(layers "F.Cu" "F.Mask" "F.Paste")
			(net "NCT7904D_PWM4")
		)
		(pad "37" smd rect
			(at 4.2418 2.74955 180)
			(size 1.524 0.3048)
			(layers "F.Cu" "F.Mask" "F.Paste")
			(net "FANIN_7")
		)
		(pad "38" smd rect
			(at 4.2418 2.25044 180)
			(size 1.524 0.3048)
			(layers "F.Cu" "F.Mask" "F.Paste")
			(net "FANIN_8")
		)
		(pad "39" smd rect
			(at 4.2418 1.75006 180)
			(size 1.524 0.3048)
			(layers "F.Cu" "F.Mask" "F.Paste")
			(net "FANIN_5")
		)
		(pad "40" smd rect
			(at 4.2418 1.24968 180)
			(size 1.524 0.3048)
			(layers "F.Cu" "F.Mask" "F.Paste")
			(net "FANIN_6")
		)
		(pad "41" smd rect
			(at 4.2418 0.75057 180)
			(size 1.524 0.3048)
			(layers "F.Cu" "F.Mask" "F.Paste")
			(net "FANIN_3")
		)
		(pad "42" smd rect
			(at 4.2418 0.25019 180)
			(size 1.524 0.3048)
			(layers "F.Cu" "F.Mask" "F.Paste")
			(net "FANIN_4")
		)
		(pad "43" smd rect
			(at 4.2418 -0.25019 180)
			(size 1.524 0.3048)
			(layers "F.Cu" "F.Mask" "F.Paste")
			(net "NCT7904_GND")
		)
		(pad "44" smd rect
			(at 4.2418 -0.75057 180)
			(size 1.524 0.3048)
			(layers "F.Cu" "F.Mask" "F.Paste")
			(net "NCT7904_TMPALM")
		)
		(pad "45" smd rect
			(at 4.2418 -1.24968 180)
			(size 1.524 0.3048)
			(layers "F.Cu" "F.Mask" "F.Paste")
			(net "NCT7904_LED")
		)
		(pad "46" smd rect
			(at 4.2418 -1.75006 180)
			(size 1.524 0.3048)
			(layers "F.Cu" "F.Mask" "F.Paste")
			(net "NCT7904_RESET")
		)
		(pad "47" smd rect
			(at 4.2418 -2.25044 180)
			(size 1.524 0.3048)
			(layers "F.Cu" "F.Mask" "F.Paste")
			(net "NCT7904_CASEOPEN")
		)
		(pad "48" smd rect
			(at 4.2418 -2.74955 180)
			(size 1.524 0.3048)
			(layers "F.Cu" "F.Mask" "F.Paste")
			(net "NCT7904_3VSB")
		)
	)
	(footprint ""
		(layer "F.Cu")
		(at 33.2232 -248.5644)
		(property "Reference" "C20"
			(at 0 0 0)
			(layer "F.SilkS")
			(hide yes)
			(effects
				(font
					(size 1.27 1.27)
				)
			)
		)
		(property "Value" "SCD1U50V3KX-GP"
			(at 0 -2.8194 0)
			(unlocked yes)
			(layer "F.Fab")
			(hide yes)
			(effects
				(font
					(size 1.016 1.016)
					(thickness 0.1524)
				)
			)
		)
		(property "Device Type" "C603H36"
			(at 0 -4.3434 0)
			(unlocked yes)
			(layer "F.Fab")
			(hide yes)
			(effects
				(font
					(size 1.016 1.016)
					(thickness 0.1524)
				)
			)
		)
		(duplicate_pad_numbers_are_jumpers no)
		(fp_line
			(start 0.508 0)
			(end -0.508 0)
			(stroke
				(width 0.2032)
				(type default)
			)
			(layer "F.SilkS")
		)
		(fp_rect
			(start -0.5842 1.3335)
			(end 0.5842 -1.3335)
			(stroke
				(width 0)
				(type default)
			)
			(fill no)
			(layer "F.CrtYd")
		)
		(fp_rect
			(start -0.5842 1.3335)
			(end 0.5842 -1.3335)
			(stroke
				(width 0)
				(type default)
			)
			(fill no)
			(layer "F.Fab")
		)
		(pad "1" smd custom
			(at 0 -0.762)
			(size 0.2159 0.2159)
			(layers "F.Cu" "F.Mask" "F.Paste")
			(net "P3V3")
			(options
				(clearance outline)
				(anchor circle)
			)
			(primitives
				(gr_poly
					(pts
						(arc
							(start -0.3302 -0.4318)
							(mid -0.402042 -0.402042)
							(end -0.4318 -0.3302)
						)
						(arc
							(start -0.4318 0.3302)
							(mid -0.402042 0.402042)
							(end -0.3302 0.4318)
						)
						(arc
							(start 0.3302 0.4318)
							(mid 0.402042 0.402042)
							(end 0.4318 0.3302)
						)
						(arc
							(start 0.4318 -0.3302)
							(mid 0.402042 -0.402042)
							(end 0.3302 -0.4318)
						)
					)
					(width 0)
					(fill yes)
				)
			)
		)
		(pad "2" smd custom
			(at 0 0.762)
			(size 0.2159 0.2159)
			(layers "F.Cu" "F.Mask" "F.Paste")
			(net "GND")
			(options
				(clearance outline)
				(anchor circle)
			)
			(primitives
				(gr_poly
					(pts
						(arc
							(start -0.3302 -0.4318)
							(mid -0.402042 -0.402042)
							(end -0.4318 -0.3302)
						)
						(arc
							(start -0.4318 0.3302)
							(mid -0.402042 0.402042)
							(end -0.3302 0.4318)
						)
						(arc
							(start 0.3302 0.4318)
							(mid 0.402042 0.402042)
							(end 0.4318 0.3302)
						)
						(arc
							(start 0.4318 -0.3302)
							(mid 0.402042 -0.402042)
							(end 0.3302 -0.4318)
						)
					)
					(width 0)
					(fill yes)
				)
			)
		)
	)
	(footprint ""
		(layer "F.Cu")
		(at 12.2682 -445.516 180)
		(property "Reference" "R97"
			(at 0 0 180)
			(layer "F.SilkS")
			(hide yes)
			(effects
				(font
					(size 1.27 1.27)
				)
			)
		)
		(property "Value" "4K7R2F-GP"
			(at 0.064008 -3.993896 180)
			(unlocked yes)
			(layer "F.Fab")
			(hide yes)
			(effects
				(font
					(size 1.016 1.016)
					(thickness 0.1524)
				)
			)
		)
		(property "Device Type" "R402H16"
			(at 0.064008 -5.517896 180)
			(unlocked yes)
			(layer "F.Fab")
			(hide yes)
			(effects
				(font
					(size 1.016 1.016)
					(thickness 0.1524)
				)
			)
		)
		(duplicate_pad_numbers_are_jumpers no)
		(fp_line
			(start 0.508 -0.9398)
			(end -0.508 -0.9398)
			(stroke
				(width 0.1524)
				(type default)
			)
			(layer "F.SilkS")
		)
		(fp_line
			(start -0.508 -0.9398)
			(end -0.508 0.9398)
			(stroke
				(width 0.1524)
				(type default)
			)
			(layer "F.SilkS")
		)
		(fp_rect
			(start -0.508 0.9398)
			(end 0.508 -0.9398)
			(stroke
				(width 0)
				(type default)
			)
			(fill no)
			(layer "F.CrtYd")
		)
		(fp_rect
			(start -0.508 0.9398)
			(end 0.508 -0.9398)
			(stroke
				(width 0)
				(type default)
			)
			(fill no)
			(layer "F.Fab")
		)
		(pad "1" smd custom
			(at 0 -0.4445 180)
			(size 0.1397 0.1397)
			(layers "F.Cu" "F.Mask" "F.Paste")
			(net "P12V")
			(options
				(clearance outline)
				(anchor circle)
			)
			(primitives
				(gr_poly
					(pts
						(arc
							(start -0.1778 -0.2794)
							(mid -0.249642 -0.249642)
							(end -0.2794 -0.1778)
						)
						(arc
							(start -0.2794 0.1778)
							(mid -0.249642 0.249642)
							(end -0.1778 0.2794)
						)
						(arc
							(start 0.1778 0.2794)
							(mid 0.249642 0.249642)
							(end 0.2794 0.1778)
						)
						(arc
							(start 0.2794 -0.1778)
							(mid 0.249642 -0.249642)
							(end 0.1778 -0.2794)
						)
					)
					(width 0)
					(fill yes)
				)
			)
		)
		(pad "2" smd custom
			(at 0 0.4445 180)
			(size 0.1397 0.1397)
			(layers "F.Cu" "F.Mask" "F.Paste")
			(net "FAN_TACH2")
			(options
				(clearance outline)
				(anchor circle)
			)
			(primitives
				(gr_poly
					(pts
						(arc
							(start -0.1778 -0.2794)
							(mid -0.249642 -0.249642)
							(end -0.2794 -0.1778)
						)
						(arc
							(start -0.2794 0.1778)
							(mid -0.249642 0.249642)
							(end -0.1778 0.2794)
						)
						(arc
							(start 0.1778 0.2794)
							(mid 0.249642 0.249642)
							(end 0.2794 0.1778)
						)
						(arc
							(start 0.2794 -0.1778)
							(mid 0.249642 -0.249642)
							(end 0.1778 -0.2794)
						)
					)
					(width 0)
					(fill yes)
				)
			)
		)
	)
	(footprint ""
		(layer "F.Cu")
		(at 23.876 -243.84 180)
		(property "Reference" "PR54"
			(at 0 0 180)
			(layer "F.SilkS")
			(hide yes)
			(effects
				(font
					(size 1.27 1.27)
				)
			)
		)
		(property "Value" "0R3J-0-U-GP"
			(at -0.0254 -2.5146 180)
			(unlocked yes)
			(layer "F.Fab")
			(hide yes)
			(effects
				(font
					(size 1.016 1.016)
					(thickness 0.1524)
				)
			)
		)
		(property "Device Type" "R603H22"
			(at -0.0254 -4.0386 180)
			(unlocked yes)
			(layer "F.Fab")
			(hide yes)
			(effects
				(font
					(size 1.016 1.016)
					(thickness 0.1524)
				)
			)
		)
		(duplicate_pad_numbers_are_jumpers no)
		(fp_line
			(start 0.2032 0)
			(end 0.4826 0)
			(stroke
				(width 0.2032)
				(type default)
			)
			(layer "F.SilkS")
		)
		(fp_line
			(start -0.4826 0)
			(end -0.2032 0)
			(stroke
				(width 0.2032)
				(type default)
			)
			(layer "F.SilkS")
		)
		(fp_rect
			(start -0.5842 1.3335)
			(end 0.5842 -1.3335)
			(stroke
				(width 0)
				(type default)
			)
			(fill no)
			(layer "F.CrtYd")
		)
		(fp_rect
			(start -0.5842 1.3335)
			(end 0.5842 -1.3335)
			(stroke
				(width 0)
				(type default)
			)
			(fill no)
			(layer "F.Fab")
		)
		(pad "1" smd custom
			(at 0 -0.762 180)
			(size 0.2159 0.2159)
			(layers "F.Cu" "F.Mask" "F.Paste")
			(net "P3V3_LX_COPPER")
			(options
				(clearance outline)
				(anchor circle)
			)
			(primitives
				(gr_poly
					(pts
						(arc
							(start -0.3302 -0.4318)
							(mid -0.402042 -0.402042)
							(end -0.4318 -0.3302)
						)
						(arc
							(start -0.4318 0.3302)
							(mid -0.402042 0.402042)
							(end -0.3302 0.4318)
						)
						(arc
							(start 0.3302 0.4318)
							(mid 0.402042 0.402042)
							(end 0.4318 0.3302)
						)
						(arc
							(start 0.4318 -0.3302)
							(mid 0.402042 -0.402042)
							(end 0.3302 -0.4318)
						)
					)
					(width 0)
					(fill yes)
				)
			)
		)
		(pad "2" smd custom
			(at 0 0.762 180)
			(size 0.2159 0.2159)
			(layers "F.Cu" "F.Mask" "F.Paste")
			(net "P3V3_LX_REV")
			(options
				(clearance outline)
				(anchor circle)
			)
			(primitives
				(gr_poly
					(pts
						(arc
							(start -0.3302 -0.4318)
							(mid -0.402042 -0.402042)
							(end -0.4318 -0.3302)
						)
						(arc
							(start -0.4318 0.3302)
							(mid -0.402042 0.402042)
							(end -0.3302 0.4318)
						)
						(arc
							(start 0.3302 0.4318)
							(mid 0.402042 0.402042)
							(end 0.4318 0.3302)
						)
						(arc
							(start 0.4318 -0.3302)
							(mid 0.402042 -0.402042)
							(end 0.3302 -0.4318)
						)
					)
					(width 0)
					(fill yes)
				)
			)
		)
	)
	(footprint ""
		(layer "F.Cu")
		(at 38.354 -378.333 180)
		(property "Reference" "PR28"
			(at 0 0 180)
			(layer "F.SilkS")
			(hide yes)
			(effects
				(font
					(size 1.27 1.27)
				)
			)
		)
		(property "Value" "10R2F-L-GP"
			(at 0.064008 -3.993896 180)
			(unlocked yes)
			(layer "F.Fab")
			(hide yes)
			(effects
				(font
					(size 1.016 1.016)
					(thickness 0.1524)
				)
			)
		)
		(property "Device Type" "R402H14"
			(at 0.064008 -5.517896 180)
			(unlocked yes)
			(layer "F.Fab")
			(hide yes)
			(effects
				(font
					(size 1.016 1.016)
					(thickness 0.1524)
				)
			)
		)
		(duplicate_pad_numbers_are_jumpers no)
		(fp_line
			(start 0.508 -0.9398)
			(end -0.508 -0.9398)
			(stroke
				(width 0.1524)
				(type default)
			)
			(layer "F.SilkS")
		)
		(fp_line
			(start -0.508 -0.9398)
			(end -0.508 0.9398)
			(stroke
				(width 0.1524)
				(type default)
			)
			(layer "F.SilkS")
		)
		(fp_rect
			(start -0.508 0.9398)
			(end 0.508 -0.9398)
			(stroke
				(width 0)
				(type default)
			)
			(fill no)
			(layer "F.CrtYd")
		)
		(fp_rect
			(start -0.508 0.9398)
			(end 0.508 -0.9398)
			(stroke
				(width 0)
				(type default)
			)
			(fill no)
			(layer "F.Fab")
		)
		(pad "1" smd custom
			(at 0 -0.4445 180)
			(size 0.1397 0.1397)
			(layers "F.Cu" "F.Mask" "F.Paste")
			(net "ADM1276_GATE")
			(options
				(clearance outline)
				(anchor circle)
			)
			(primitives
				(gr_poly
					(pts
						(arc
							(start -0.1778 -0.2794)
							(mid -0.249642 -0.249642)
							(end -0.2794 -0.1778)
						)
						(arc
							(start -0.2794 0.1778)
							(mid -0.249642 0.249642)
							(end -0.1778 0.2794)
						)
						(arc
							(start 0.1778 0.2794)
							(mid 0.249642 0.249642)
							(end 0.2794 0.1778)
						)
						(arc
							(start 0.2794 -0.1778)
							(mid 0.249642 -0.249642)
							(end 0.1778 -0.2794)
						)
					)
					(width 0)
					(fill yes)
				)
			)
		)
		(pad "2" smd custom
			(at 0 0.4445 180)
			(size 0.1397 0.1397)
			(layers "F.Cu" "F.Mask" "F.Paste")
			(net "ADM1276_GATE_DRV3")
			(options
				(clearance outline)
				(anchor circle)
			)
			(primitives
				(gr_poly
					(pts
						(arc
							(start -0.1778 -0.2794)
							(mid -0.249642 -0.249642)
							(end -0.2794 -0.1778)
						)
						(arc
							(start -0.2794 0.1778)
							(mid -0.249642 0.249642)
							(end -0.1778 0.2794)
						)
						(arc
							(start 0.1778 0.2794)
							(mid 0.249642 0.249642)
							(end 0.2794 0.1778)
						)
						(arc
							(start 0.2794 -0.1778)
							(mid 0.249642 -0.249642)
							(end 0.1778 -0.2794)
						)
					)
					(width 0)
					(fill yes)
				)
			)
		)
	)
	(footprint ""
		(layer "F.Cu")
		(at 32.749998 -451.820026)
		(property "Reference" "CN8"
			(at 0 0 0)
			(layer "F.SilkS")
			(hide yes)
			(effects
				(font
					(size 1.27 1.27)
				)
			)
		)
		(property "Value" "JWT-CON3-S11-GP"
			(at 5.715 1.1684 0)
			(unlocked yes)
			(layer "F.Fab")
			(hide yes)
			(effects
				(font
					(size 1.016 1.016)
					(thickness 0.1524)
				)
			)
		)
		(property "Device Type" "A2541WV0-1QX3PA-6T"
			(at 5.715 -0.3556 0)
			(unlocked yes)
			(layer "F.Fab")
			(hide yes)
			(effects
				(font
					(size 1.016 1.016)
					(thickness 0.1524)
				)
			)
		)
		(duplicate_pad_numbers_are_jumpers no)
		(fp_line
			(start -4.190746 -1.651)
			(end -2.920746 -1.651)
			(stroke
				(width 0.4064)
				(type default)
			)
			(layer "F.SilkS")
		)
		(fp_line
			(start -4.190746 -0.381)
			(end -4.190746 -1.651)
			(stroke
				(width 0.4064)
				(type default)
			)
			(layer "F.SilkS")
		)
		(fp_line
			(start -4.064 -1.524)
			(end -4.064 1.524)
			(stroke
				(width 0.1524)
				(type default)
			)
			(layer "F.SilkS")
		)
		(fp_line
			(start -4.064 1.524)
			(end 4.064 1.524)
			(stroke
				(width 0.1524)
				(type default)
			)
			(layer "F.SilkS")
		)
		(fp_line
			(start 4.064 -1.524)
			(end -4.064 -1.524)
			(stroke
				(width 0.1524)
				(type default)
			)
			(layer "F.SilkS")
		)
		(fp_line
			(start 4.064 1.524)
			(end 4.064 -1.524)
			(stroke
				(width 0.1524)
				(type default)
			)
			(layer "F.SilkS")
		)
		(fp_circle
			(center -2.54 0)
			(end -1.4732 0)
			(stroke
				(width 0.3048)
				(type default)
			)
			(fill no)
			(layer "F.SilkS")
		)
		(fp_circle
			(center 0 0)
			(end 1.0668 0)
			(stroke
				(width 0.3048)
				(type default)
			)
			(fill no)
			(layer "F.SilkS")
		)
		(fp_circle
			(center 2.54 0)
			(end 3.6068 0)
			(stroke
				(width 0.3048)
				(type default)
			)
			(fill no)
			(layer "F.SilkS")
		)
		(fp_rect
			(start -3.81 1.27)
			(end 3.81 -1.27)
			(stroke
				(width 0)
				(type default)
			)
			(fill no)
			(layer "F.CrtYd")
		)
		(fp_poly
			(pts
				(xy -4.318 1.778) (xy -4.318 -1.778) (xy 4.318 -1.778) (xy 4.318 -1.27) (xy -3.81 -1.27) (xy -3.81 1.27)
				(xy 3.81 1.27) (xy 3.81 -1.2573) (xy 4.318 -1.2573) (xy 4.318 1.778)
			)
			(stroke
				(width 0)
				(type default)
			)
			(fill no)
			(layer "F.CrtYd")
		)
		(fp_rect
			(start -4.318 1.778)
			(end 4.318 -1.778)
			(stroke
				(width 0)
				(type default)
			)
			(fill no)
			(layer "F.Fab")
		)
		(pad "1" thru_hole circle
			(at -2.54 0)
			(size 1.4224 1.4224)
			(drill 1.016)
			(layers "*.Cu" "*.Mask")
			(remove_unused_layers no)
			(net "Net_3")
			(clearance 0.1524)
			(thermal_gap 0.1524)
		)
		(pad "2" thru_hole circle
			(at 0 0)
			(size 1.4224 1.4224)
			(drill 1.016)
			(layers "*.Cu" "*.Mask")
			(remove_unused_layers no)
			(net "Net_2")
			(clearance 0.1524)
			(thermal_gap 0.1524)
		)
		(pad "3" thru_hole circle
			(at 2.54 0)
			(size 1.4224 1.4224)
			(drill 1.016)
			(layers "*.Cu" "*.Mask")
			(remove_unused_layers no)
			(net "Net_1")
			(clearance 0.1524)
			(thermal_gap 0.1524)
		)
	)
	(footprint ""
		(layer "F.Cu")
		(at 34.3916 -184.4802)
		(property "Reference" "PQ10"
			(at 0 0 0)
			(layer "F.SilkS")
			(hide yes)
			(effects
				(font
					(size 1.27 1.27)
				)
			)
		)
		(property "Value" "PMBS3904-1-GP"
			(at 0 -9.0932 0)
			(unlocked yes)
			(layer "F.Fab")
			(hide yes)
			(effects
				(font
					(size 1.016 1.016)
					(thickness 0.1524)
				)
			)
		)
		(property "Device Type" "SOT-23-10H44"
			(at 0 -10.6172 0)
			(unlocked yes)
			(layer "F.Fab")
			(hide yes)
			(effects
				(font
					(size 1.016 1.016)
					(thickness 0.1524)
				)
			)
		)
		(duplicate_pad_numbers_are_jumpers no)
		(fp_line
			(start -1.7526 1.8796)
			(end -1.7526 0.9906)
			(stroke
				(width 0.3302)
				(type default)
			)
			(layer "F.SilkS")
		)
		(fp_line
			(start -1.651 -1.778)
			(end -1.651 1.778)
			(stroke
				(width 0.1524)
				(type default)
			)
			(layer "F.SilkS")
		)
		(fp_line
			(start -1.651 1.778)
			(end 1.651 1.778)
			(stroke
				(width 0.1524)
				(type default)
			)
			(layer "F.SilkS")
		)
		(fp_line
			(start -1.279398 2.152142)
			(end -0.9906 1.86309)
			(stroke
				(width 0.0127)
				(type default)
			)
			(layer "F.SilkS")
		)
		(fp_line
			(start -1.279144 2.15265)
			(end -0.701294 2.15265)
			(stroke
				(width 0.0127)
				(type default)
			)
			(layer "F.SilkS")
		)
		(fp_line
			(start -1.260856 2.1336)
			(end -0.720344 2.1336)
			(stroke
				(width 0.0127)
				(type default)
			)
			(layer "F.SilkS")
		)
		(fp_line
			(start -1.251458 2.124202)
			(end -0.729996 2.124202)
			(stroke
				(width 0.0127)
				(type default)
			)
			(layer "F.SilkS")
		)
		(fp_line
			(start -1.241806 2.11455)
			(end -0.739394 2.11455)
			(stroke
				(width 0.0127)
				(type default)
			)
			(layer "F.SilkS")
		)
		(fp_line
			(start -1.232408 2.105152)
			(end -0.749046 2.105152)
			(stroke
				(width 0.0127)
				(type default)
			)
			(layer "F.SilkS")
		)
		(fp_line
			(start -1.222756 2.0955)
			(end -0.758444 2.0955)
			(stroke
				(width 0.0127)
				(type default)
			)
			(layer "F.SilkS")
		)
		(fp_line
			(start -1.213358 2.086102)
			(end -0.768096 2.086102)
			(stroke
				(width 0.0127)
				(type default)
			)
			(layer "F.SilkS")
		)
		(fp_line
			(start -1.203706 2.07645)
			(end -0.777494 2.07645)
			(stroke
				(width 0.0127)
				(type default)
			)
			(layer "F.SilkS")
		)
		(fp_line
			(start -1.194308 2.067052)
			(end -0.787146 2.067052)
			(stroke
				(width 0.0127)
				(type default)
			)
			(layer "F.SilkS")
		)
		(fp_line
			(start -1.184656 2.0574)
			(end -0.796544 2.0574)
			(stroke
				(width 0.0127)
				(type default)
			)
			(layer "F.SilkS")
		)
		(fp_line
			(start -1.175258 2.048002)
			(end -0.806196 2.048002)
			(stroke
				(width 0.0127)
				(type default)
			)
			(layer "F.SilkS")
		)
		(fp_line
			(start -1.165606 2.03835)
			(end -0.815594 2.03835)
			(stroke
				(width 0.0127)
				(type default)
			)
			(layer "F.SilkS")
		)
		(fp_line
			(start -1.156208 2.028952)
			(end -0.825246 2.028952)
			(stroke
				(width 0.0127)
				(type default)
			)
			(layer "F.SilkS")
		)
		(fp_line
			(start -1.146556 2.0193)
			(end -0.834644 2.0193)
			(stroke
				(width 0.0127)
				(type default)
			)
			(layer "F.SilkS")
		)
		(fp_line
			(start -1.137158 2.009902)
			(end -0.844296 2.009902)
			(stroke
				(width 0.0127)
				(type default)
			)
			(layer "F.SilkS")
		)
		(fp_line
			(start -1.127506 2.00025)
			(end -0.853694 2.00025)
			(stroke
				(width 0.0127)
				(type default)
			)
			(layer "F.SilkS")
		)
		(fp_line
			(start -1.118108 1.990852)
			(end -0.863346 1.990852)
			(stroke
				(width 0.0127)
				(type default)
			)
			(layer "F.SilkS")
		)
		(fp_line
			(start -1.108456 1.9812)
			(end -0.872744 1.9812)
			(stroke
				(width 0.0127)
				(type default)
			)
			(layer "F.SilkS")
		)
		(fp_line
			(start -1.099058 1.971802)
			(end -0.882396 1.971802)
			(stroke
				(width 0.0127)
				(type default)
			)
			(layer "F.SilkS")
		)
		(fp_line
			(start -1.089406 1.96215)
			(end -0.891794 1.96215)
			(stroke
				(width 0.0127)
				(type default)
			)
			(layer "F.SilkS")
		)
		(fp_line
			(start -1.080008 1.952752)
			(end -0.901446 1.952752)
			(stroke
				(width 0.0127)
				(type default)
			)
			(layer "F.SilkS")
		)
		(fp_line
			(start -1.070356 1.9431)
			(end -0.910844 1.9431)
			(stroke
				(width 0.0127)
				(type default)
			)
			(layer "F.SilkS")
		)
		(fp_line
			(start -1.060958 1.933702)
			(end -0.920496 1.933702)
			(stroke
				(width 0.0127)
				(type default)
			)
			(layer "F.SilkS")
		)
		(fp_line
			(start -1.051306 1.92405)
			(end -0.929894 1.92405)
			(stroke
				(width 0.0127)
				(type default)
			)
			(layer "F.SilkS")
		)
		(fp_line
			(start -1.041908 1.914652)
			(end -0.939546 1.914652)
			(stroke
				(width 0.0127)
				(type default)
			)
			(layer "F.SilkS")
		)
		(fp_line
			(start -1.032256 1.905)
			(end -0.948944 1.905)
			(stroke
				(width 0.0127)
				(type default)
			)
			(layer "F.SilkS")
		)
		(fp_line
			(start -1.022858 1.895602)
			(end -0.958596 1.895602)
			(stroke
				(width 0.0127)
				(type default)
			)
			(layer "F.SilkS")
		)
		(fp_line
			(start -1.013206 1.88595)
			(end -0.967994 1.88595)
			(stroke
				(width 0.0127)
				(type default)
			)
			(layer "F.SilkS")
		)
		(fp_line
			(start -1.003808 1.876552)
			(end -0.977646 1.876552)
			(stroke
				(width 0.0127)
				(type default)
			)
			(layer "F.SilkS")
		)
		(fp_line
			(start -0.994156 1.8669)
			(end -0.987044 1.8669)
			(stroke
				(width 0.0127)
				(type default)
			)
			(layer "F.SilkS")
		)
		(fp_line
			(start -0.9906 1.86309)
			(end -0.701294 2.15265)
			(stroke
				(width 0.0127)
				(type default)
			)
			(layer "F.SilkS")
		)
		(fp_line
			(start -0.719074 2.145538)
			(end -1.265936 2.14122)
			(stroke
				(width 0.0127)
				(type default)
			)
			(layer "F.SilkS")
		)
		(fp_line
			(start -0.71628 2.15265)
			(end -1.26492 2.15265)
			(stroke
				(width 0.0127)
				(type default)
			)
			(layer "F.SilkS")
		)
		(fp_line
			(start -0.635 1.8796)
			(end -1.7526 1.8796)
			(stroke
				(width 0.3302)
				(type default)
			)
			(layer "F.SilkS")
		)
		(fp_line
			(start 1.651 -1.778)
			(end -1.651 -1.778)
			(stroke
				(width 0.1524)
				(type default)
			)
			(layer "F.SilkS")
		)
		(fp_line
			(start 1.651 1.778)
			(end 1.651 -1.778)
			(stroke
				(width 0.1524)
				(type default)
			)
			(layer "F.SilkS")
		)
		(fp_poly
			(pts
				(xy -1.285748 2.159) (xy -1.285748 1.8796) (xy -1.778 1.8796) (xy -1.778 -1.8796) (xy 1.778 -1.8796)
				(xy 1.778 1.8796) (xy -0.694944 1.8796) (xy -0.694944 2.159)
			)
			(stroke
				(width 0)
				(type default)
			)
			(fill no)
			(layer "F.CrtYd")
		)
		(fp_poly
			(pts
				(xy -1.285748 2.159) (xy -1.285748 1.8796) (xy -1.778 1.8796) (xy -1.778 -1.8796) (xy 1.778 -1.8796)
				(xy 1.778 1.8796) (xy -0.694944 1.8796) (xy -0.694944 2.159)
			)
			(stroke
				(width 0)
				(type default)
			)
			(fill no)
			(layer "F.Fab")
		)
		(pad "1" smd rect
			(at -0.98425 0.9525)
			(size 0.762 1.143)
			(layers "F.Cu" "F.Mask" "F.Paste")
			(net "P3V3_AUX_BJT_B")
		)
		(pad "2" smd rect
			(at 0.98425 0.9525)
			(size 0.762 1.143)
			(layers "F.Cu" "F.Mask" "F.Paste")
			(net "P3V3_AUX")
		)
		(pad "3" smd rect
			(at 0 -0.9525)
			(size 0.762 1.143)
			(layers "F.Cu" "F.Mask" "F.Paste")
			(net "P12V_AUX")
		)
	)
	(footprint ""
		(layer "F.Cu")
		(at 32.7406 -149.071584 180)
		(property "Reference" "R36"
			(at 0 0 180)
			(layer "F.SilkS")
			(hide yes)
			(effects
				(font
					(size 1.27 1.27)
				)
			)
		)
		(property "Value" "110KR2F-L-GP"
			(at 0.064008 -3.993896 180)
			(unlocked yes)
			(layer "F.Fab")
			(hide yes)
			(effects
				(font
					(size 1.016 1.016)
					(thickness 0.1524)
				)
			)
		)
		(property "Device Type" "R402H16"
			(at 0.064008 -5.517896 180)
			(unlocked yes)
			(layer "F.Fab")
			(hide yes)
			(effects
				(font
					(size 1.016 1.016)
					(thickness 0.1524)
				)
			)
		)
		(duplicate_pad_numbers_are_jumpers no)
		(fp_line
			(start 0.508 -0.9398)
			(end -0.508 -0.9398)
			(stroke
				(width 0.1524)
				(type default)
			)
			(layer "F.SilkS")
		)
		(fp_line
			(start -0.508 -0.9398)
			(end -0.508 0.9398)
			(stroke
				(width 0.1524)
				(type default)
			)
			(layer "F.SilkS")
		)
		(fp_rect
			(start -0.508 0.9398)
			(end 0.508 -0.9398)
			(stroke
				(width 0)
				(type default)
			)
			(fill no)
			(layer "F.CrtYd")
		)
		(fp_rect
			(start -0.508 0.9398)
			(end 0.508 -0.9398)
			(stroke
				(width 0)
				(type default)
			)
			(fill no)
			(layer "F.Fab")
		)
		(pad "1" smd custom
			(at 0 -0.4445 180)
			(size 0.1397 0.1397)
			(layers "F.Cu" "F.Mask" "F.Paste")
			(net "P12VU")
			(options
				(clearance outline)
				(anchor circle)
			)
			(primitives
				(gr_poly
					(pts
						(arc
							(start -0.1778 -0.2794)
							(mid -0.249642 -0.249642)
							(end -0.2794 -0.1778)
						)
						(arc
							(start -0.2794 0.1778)
							(mid -0.249642 0.249642)
							(end -0.1778 0.2794)
						)
						(arc
							(start 0.1778 0.2794)
							(mid 0.249642 0.249642)
							(end 0.2794 0.1778)
						)
						(arc
							(start 0.2794 -0.1778)
							(mid 0.249642 -0.249642)
							(end 0.1778 -0.2794)
						)
					)
					(width 0)
					(fill yes)
				)
			)
		)
		(pad "2" smd custom
			(at 0 0.4445 180)
			(size 0.1397 0.1397)
			(layers "F.Cu" "F.Mask" "F.Paste")
			(net "NCT7904_VSEN7")
			(options
				(clearance outline)
				(anchor circle)
			)
			(primitives
				(gr_poly
					(pts
						(arc
							(start -0.1778 -0.2794)
							(mid -0.249642 -0.249642)
							(end -0.2794 -0.1778)
						)
						(arc
							(start -0.2794 0.1778)
							(mid -0.249642 0.249642)
							(end -0.1778 0.2794)
						)
						(arc
							(start 0.1778 0.2794)
							(mid 0.249642 0.249642)
							(end 0.2794 0.1778)
						)
						(arc
							(start 0.2794 -0.1778)
							(mid 0.249642 -0.249642)
							(end 0.1778 -0.2794)
						)
					)
					(width 0)
					(fill yes)
				)
			)
		)
	)
	(footprint ""
		(layer "F.Cu")
		(at 36.7284 -478.4598 90)
		(property "Reference" "C49"
			(at 0 0 90)
			(layer "F.SilkS")
			(hide yes)
			(effects
				(font
					(size 1.27 1.27)
				)
			)
		)
		(property "Value" "SCD1U50V3KX-GP"
			(at 0 -2.8194 90)
			(unlocked yes)
			(layer "F.Fab")
			(hide yes)
			(effects
				(font
					(size 1.016 1.016)
					(thickness 0.1524)
				)
			)
		)
		(property "Device Type" "C603H36"
			(at 0 -4.3434 90)
			(unlocked yes)
			(layer "F.Fab")
			(hide yes)
			(effects
				(font
					(size 1.016 1.016)
					(thickness 0.1524)
				)
			)
		)
		(duplicate_pad_numbers_are_jumpers no)
		(fp_line
			(start 0.508 0)
			(end -0.508 0)
			(stroke
				(width 0.2032)
				(type default)
			)
			(layer "F.SilkS")
		)
		(fp_rect
			(start -0.5842 1.3335)
			(end 0.5842 -1.3335)
			(stroke
				(width 0)
				(type default)
			)
			(fill no)
			(layer "F.CrtYd")
		)
		(fp_rect
			(start -0.5842 1.3335)
			(end 0.5842 -1.3335)
			(stroke
				(width 0)
				(type default)
			)
			(fill no)
			(layer "F.Fab")
		)
		(pad "1" smd custom
			(at 0 -0.762 90)
			(size 0.2159 0.2159)
			(layers "F.Cu" "F.Mask" "F.Paste")
			(net "P12V")
			(options
				(clearance outline)
				(anchor circle)
			)
			(primitives
				(gr_poly
					(pts
						(arc
							(start -0.3302 -0.4318)
							(mid -0.402042 -0.402042)
							(end -0.4318 -0.3302)
						)
						(arc
							(start -0.4318 0.3302)
							(mid -0.402042 0.402042)
							(end -0.3302 0.4318)
						)
						(arc
							(start 0.3302 0.4318)
							(mid 0.402042 0.402042)
							(end 0.4318 0.3302)
						)
						(arc
							(start 0.4318 -0.3302)
							(mid 0.402042 -0.402042)
							(end 0.3302 -0.4318)
						)
					)
					(width 0)
					(fill yes)
				)
			)
		)
		(pad "2" smd custom
			(at 0 0.762 90)
			(size 0.2159 0.2159)
			(layers "F.Cu" "F.Mask" "F.Paste")
			(net "GND")
			(options
				(clearance outline)
				(anchor circle)
			)
			(primitives
				(gr_poly
					(pts
						(arc
							(start -0.3302 -0.4318)
							(mid -0.402042 -0.402042)
							(end -0.4318 -0.3302)
						)
						(arc
							(start -0.4318 0.3302)
							(mid -0.402042 0.402042)
							(end -0.3302 0.4318)
						)
						(arc
							(start 0.3302 0.4318)
							(mid 0.402042 0.402042)
							(end 0.4318 0.3302)
						)
						(arc
							(start 0.4318 -0.3302)
							(mid 0.402042 -0.402042)
							(end 0.3302 -0.4318)
						)
					)
					(width 0)
					(fill yes)
				)
			)
		)
	)
	(footprint ""
		(layer "F.Cu")
		(at 13.2588 -61.3918)
		(property "Reference" "C31"
			(at 0 0 0)
			(layer "F.SilkS")
			(hide yes)
			(effects
				(font
					(size 1.27 1.27)
				)
			)
		)
		(property "Value" "SCD1U50V3KX-GP"
			(at 0 -2.8194 0)
			(unlocked yes)
			(layer "F.Fab")
			(hide yes)
			(effects
				(font
					(size 1.016 1.016)
					(thickness 0.1524)
				)
			)
		)
		(property "Device Type" "C603H36"
			(at 0 -4.3434 0)
			(unlocked yes)
			(layer "F.Fab")
			(hide yes)
			(effects
				(font
					(size 1.016 1.016)
					(thickness 0.1524)
				)
			)
		)
		(duplicate_pad_numbers_are_jumpers no)
		(fp_line
			(start 0.508 0)
			(end -0.508 0)
			(stroke
				(width 0.2032)
				(type default)
			)
			(layer "F.SilkS")
		)
		(fp_rect
			(start -0.5842 1.3335)
			(end 0.5842 -1.3335)
			(stroke
				(width 0)
				(type default)
			)
			(fill no)
			(layer "F.CrtYd")
		)
		(fp_rect
			(start -0.5842 1.3335)
			(end 0.5842 -1.3335)
			(stroke
				(width 0)
				(type default)
			)
			(fill no)
			(layer "F.Fab")
		)
		(pad "1" smd custom
			(at 0 -0.762)
			(size 0.2159 0.2159)
			(layers "F.Cu" "F.Mask" "F.Paste")
			(net "P12V")
			(options
				(clearance outline)
				(anchor circle)
			)
			(primitives
				(gr_poly
					(pts
						(arc
							(start -0.3302 -0.4318)
							(mid -0.402042 -0.402042)
							(end -0.4318 -0.3302)
						)
						(arc
							(start -0.4318 0.3302)
							(mid -0.402042 0.402042)
							(end -0.3302 0.4318)
						)
						(arc
							(start 0.3302 0.4318)
							(mid 0.402042 0.402042)
							(end 0.4318 0.3302)
						)
						(arc
							(start 0.4318 -0.3302)
							(mid 0.402042 -0.402042)
							(end 0.3302 -0.4318)
						)
					)
					(width 0)
					(fill yes)
				)
			)
		)
		(pad "2" smd custom
			(at 0 0.762)
			(size 0.2159 0.2159)
			(layers "F.Cu" "F.Mask" "F.Paste")
			(net "GND")
			(options
				(clearance outline)
				(anchor circle)
			)
			(primitives
				(gr_poly
					(pts
						(arc
							(start -0.3302 -0.4318)
							(mid -0.402042 -0.402042)
							(end -0.4318 -0.3302)
						)
						(arc
							(start -0.4318 0.3302)
							(mid -0.402042 0.402042)
							(end -0.3302 0.4318)
						)
						(arc
							(start 0.3302 0.4318)
							(mid 0.402042 0.402042)
							(end 0.4318 0.3302)
						)
						(arc
							(start 0.4318 -0.3302)
							(mid 0.402042 -0.402042)
							(end 0.3302 -0.4318)
						)
					)
					(width 0)
					(fill yes)
				)
			)
		)
	)
	(footprint ""
		(layer "F.Cu")
		(at 43.2308 -158.8516)
		(property "Reference" "R51"
			(at 0 0 0)
			(layer "F.SilkS")
			(hide yes)
			(effects
				(font
					(size 1.27 1.27)
				)
			)
		)
		(property "Value" "0R2J-2-GP"
			(at 0.064008 -3.993896 0)
			(unlocked yes)
			(layer "F.Fab")
			(hide yes)
			(effects
				(font
					(size 1.016 1.016)
					(thickness 0.1524)
				)
			)
		)
		(property "Device Type" "R402H16"
			(at 0.064008 -5.517896 0)
			(unlocked yes)
			(layer "F.Fab")
			(hide yes)
			(effects
				(font
					(size 1.016 1.016)
					(thickness 0.1524)
				)
			)
		)
		(duplicate_pad_numbers_are_jumpers no)
		(fp_line
			(start -0.508 -0.9398)
			(end -0.508 0.9398)
			(stroke
				(width 0.1524)
				(type default)
			)
			(layer "F.SilkS")
		)
		(fp_line
			(start 0.508 -0.9398)
			(end -0.508 -0.9398)
			(stroke
				(width 0.1524)
				(type default)
			)
			(layer "F.SilkS")
		)
		(fp_rect
			(start -0.508 0.9398)
			(end 0.508 -0.9398)
			(stroke
				(width 0)
				(type default)
			)
			(fill no)
			(layer "F.CrtYd")
		)
		(fp_rect
			(start -0.508 0.9398)
			(end 0.508 -0.9398)
			(stroke
				(width 0)
				(type default)
			)
			(fill no)
			(layer "F.Fab")
		)
		(pad "1" smd custom
			(at 0 -0.4445)
			(size 0.1397 0.1397)
			(layers "F.Cu" "F.Mask" "F.Paste")
			(net "NCT7904_VSEN_P12V_AUX")
			(options
				(clearance outline)
				(anchor circle)
			)
			(primitives
				(gr_poly
					(pts
						(arc
							(start -0.1778 -0.2794)
							(mid -0.249642 -0.249642)
							(end -0.2794 -0.1778)
						)
						(arc
							(start -0.2794 0.1778)
							(mid -0.249642 0.249642)
							(end -0.1778 0.2794)
						)
						(arc
							(start 0.1778 0.2794)
							(mid 0.249642 0.249642)
							(end 0.2794 0.1778)
						)
						(arc
							(start 0.2794 -0.1778)
							(mid 0.249642 -0.249642)
							(end 0.1778 -0.2794)
						)
					)
					(width 0)
					(fill yes)
				)
			)
		)
		(pad "2" smd custom
			(at 0 0.4445)
			(size 0.1397 0.1397)
			(layers "F.Cu" "F.Mask" "F.Paste")
			(net "NCT7904_VSEN9")
			(options
				(clearance outline)
				(anchor circle)
			)
			(primitives
				(gr_poly
					(pts
						(arc
							(start -0.1778 -0.2794)
							(mid -0.249642 -0.249642)
							(end -0.2794 -0.1778)
						)
						(arc
							(start -0.2794 0.1778)
							(mid -0.249642 0.249642)
							(end -0.1778 0.2794)
						)
						(arc
							(start 0.1778 0.2794)
							(mid 0.249642 0.249642)
							(end 0.2794 0.1778)
						)
						(arc
							(start 0.2794 -0.1778)
							(mid 0.249642 -0.249642)
							(end 0.1778 -0.2794)
						)
					)
					(width 0)
					(fill yes)
				)
			)
		)
	)
	(footprint ""
		(layer "F.Cu")
		(at 38.862 -240.665 180)
		(property "Reference" "R156"
			(at 0 0 180)
			(layer "F.SilkS")
			(hide yes)
			(effects
				(font
					(size 1.27 1.27)
				)
			)
		)
		(property "Value" "330R2J-3-GP"
			(at 0.064008 -3.993896 180)
			(unlocked yes)
			(layer "F.Fab")
			(hide yes)
			(effects
				(font
					(size 1.016 1.016)
					(thickness 0.1524)
				)
			)
		)
		(property "Device Type" "R402H16"
			(at 0.064008 -5.517896 180)
			(unlocked yes)
			(layer "F.Fab")
			(hide yes)
			(effects
				(font
					(size 1.016 1.016)
					(thickness 0.1524)
				)
			)
		)
		(duplicate_pad_numbers_are_jumpers no)
		(fp_line
			(start 0.508 -0.9398)
			(end -0.508 -0.9398)
			(stroke
				(width 0.1524)
				(type default)
			)
			(layer "F.SilkS")
		)
		(fp_line
			(start -0.508 -0.9398)
			(end -0.508 0.9398)
			(stroke
				(width 0.1524)
				(type default)
			)
			(layer "F.SilkS")
		)
		(fp_rect
			(start -0.508 0.9398)
			(end 0.508 -0.9398)
			(stroke
				(width 0)
				(type default)
			)
			(fill no)
			(layer "F.CrtYd")
		)
		(fp_rect
			(start -0.508 0.9398)
			(end 0.508 -0.9398)
			(stroke
				(width 0)
				(type default)
			)
			(fill no)
			(layer "F.Fab")
		)
		(pad "1" smd custom
			(at 0 -0.4445 180)
			(size 0.1397 0.1397)
			(layers "F.Cu" "F.Mask" "F.Paste")
			(net "P3V3")
			(options
				(clearance outline)
				(anchor circle)
			)
			(primitives
				(gr_poly
					(pts
						(arc
							(start -0.1778 -0.2794)
							(mid -0.249642 -0.249642)
							(end -0.2794 -0.1778)
						)
						(arc
							(start -0.2794 0.1778)
							(mid -0.249642 0.249642)
							(end -0.1778 0.2794)
						)
						(arc
							(start 0.1778 0.2794)
							(mid 0.249642 0.249642)
							(end 0.2794 0.1778)
						)
						(arc
							(start 0.2794 -0.1778)
							(mid 0.249642 -0.249642)
							(end 0.1778 -0.2794)
						)
					)
					(width 0)
					(fill yes)
				)
			)
		)
		(pad "2" smd custom
			(at 0 0.4445 180)
			(size 0.1397 0.1397)
			(layers "F.Cu" "F.Mask" "F.Paste")
			(net "LED_DR_LED2")
			(options
				(clearance outline)
				(anchor circle)
			)
			(primitives
				(gr_poly
					(pts
						(arc
							(start -0.1778 -0.2794)
							(mid -0.249642 -0.249642)
							(end -0.2794 -0.1778)
						)
						(arc
							(start -0.2794 0.1778)
							(mid -0.249642 0.249642)
							(end -0.1778 0.2794)
						)
						(arc
							(start 0.1778 0.2794)
							(mid 0.249642 0.249642)
							(end 0.2794 0.1778)
						)
						(arc
							(start 0.2794 -0.1778)
							(mid 0.249642 -0.249642)
							(end 0.1778 -0.2794)
						)
					)
					(width 0)
					(fill yes)
				)
			)
		)
	)
	(footprint ""
		(layer "F.Cu")
		(at 32.399224 -173.65091 90)
		(property "Reference" "R17"
			(at 0 0 90)
			(layer "F.SilkS")
			(hide yes)
			(effects
				(font
					(size 1.27 1.27)
				)
			)
		)
		(property "Value" "100KR2F-L1-GP"
			(at 0.064008 -3.993896 90)
			(unlocked yes)
			(layer "F.Fab")
			(hide yes)
			(effects
				(font
					(size 1.016 1.016)
					(thickness 0.1524)
				)
			)
		)
		(property "Device Type" "R402H16"
			(at 0.064008 -5.517896 90)
			(unlocked yes)
			(layer "F.Fab")
			(hide yes)
			(effects
				(font
					(size 1.016 1.016)
					(thickness 0.1524)
				)
			)
		)
		(duplicate_pad_numbers_are_jumpers no)
		(fp_line
			(start 0.508 -0.9398)
			(end -0.508 -0.9398)
			(stroke
				(width 0.1524)
				(type default)
			)
			(layer "F.SilkS")
		)
		(fp_line
			(start -0.508 -0.9398)
			(end -0.508 0.9398)
			(stroke
				(width 0.1524)
				(type default)
			)
			(layer "F.SilkS")
		)
		(fp_rect
			(start -0.508 0.9398)
			(end 0.508 -0.9398)
			(stroke
				(width 0)
				(type default)
			)
			(fill no)
			(layer "F.CrtYd")
		)
		(fp_rect
			(start -0.508 0.9398)
			(end 0.508 -0.9398)
			(stroke
				(width 0)
				(type default)
			)
			(fill no)
			(layer "F.Fab")
		)
		(pad "1" smd custom
			(at 0 -0.4445 90)
			(size 0.1397 0.1397)
			(layers "F.Cu" "F.Mask" "F.Paste")
			(net "PWM_EXP_1A")
			(options
				(clearance outline)
				(anchor circle)
			)
			(primitives
				(gr_poly
					(pts
						(arc
							(start -0.1778 -0.2794)
							(mid -0.249642 -0.249642)
							(end -0.2794 -0.1778)
						)
						(arc
							(start -0.2794 0.1778)
							(mid -0.249642 0.249642)
							(end -0.1778 0.2794)
						)
						(arc
							(start 0.1778 0.2794)
							(mid 0.249642 0.249642)
							(end 0.2794 0.1778)
						)
						(arc
							(start 0.2794 -0.1778)
							(mid 0.249642 -0.249642)
							(end 0.1778 -0.2794)
						)
					)
					(width 0)
					(fill yes)
				)
			)
		)
		(pad "2" smd custom
			(at 0 0.4445 90)
			(size 0.1397 0.1397)
			(layers "F.Cu" "F.Mask" "F.Paste")
			(net "GND")
			(options
				(clearance outline)
				(anchor circle)
			)
			(primitives
				(gr_poly
					(pts
						(arc
							(start -0.1778 -0.2794)
							(mid -0.249642 -0.249642)
							(end -0.2794 -0.1778)
						)
						(arc
							(start -0.2794 0.1778)
							(mid -0.249642 0.249642)
							(end -0.1778 0.2794)
						)
						(arc
							(start 0.1778 0.2794)
							(mid 0.249642 0.249642)
							(end 0.2794 0.1778)
						)
						(arc
							(start 0.2794 -0.1778)
							(mid 0.249642 -0.249642)
							(end 0.1778 -0.2794)
						)
					)
					(width 0)
					(fill yes)
				)
			)
		)
	)
	(footprint ""
		(layer "F.Cu")
		(at 23.622 -365.506 90)
		(property "Reference" "PR1"
			(at 0 0 90)
			(layer "F.SilkS")
			(hide yes)
			(effects
				(font
					(size 1.27 1.27)
				)
			)
		)
		(property "Value" "100KR2F-L1-GP"
			(at 0.064008 -3.993896 90)
			(unlocked yes)
			(layer "F.Fab")
			(hide yes)
			(effects
				(font
					(size 1.016 1.016)
					(thickness 0.1524)
				)
			)
		)
		(property "Device Type" "R402H16"
			(at 0.064008 -5.517896 90)
			(unlocked yes)
			(layer "F.Fab")
			(hide yes)
			(effects
				(font
					(size 1.016 1.016)
					(thickness 0.1524)
				)
			)
		)
		(duplicate_pad_numbers_are_jumpers no)
		(fp_line
			(start 0.508 -0.9398)
			(end -0.508 -0.9398)
			(stroke
				(width 0.1524)
				(type default)
			)
			(layer "F.SilkS")
		)
		(fp_line
			(start -0.508 -0.9398)
			(end -0.508 0.9398)
			(stroke
				(width 0.1524)
				(type default)
			)
			(layer "F.SilkS")
		)
		(fp_rect
			(start -0.508 0.9398)
			(end 0.508 -0.9398)
			(stroke
				(width 0)
				(type default)
			)
			(fill no)
			(layer "F.CrtYd")
		)
		(fp_rect
			(start -0.508 0.9398)
			(end 0.508 -0.9398)
			(stroke
				(width 0)
				(type default)
			)
			(fill no)
			(layer "F.Fab")
		)
		(pad "1" smd custom
			(at 0 -0.4445 90)
			(size 0.1397 0.1397)
			(layers "F.Cu" "F.Mask" "F.Paste")
			(net "ADM1276_VCAP")
			(options
				(clearance outline)
				(anchor circle)
			)
			(primitives
				(gr_poly
					(pts
						(arc
							(start -0.1778 -0.2794)
							(mid -0.249642 -0.249642)
							(end -0.2794 -0.1778)
						)
						(arc
							(start -0.2794 0.1778)
							(mid -0.249642 0.249642)
							(end -0.1778 0.2794)
						)
						(arc
							(start 0.1778 0.2794)
							(mid 0.249642 0.249642)
							(end 0.2794 0.1778)
						)
						(arc
							(start 0.2794 -0.1778)
							(mid 0.249642 -0.249642)
							(end 0.1778 -0.2794)
						)
					)
					(width 0)
					(fill yes)
				)
			)
		)
		(pad "2" smd custom
			(at 0 0.4445 90)
			(size 0.1397 0.1397)
			(layers "F.Cu" "F.Mask" "F.Paste")
			(net "ADM1276_ISET")
			(options
				(clearance outline)
				(anchor circle)
			)
			(primitives
				(gr_poly
					(pts
						(arc
							(start -0.1778 -0.2794)
							(mid -0.249642 -0.249642)
							(end -0.2794 -0.1778)
						)
						(arc
							(start -0.2794 0.1778)
							(mid -0.249642 0.249642)
							(end -0.1778 0.2794)
						)
						(arc
							(start 0.1778 0.2794)
							(mid 0.249642 0.249642)
							(end 0.2794 0.1778)
						)
						(arc
							(start 0.2794 -0.1778)
							(mid 0.249642 -0.249642)
							(end 0.1778 -0.2794)
						)
					)
					(width 0)
					(fill yes)
				)
			)
		)
	)
	(footprint ""
		(layer "F.Cu")
		(at 9.4488 -74.7522 -90)
		(property "Reference" "C23"
			(at 0 0 270)
			(layer "F.SilkS")
			(hide yes)
			(effects
				(font
					(size 1.27 1.27)
				)
			)
		)
		(property "Value" "SCD1U50V3KX-GP"
			(at 0 -2.8194 270)
			(unlocked yes)
			(layer "F.Fab")
			(hide yes)
			(effects
				(font
					(size 1.016 1.016)
					(thickness 0.1524)
				)
			)
		)
		(property "Device Type" "C603H36"
			(at 0 -4.3434 270)
			(unlocked yes)
			(layer "F.Fab")
			(hide yes)
			(effects
				(font
					(size 1.016 1.016)
					(thickness 0.1524)
				)
			)
		)
		(duplicate_pad_numbers_are_jumpers no)
		(fp_line
			(start 0.508 0)
			(end -0.508 0)
			(stroke
				(width 0.2032)
				(type default)
			)
			(layer "F.SilkS")
		)
		(fp_rect
			(start -0.5842 1.3335)
			(end 0.5842 -1.3335)
			(stroke
				(width 0)
				(type default)
			)
			(fill no)
			(layer "F.CrtYd")
		)
		(fp_rect
			(start -0.5842 1.3335)
			(end 0.5842 -1.3335)
			(stroke
				(width 0)
				(type default)
			)
			(fill no)
			(layer "F.Fab")
		)
		(pad "1" smd custom
			(at 0 -0.762 270)
			(size 0.2159 0.2159)
			(layers "F.Cu" "F.Mask" "F.Paste")
			(net "P12VU")
			(options
				(clearance outline)
				(anchor circle)
			)
			(primitives
				(gr_poly
					(pts
						(arc
							(start -0.3302 -0.4318)
							(mid -0.402042 -0.402042)
							(end -0.4318 -0.3302)
						)
						(arc
							(start -0.4318 0.3302)
							(mid -0.402042 0.402042)
							(end -0.3302 0.4318)
						)
						(arc
							(start 0.3302 0.4318)
							(mid 0.402042 0.402042)
							(end 0.4318 0.3302)
						)
						(arc
							(start 0.4318 -0.3302)
							(mid 0.402042 -0.402042)
							(end 0.3302 -0.4318)
						)
					)
					(width 0)
					(fill yes)
				)
			)
		)
		(pad "2" smd custom
			(at 0 0.762 270)
			(size 0.2159 0.2159)
			(layers "F.Cu" "F.Mask" "F.Paste")
			(net "GND")
			(options
				(clearance outline)
				(anchor circle)
			)
			(primitives
				(gr_poly
					(pts
						(arc
							(start -0.3302 -0.4318)
							(mid -0.402042 -0.402042)
							(end -0.4318 -0.3302)
						)
						(arc
							(start -0.4318 0.3302)
							(mid -0.402042 0.402042)
							(end -0.3302 0.4318)
						)
						(arc
							(start 0.3302 0.4318)
							(mid 0.402042 0.402042)
							(end 0.4318 0.3302)
						)
						(arc
							(start 0.4318 -0.3302)
							(mid 0.402042 -0.402042)
							(end 0.3302 -0.4318)
						)
					)
					(width 0)
					(fill yes)
				)
			)
		)
	)
	(footprint ""
		(layer "F.Cu")
		(at 45.81271 -163.594034)
		(property "Reference" "R3"
			(at 0 0 0)
			(layer "F.SilkS")
			(hide yes)
			(effects
				(font
					(size 1.27 1.27)
				)
			)
		)
		(property "Value" "4K7R2F-GP"
			(at 0.064008 -3.993896 0)
			(unlocked yes)
			(layer "F.Fab")
			(hide yes)
			(effects
				(font
					(size 1.016 1.016)
					(thickness 0.1524)
				)
			)
		)
		(property "Device Type" "R402H16"
			(at 0.064008 -5.517896 0)
			(unlocked yes)
			(layer "F.Fab")
			(hide yes)
			(effects
				(font
					(size 1.016 1.016)
					(thickness 0.1524)
				)
			)
		)
		(duplicate_pad_numbers_are_jumpers no)
		(fp_line
			(start -0.508 -0.9398)
			(end -0.508 0.9398)
			(stroke
				(width 0.1524)
				(type default)
			)
			(layer "F.SilkS")
		)
		(fp_line
			(start 0.508 -0.9398)
			(end -0.508 -0.9398)
			(stroke
				(width 0.1524)
				(type default)
			)
			(layer "F.SilkS")
		)
		(fp_rect
			(start -0.508 0.9398)
			(end 0.508 -0.9398)
			(stroke
				(width 0)
				(type default)
			)
			(fill no)
			(layer "F.CrtYd")
		)
		(fp_rect
			(start -0.508 0.9398)
			(end 0.508 -0.9398)
			(stroke
				(width 0)
				(type default)
			)
			(fill no)
			(layer "F.Fab")
		)
		(pad "1" smd custom
			(at 0 -0.4445)
			(size 0.1397 0.1397)
			(layers "F.Cu" "F.Mask" "F.Paste")
			(net "OSC_TRI_S")
			(options
				(clearance outline)
				(anchor circle)
			)
			(primitives
				(gr_poly
					(pts
						(arc
							(start -0.1778 -0.2794)
							(mid -0.249642 -0.249642)
							(end -0.2794 -0.1778)
						)
						(arc
							(start -0.2794 0.1778)
							(mid -0.249642 0.249642)
							(end -0.1778 0.2794)
						)
						(arc
							(start 0.1778 0.2794)
							(mid 0.249642 0.249642)
							(end 0.2794 0.1778)
						)
						(arc
							(start 0.2794 -0.1778)
							(mid 0.249642 -0.249642)
							(end 0.1778 -0.2794)
						)
					)
					(width 0)
					(fill yes)
				)
			)
		)
		(pad "2" smd custom
			(at 0 0.4445)
			(size 0.1397 0.1397)
			(layers "F.Cu" "F.Mask" "F.Paste")
			(net "P3V3")
			(options
				(clearance outline)
				(anchor circle)
			)
			(primitives
				(gr_poly
					(pts
						(arc
							(start -0.1778 -0.2794)
							(mid -0.249642 -0.249642)
							(end -0.2794 -0.1778)
						)
						(arc
							(start -0.2794 0.1778)
							(mid -0.249642 0.249642)
							(end -0.1778 0.2794)
						)
						(arc
							(start 0.1778 0.2794)
							(mid 0.249642 0.249642)
							(end 0.2794 0.1778)
						)
						(arc
							(start 0.2794 -0.1778)
							(mid 0.249642 -0.249642)
							(end 0.1778 -0.2794)
						)
					)
					(width 0)
					(fill yes)
				)
			)
		)
	)
	(footprint ""
		(layer "F.Cu")
		(at 9.4488 -64.8208 180)
		(property "Reference" "R26"
			(at 0 0 180)
			(layer "F.SilkS")
			(hide yes)
			(effects
				(font
					(size 1.27 1.27)
				)
			)
		)
		(property "Value" "0R2J-2-GP"
			(at 0.064008 -3.993896 180)
			(unlocked yes)
			(layer "F.Fab")
			(hide yes)
			(effects
				(font
					(size 1.016 1.016)
					(thickness 0.1524)
				)
			)
		)
		(property "Device Type" "R402H16"
			(at 0.064008 -5.517896 180)
			(unlocked yes)
			(layer "F.Fab")
			(hide yes)
			(effects
				(font
					(size 1.016 1.016)
					(thickness 0.1524)
				)
			)
		)
		(duplicate_pad_numbers_are_jumpers no)
		(fp_line
			(start 0.508 -0.9398)
			(end -0.508 -0.9398)
			(stroke
				(width 0.1524)
				(type default)
			)
			(layer "F.SilkS")
		)
		(fp_line
			(start -0.508 -0.9398)
			(end -0.508 0.9398)
			(stroke
				(width 0.1524)
				(type default)
			)
			(layer "F.SilkS")
		)
		(fp_rect
			(start -0.508 0.9398)
			(end 0.508 -0.9398)
			(stroke
				(width 0)
				(type default)
			)
			(fill no)
			(layer "F.CrtYd")
		)
		(fp_rect
			(start -0.508 0.9398)
			(end 0.508 -0.9398)
			(stroke
				(width 0)
				(type default)
			)
			(fill no)
			(layer "F.Fab")
		)
		(pad "1" smd custom
			(at 0 -0.4445 180)
			(size 0.1397 0.1397)
			(layers "F.Cu" "F.Mask" "F.Paste")
			(net "LED_DR_LED5_K")
			(options
				(clearance outline)
				(anchor circle)
			)
			(primitives
				(gr_poly
					(pts
						(arc
							(start -0.1778 -0.2794)
							(mid -0.249642 -0.249642)
							(end -0.2794 -0.1778)
						)
						(arc
							(start -0.2794 0.1778)
							(mid -0.249642 0.249642)
							(end -0.1778 0.2794)
						)
						(arc
							(start 0.1778 0.2794)
							(mid 0.249642 0.249642)
							(end 0.2794 0.1778)
						)
						(arc
							(start 0.2794 -0.1778)
							(mid 0.249642 -0.249642)
							(end 0.1778 -0.2794)
						)
					)
					(width 0)
					(fill yes)
				)
			)
		)
		(pad "2" smd custom
			(at 0 0.4445 180)
			(size 0.1397 0.1397)
			(layers "F.Cu" "F.Mask" "F.Paste")
			(net "GND")
			(options
				(clearance outline)
				(anchor circle)
			)
			(primitives
				(gr_poly
					(pts
						(arc
							(start -0.1778 -0.2794)
							(mid -0.249642 -0.249642)
							(end -0.2794 -0.1778)
						)
						(arc
							(start -0.2794 0.1778)
							(mid -0.249642 0.249642)
							(end -0.1778 0.2794)
						)
						(arc
							(start 0.1778 0.2794)
							(mid 0.249642 0.249642)
							(end 0.2794 0.1778)
						)
						(arc
							(start 0.2794 -0.1778)
							(mid 0.249642 -0.249642)
							(end 0.1778 -0.2794)
						)
					)
					(width 0)
					(fill yes)
				)
			)
		)
	)
	(footprint ""
		(layer "F.Cu")
		(at 30.6832 -149.073616)
		(property "Reference" "R35"
			(at 0 0 0)
			(layer "F.SilkS")
			(hide yes)
			(effects
				(font
					(size 1.27 1.27)
				)
			)
		)
		(property "Value" "10KR2F-2-GP"
			(at 0.064008 -3.993896 0)
			(unlocked yes)
			(layer "F.Fab")
			(hide yes)
			(effects
				(font
					(size 1.016 1.016)
					(thickness 0.1524)
				)
			)
		)
		(property "Device Type" "R402H16"
			(at 0.064008 -5.517896 0)
			(unlocked yes)
			(layer "F.Fab")
			(hide yes)
			(effects
				(font
					(size 1.016 1.016)
					(thickness 0.1524)
				)
			)
		)
		(duplicate_pad_numbers_are_jumpers no)
		(fp_line
			(start -0.508 -0.9398)
			(end -0.508 0.9398)
			(stroke
				(width 0.1524)
				(type default)
			)
			(layer "F.SilkS")
		)
		(fp_line
			(start 0.508 -0.9398)
			(end -0.508 -0.9398)
			(stroke
				(width 0.1524)
				(type default)
			)
			(layer "F.SilkS")
		)
		(fp_rect
			(start -0.508 0.9398)
			(end 0.508 -0.9398)
			(stroke
				(width 0)
				(type default)
			)
			(fill no)
			(layer "F.CrtYd")
		)
		(fp_rect
			(start -0.508 0.9398)
			(end 0.508 -0.9398)
			(stroke
				(width 0)
				(type default)
			)
			(fill no)
			(layer "F.Fab")
		)
		(pad "1" smd custom
			(at 0 -0.4445)
			(size 0.1397 0.1397)
			(layers "F.Cu" "F.Mask" "F.Paste")
			(net "NCT7904_VSEN6")
			(options
				(clearance outline)
				(anchor circle)
			)
			(primitives
				(gr_poly
					(pts
						(arc
							(start -0.1778 -0.2794)
							(mid -0.249642 -0.249642)
							(end -0.2794 -0.1778)
						)
						(arc
							(start -0.2794 0.1778)
							(mid -0.249642 0.249642)
							(end -0.1778 0.2794)
						)
						(arc
							(start 0.1778 0.2794)
							(mid 0.249642 0.249642)
							(end 0.2794 0.1778)
						)
						(arc
							(start 0.2794 -0.1778)
							(mid 0.249642 -0.249642)
							(end 0.1778 -0.2794)
						)
					)
					(width 0)
					(fill yes)
				)
			)
		)
		(pad "2" smd custom
			(at 0 0.4445)
			(size 0.1397 0.1397)
			(layers "F.Cu" "F.Mask" "F.Paste")
			(net "GND")
			(options
				(clearance outline)
				(anchor circle)
			)
			(primitives
				(gr_poly
					(pts
						(arc
							(start -0.1778 -0.2794)
							(mid -0.249642 -0.249642)
							(end -0.2794 -0.1778)
						)
						(arc
							(start -0.2794 0.1778)
							(mid -0.249642 0.249642)
							(end -0.1778 0.2794)
						)
						(arc
							(start 0.1778 0.2794)
							(mid 0.249642 0.249642)
							(end 0.2794 0.1778)
						)
						(arc
							(start 0.2794 -0.1778)
							(mid 0.249642 -0.249642)
							(end 0.1778 -0.2794)
						)
					)
					(width 0)
					(fill yes)
				)
			)
		)
	)
	(footprint ""
		(layer "F.Cu")
		(at 41.3258 -136.271 90)
		(property "Reference" "PC88"
			(at 0 0 90)
			(layer "F.SilkS")
			(hide yes)
			(effects
				(font
					(size 1.27 1.27)
				)
			)
		)
		(property "Value" "SC220P50V2KX-3GP"
			(at 1.1811 -2.7051 90)
			(unlocked yes)
			(layer "F.Fab")
			(hide yes)
			(effects
				(font
					(size 1.016 1.016)
					(thickness 0.1524)
				)
			)
		)
		(property "Device Type" "C402H22"
			(at 1.1811 -4.2291 90)
			(unlocked yes)
			(layer "F.Fab")
			(hide yes)
			(effects
				(font
					(size 1.016 1.016)
					(thickness 0.1524)
				)
			)
		)
		(duplicate_pad_numbers_are_jumpers no)
		(fp_rect
			(start -0.4318 0.9525)
			(end 0.4318 -0.9525)
			(stroke
				(width 0)
				(type default)
			)
			(fill no)
			(layer "F.CrtYd")
		)
		(fp_rect
			(start -0.4318 0.9525)
			(end 0.4318 -0.9525)
			(stroke
				(width 0)
				(type default)
			)
			(fill no)
			(layer "F.Fab")
		)
		(pad "1" smd custom
			(at 0 -0.4445 90)
			(size 0.1524 0.1524)
			(layers "F.Cu" "F.Mask" "F.Paste")
			(net "P12VL_2490_SENSE")
			(options
				(clearance outline)
				(anchor circle)
			)
			(primitives
				(gr_poly
					(pts
						(arc
							(start 0.3048 -0.2032)
							(mid 0.275042 -0.275042)
							(end 0.2032 -0.3048)
						)
						(arc
							(start -0.2032 -0.3048)
							(mid -0.275042 -0.275042)
							(end -0.3048 -0.2032)
						)
						(arc
							(start -0.3048 0.2032)
							(mid -0.275042 0.275042)
							(end -0.2032 0.3048)
						)
						(arc
							(start 0.2032 0.3048)
							(mid 0.275042 0.275042)
							(end 0.3048 0.2032)
						)
					)
					(width 0)
					(fill yes)
				)
			)
		)
		(pad "2" smd custom
			(at 0 0.4445 90)
			(size 0.1524 0.1524)
			(layers "F.Cu" "F.Mask" "F.Paste")
			(net "P12VL_2490_VCC")
			(options
				(clearance outline)
				(anchor circle)
			)
			(primitives
				(gr_poly
					(pts
						(arc
							(start 0.3048 -0.2032)
							(mid 0.275042 -0.275042)
							(end 0.2032 -0.3048)
						)
						(arc
							(start -0.2032 -0.3048)
							(mid -0.275042 -0.275042)
							(end -0.3048 -0.2032)
						)
						(arc
							(start -0.3048 0.2032)
							(mid -0.275042 0.275042)
							(end -0.2032 0.3048)
						)
						(arc
							(start 0.2032 0.3048)
							(mid 0.275042 0.275042)
							(end 0.3048 0.2032)
						)
					)
					(width 0)
					(fill yes)
				)
			)
		)
	)
	(footprint ""
		(layer "F.Cu")
		(at 23.241 -361.188)
		(property "Reference" "PR5"
			(at 0 0 0)
			(layer "F.SilkS")
			(hide yes)
			(effects
				(font
					(size 1.27 1.27)
				)
			)
		)
		(property "Value" "0R2J-2-GP"
			(at 0.064008 -3.993896 0)
			(unlocked yes)
			(layer "F.Fab")
			(hide yes)
			(effects
				(font
					(size 1.016 1.016)
					(thickness 0.1524)
				)
			)
		)
		(property "Device Type" "R402H16"
			(at 0.064008 -5.517896 0)
			(unlocked yes)
			(layer "F.Fab")
			(hide yes)
			(effects
				(font
					(size 1.016 1.016)
					(thickness 0.1524)
				)
			)
		)
		(duplicate_pad_numbers_are_jumpers no)
		(fp_line
			(start -0.508 -0.9398)
			(end -0.508 0.9398)
			(stroke
				(width 0.1524)
				(type default)
			)
			(layer "F.SilkS")
		)
		(fp_line
			(start 0.508 -0.9398)
			(end -0.508 -0.9398)
			(stroke
				(width 0.1524)
				(type default)
			)
			(layer "F.SilkS")
		)
		(fp_rect
			(start -0.508 0.9398)
			(end 0.508 -0.9398)
			(stroke
				(width 0)
				(type default)
			)
			(fill no)
			(layer "F.CrtYd")
		)
		(fp_rect
			(start -0.508 0.9398)
			(end 0.508 -0.9398)
			(stroke
				(width 0)
				(type default)
			)
			(fill no)
			(layer "F.Fab")
		)
		(pad "1" smd custom
			(at 0 -0.4445)
			(size 0.1397 0.1397)
			(layers "F.Cu" "F.Mask" "F.Paste")
			(net "ADM1276_VCAP")
			(options
				(clearance outline)
				(anchor circle)
			)
			(primitives
				(gr_poly
					(pts
						(arc
							(start -0.1778 -0.2794)
							(mid -0.249642 -0.249642)
							(end -0.2794 -0.1778)
						)
						(arc
							(start -0.2794 0.1778)
							(mid -0.249642 0.249642)
							(end -0.1778 0.2794)
						)
						(arc
							(start 0.1778 0.2794)
							(mid 0.249642 0.249642)
							(end 0.2794 0.1778)
						)
						(arc
							(start 0.2794 -0.1778)
							(mid 0.249642 -0.249642)
							(end 0.1778 -0.2794)
						)
					)
					(width 0)
					(fill yes)
				)
			)
		)
		(pad "2" smd custom
			(at 0 0.4445)
			(size 0.1397 0.1397)
			(layers "F.Cu" "F.Mask" "F.Paste")
			(net "ADM1276_ADR")
			(options
				(clearance outline)
				(anchor circle)
			)
			(primitives
				(gr_poly
					(pts
						(arc
							(start -0.1778 -0.2794)
							(mid -0.249642 -0.249642)
							(end -0.2794 -0.1778)
						)
						(arc
							(start -0.2794 0.1778)
							(mid -0.249642 0.249642)
							(end -0.1778 0.2794)
						)
						(arc
							(start 0.1778 0.2794)
							(mid 0.249642 0.249642)
							(end 0.2794 0.1778)
						)
						(arc
							(start 0.2794 -0.1778)
							(mid 0.249642 -0.249642)
							(end 0.1778 -0.2794)
						)
					)
					(width 0)
					(fill yes)
				)
			)
		)
	)
	(footprint ""
		(layer "F.Cu")
		(at 41.4782 -177.6222)
		(property "Reference" "C253"
			(at 0 0 0)
			(layer "F.SilkS")
			(hide yes)
			(effects
				(font
					(size 1.27 1.27)
				)
			)
		)
		(property "Value" "SC4D7U6D3V3KX-GP"
			(at 0 -2.8194 0)
			(unlocked yes)
			(layer "F.Fab")
			(hide yes)
			(effects
				(font
					(size 1.016 1.016)
					(thickness 0.1524)
				)
			)
		)
		(property "Device Type" "C603H36"
			(at 0 -4.3434 0)
			(unlocked yes)
			(layer "F.Fab")
			(hide yes)
			(effects
				(font
					(size 1.016 1.016)
					(thickness 0.1524)
				)
			)
		)
		(duplicate_pad_numbers_are_jumpers no)
		(fp_line
			(start 0.508 0)
			(end -0.508 0)
			(stroke
				(width 0.2032)
				(type default)
			)
			(layer "F.SilkS")
		)
		(fp_rect
			(start -0.5842 1.3335)
			(end 0.5842 -1.3335)
			(stroke
				(width 0)
				(type default)
			)
			(fill no)
			(layer "F.CrtYd")
		)
		(fp_rect
			(start -0.5842 1.3335)
			(end 0.5842 -1.3335)
			(stroke
				(width 0)
				(type default)
			)
			(fill no)
			(layer "F.Fab")
		)
		(pad "1" smd custom
			(at 0 -0.762)
			(size 0.2159 0.2159)
			(layers "F.Cu" "F.Mask" "F.Paste")
			(net "D_LATCH_PRE#")
			(options
				(clearance outline)
				(anchor circle)
			)
			(primitives
				(gr_poly
					(pts
						(arc
							(start -0.3302 -0.4318)
							(mid -0.402042 -0.402042)
							(end -0.4318 -0.3302)
						)
						(arc
							(start -0.4318 0.3302)
							(mid -0.402042 0.402042)
							(end -0.3302 0.4318)
						)
						(arc
							(start 0.3302 0.4318)
							(mid 0.402042 0.402042)
							(end 0.4318 0.3302)
						)
						(arc
							(start 0.4318 -0.3302)
							(mid 0.402042 -0.402042)
							(end 0.3302 -0.4318)
						)
					)
					(width 0)
					(fill yes)
				)
			)
		)
		(pad "2" smd custom
			(at 0 0.762)
			(size 0.2159 0.2159)
			(layers "F.Cu" "F.Mask" "F.Paste")
			(net "GND")
			(options
				(clearance outline)
				(anchor circle)
			)
			(primitives
				(gr_poly
					(pts
						(arc
							(start -0.3302 -0.4318)
							(mid -0.402042 -0.402042)
							(end -0.4318 -0.3302)
						)
						(arc
							(start -0.4318 0.3302)
							(mid -0.402042 0.402042)
							(end -0.3302 0.4318)
						)
						(arc
							(start 0.3302 0.4318)
							(mid 0.402042 0.402042)
							(end 0.4318 0.3302)
						)
						(arc
							(start 0.4318 -0.3302)
							(mid 0.402042 -0.402042)
							(end 0.3302 -0.4318)
						)
					)
					(width 0)
					(fill yes)
				)
			)
		)
	)
	(footprint ""
		(layer "F.Cu")
		(at 37.719 -373.9896 180)
		(property "Reference" "PR25"
			(at 0 0 180)
			(layer "F.SilkS")
			(hide yes)
			(effects
				(font
					(size 1.27 1.27)
				)
			)
		)
		(property "Value" "0R2J-2-GP"
			(at 0.064008 -3.993896 180)
			(unlocked yes)
			(layer "F.Fab")
			(hide yes)
			(effects
				(font
					(size 1.016 1.016)
					(thickness 0.1524)
				)
			)
		)
		(property "Device Type" "R402H16"
			(at 0.064008 -5.517896 180)
			(unlocked yes)
			(layer "F.Fab")
			(hide yes)
			(effects
				(font
					(size 1.016 1.016)
					(thickness 0.1524)
				)
			)
		)
		(duplicate_pad_numbers_are_jumpers no)
		(fp_line
			(start 0.508 -0.9398)
			(end -0.508 -0.9398)
			(stroke
				(width 0.1524)
				(type default)
			)
			(layer "F.SilkS")
		)
		(fp_line
			(start -0.508 -0.9398)
			(end -0.508 0.9398)
			(stroke
				(width 0.1524)
				(type default)
			)
			(layer "F.SilkS")
		)
		(fp_rect
			(start -0.508 0.9398)
			(end 0.508 -0.9398)
			(stroke
				(width 0)
				(type default)
			)
			(fill no)
			(layer "F.CrtYd")
		)
		(fp_rect
			(start -0.508 0.9398)
			(end 0.508 -0.9398)
			(stroke
				(width 0)
				(type default)
			)
			(fill no)
			(layer "F.Fab")
		)
		(pad "1" smd custom
			(at 0 -0.4445 180)
			(size 0.1397 0.1397)
			(layers "F.Cu" "F.Mask" "F.Paste")
			(net "P12V")
			(options
				(clearance outline)
				(anchor circle)
			)
			(primitives
				(gr_poly
					(pts
						(arc
							(start -0.1778 -0.2794)
							(mid -0.249642 -0.249642)
							(end -0.2794 -0.1778)
						)
						(arc
							(start -0.2794 0.1778)
							(mid -0.249642 0.249642)
							(end -0.1778 0.2794)
						)
						(arc
							(start 0.1778 0.2794)
							(mid 0.249642 0.249642)
							(end 0.2794 0.1778)
						)
						(arc
							(start 0.2794 -0.1778)
							(mid 0.249642 -0.249642)
							(end 0.1778 -0.2794)
						)
					)
					(width 0)
					(fill yes)
				)
			)
		)
		(pad "2" smd custom
			(at 0 0.4445 180)
			(size 0.1397 0.1397)
			(layers "F.Cu" "F.Mask" "F.Paste")
			(net "ADM1276_GATE_RSV")
			(options
				(clearance outline)
				(anchor circle)
			)
			(primitives
				(gr_poly
					(pts
						(arc
							(start -0.1778 -0.2794)
							(mid -0.249642 -0.249642)
							(end -0.2794 -0.1778)
						)
						(arc
							(start -0.2794 0.1778)
							(mid -0.249642 0.249642)
							(end -0.1778 0.2794)
						)
						(arc
							(start 0.1778 0.2794)
							(mid 0.249642 0.249642)
							(end 0.2794 0.1778)
						)
						(arc
							(start 0.2794 -0.1778)
							(mid 0.249642 -0.249642)
							(end 0.1778 -0.2794)
						)
					)
					(width 0)
					(fill yes)
				)
			)
		)
	)
	(footprint ""
		(layer "F.Cu")
		(at 22.86 -122.555)
		(property "Reference" "PR61"
			(at 0 0 0)
			(layer "F.SilkS")
			(hide yes)
			(effects
				(font
					(size 1.27 1.27)
				)
			)
		)
		(property "Value" "D002R2512F-GP"
			(at -3.228594 -1.194054 0)
			(unlocked yes)
			(layer "F.Fab")
			(hide yes)
			(effects
				(font
					(size 1.016 1.016)
					(thickness 0.1524)
				)
			)
		)
		(property "Device Type" "R2512-2H32"
			(at -3.228594 -2.718054 0)
			(unlocked yes)
			(layer "F.Fab")
			(hide yes)
			(effects
				(font
					(size 1.016 1.016)
					(thickness 0.1524)
				)
			)
		)
		(duplicate_pad_numbers_are_jumpers no)
		(fp_line
			(start -1.9685 -3.81)
			(end 1.9685 -3.81)
			(stroke
				(width 0.1524)
				(type default)
			)
			(layer "F.SilkS")
		)
		(fp_line
			(start -1.9685 3.81)
			(end -1.9685 -3.81)
			(stroke
				(width 0.1524)
				(type default)
			)
			(layer "F.SilkS")
		)
		(fp_line
			(start 1.9685 -3.81)
			(end 1.9685 3.81)
			(stroke
				(width 0.1524)
				(type default)
			)
			(layer "F.SilkS")
		)
		(fp_line
			(start 1.9685 3.81)
			(end -1.9685 3.81)
			(stroke
				(width 0.1524)
				(type default)
			)
			(layer "F.SilkS")
		)
		(fp_rect
			(start -1.5875 3.175)
			(end 1.5875 -3.175)
			(stroke
				(width 0)
				(type default)
			)
			(fill no)
			(layer "F.CrtYd")
		)
		(fp_poly
			(pts
				(xy -2.2225 3.8862) (xy -2.2225 0.00254) (xy -1.5875 0.00254) (xy -1.5875 3.175) (xy 1.5875 3.175)
				(xy 1.5875 -3.175) (xy -1.5875 -3.175) (xy -1.5875 -0.00254) (xy -2.2225 -0.00254) (xy -2.2225 -3.8862)
				(xy 2.2225 -3.8862) (xy 2.2225 3.8862)
			)
			(stroke
				(width 0)
				(type default)
			)
			(fill no)
			(layer "F.CrtYd")
		)
		(fp_rect
			(start -2.2225 3.8862)
			(end 2.2225 -3.8862)
			(stroke
				(width 0)
				(type default)
			)
			(fill no)
			(layer "F.Fab")
		)
		(pad "1" smd rect
			(at 0 -2.273808)
			(size 3.429 2.5654)
			(layers "F.Cu" "F.Mask" "F.Paste")
			(net "P12V")
		)
		(pad "2" smd rect
			(at 0 2.273808)
			(size 3.429 2.5654)
			(layers "F.Cu" "F.Mask" "F.Paste")
			(net "P12VU_NET")
		)
	)
	(footprint ""
		(layer "F.Cu")
		(at 22.71649 -162.262566 180)
		(property "Reference" "R8"
			(at 0 0 180)
			(layer "F.SilkS")
			(hide yes)
			(effects
				(font
					(size 1.27 1.27)
				)
			)
		)
		(property "Value" "0R5J-5-GP"
			(at 0 -8.9535 180)
			(unlocked yes)
			(layer "F.Fab")
			(hide yes)
			(effects
				(font
					(size 1.27 1.016)
					(thickness 0.1524)
				)
			)
		)
		(property "Device Type" "R805H24"
			(at 0 -10.6299 180)
			(unlocked yes)
			(layer "F.Fab")
			(hide yes)
			(effects
				(font
					(size 1.27 1.016)
					(thickness 0.1524)
				)
			)
		)
		(duplicate_pad_numbers_are_jumpers no)
		(fp_line
			(start 0.889 1.7018)
			(end 0.889 -0.508)
			(stroke
				(width 0.1524)
				(type default)
			)
			(layer "F.SilkS")
		)
		(fp_line
			(start 0.889 -1.7018)
			(end 0.889 -0.381)
			(stroke
				(width 0.1524)
				(type default)
			)
			(layer "F.SilkS")
		)
		(fp_line
			(start 0.889 -1.7018)
			(end -0.889 -1.7018)
			(stroke
				(width 0.1524)
				(type default)
			)
			(layer "F.SilkS")
		)
		(fp_line
			(start -0.889 1.7018)
			(end 0.889 1.7018)
			(stroke
				(width 0.1524)
				(type default)
			)
			(layer "F.SilkS")
		)
		(fp_line
			(start -0.889 0.0762)
			(end -0.889 1.7018)
			(stroke
				(width 0.1524)
				(type default)
			)
			(layer "F.SilkS")
		)
		(fp_line
			(start -0.889 -1.7018)
			(end -0.889 0.2794)
			(stroke
				(width 0.1524)
				(type default)
			)
			(layer "F.SilkS")
		)
		(fp_poly
			(pts
				(xy 0.9652 -1.778) (xy 0.9652 1.778) (xy -0.9652 1.778) (xy -0.9652 -1.778)
			)
			(stroke
				(width 0)
				(type default)
			)
			(fill no)
			(layer "F.CrtYd")
		)
		(fp_rect
			(start -0.9652 1.778)
			(end 0.9652 -1.778)
			(stroke
				(width 0)
				(type default)
			)
			(fill no)
			(layer "F.Fab")
		)
		(pad "1" smd rect
			(at 0 -0.9652 180)
			(size 1.397 1.143)
			(layers "F.Cu" "F.Mask" "F.Paste")
			(net "NCT7904_GND")
		)
		(pad "2" smd rect
			(at 0 0.9652 180)
			(size 1.397 1.143)
			(layers "F.Cu" "F.Mask" "F.Paste")
			(net "GND")
		)
	)
	(footprint ""
		(layer "F.Cu")
		(at 22.479 -181.7116 90)
		(property "Reference" "D8"
			(at 0 0 90)
			(layer "F.SilkS")
			(hide yes)
			(effects
				(font
					(size 1.27 1.27)
				)
			)
		)
		(property "Value" "BAS16H-GP"
			(at 0 -5.5372 90)
			(unlocked yes)
			(layer "F.Fab")
			(hide yes)
			(effects
				(font
					(size 1.016 1.016)
					(thickness 0.1524)
				)
			)
		)
		(property "Device Type" "SOD123AKH48"
			(at 0 -7.0612 90)
			(unlocked yes)
			(layer "F.Fab")
			(hide yes)
			(effects
				(font
					(size 1.016 1.016)
					(thickness 0.1524)
				)
			)
		)
		(duplicate_pad_numbers_are_jumpers no)
		(fp_line
			(start 1.016 -2.667)
			(end -1.016 -2.667)
			(stroke
				(width 0.1524)
				(type default)
			)
			(layer "F.SilkS")
		)
		(fp_line
			(start -1.016 -2.667)
			(end -1.016 2.667)
			(stroke
				(width 0.1524)
				(type default)
			)
			(layer "F.SilkS")
		)
		(fp_line
			(start 1.016 2.667)
			(end 1.016 -2.667)
			(stroke
				(width 0.1524)
				(type default)
			)
			(layer "F.SilkS")
		)
		(fp_line
			(start -1.016 2.667)
			(end 1.016 2.667)
			(stroke
				(width 0.1524)
				(type default)
			)
			(layer "F.SilkS")
		)
		(fp_line
			(start 0.889 2.921)
			(end -0.889 2.921)
			(stroke
				(width 0.508)
				(type default)
			)
			(layer "F.SilkS")
		)
		(fp_rect
			(start -1.143 3.175)
			(end 1.143 -2.794)
			(stroke
				(width 0)
				(type default)
			)
			(fill no)
			(layer "F.CrtYd")
		)
		(fp_poly
			(pts
				(xy -1.143 -2.794) (xy 1.143 -2.794) (xy 1.143 3.175) (xy -1.143 3.175)
			)
			(stroke
				(width 0)
				(type default)
			)
			(fill no)
			(layer "F.Fab")
		)
		(pad "A" smd rect
			(at 0 -1.6891 90)
			(size 0.889 1.397)
			(layers "F.Cu" "F.Mask" "F.Paste")
			(net "FAN_TACH7")
		)
		(pad "K" smd rect
			(at 0 1.6891 90)
			(size 0.889 1.397)
			(layers "F.Cu" "F.Mask" "F.Paste")
			(net "P12V")
		)
	)
	(footprint ""
		(layer "F.Cu")
		(at 37.032692 -289.281362 180)
		(property "Reference" "TC17"
			(at 0 0 180)
			(layer "F.SilkS")
			(hide yes)
			(effects
				(font
					(size 1.27 1.27)
				)
			)
		)
		(property "Value" "ST15U25VDM-1-GP"
			(at 0 -9.6012 180)
			(unlocked yes)
			(layer "F.Fab")
			(hide yes)
			(effects
				(font
					(size 1.016 1.016)
					(thickness 0.1524)
				)
			)
		)
		(property "Device Type" "CT7343H79"
			(at 0 -11.1252 180)
			(unlocked yes)
			(layer "F.Fab")
			(hide yes)
			(effects
				(font
					(size 1.016 1.016)
					(thickness 0.1524)
				)
			)
		)
		(duplicate_pad_numbers_are_jumpers no)
		(fp_line
			(start 2.286 4.8768)
			(end -2.286 4.8768)
			(stroke
				(width 0.1524)
				(type default)
			)
			(layer "F.SilkS")
		)
		(fp_line
			(start 2.286 2.032)
			(end 2.286 4.8768)
			(stroke
				(width 0.1524)
				(type default)
			)
			(layer "F.SilkS")
		)
		(fp_line
			(start 2.286 -2.032)
			(end 2.286 -4.8768)
			(stroke
				(width 0.1524)
				(type default)
			)
			(layer "F.SilkS")
		)
		(fp_line
			(start 2.286 -4.8768)
			(end -2.286 -4.8768)
			(stroke
				(width 0.1524)
				(type default)
			)
			(layer "F.SilkS")
		)
		(fp_line
			(start 2.1082 -4.699)
			(end -2.1082 -4.699)
			(stroke
				(width 0.508)
				(type default)
			)
			(layer "F.SilkS")
		)
		(fp_line
			(start -2.286 4.8768)
			(end -2.286 2.032)
			(stroke
				(width 0.1524)
				(type default)
			)
			(layer "F.SilkS")
		)
		(fp_line
			(start -2.286 -4.8768)
			(end -2.286 -2.032)
			(stroke
				(width 0.1524)
				(type default)
			)
			(layer "F.SilkS")
		)
		(fp_rect
			(start -2.1463 3.6449)
			(end 2.1463 -3.6449)
			(stroke
				(width 0)
				(type default)
			)
			(fill no)
			(layer "F.CrtYd")
		)
		(fp_poly
			(pts
				(xy -2.54 4.953) (xy -2.54 4.2926) (xy -3.81 4.2926) (xy -3.81 -4.2926) (xy -2.54 -4.2926) (xy -2.54 -4.953)
				(xy 2.54 -4.953) (xy 2.54 -4.2926) (xy 3.81 -4.2926) (xy 3.81 -1.6256) (xy 2.1463 -1.6256) (xy 2.1463 -3.6449)
				(xy -2.1463 -3.6449) (xy -2.1463 3.6449) (xy 2.1463 3.6449) (xy 2.1463 -1.6129) (xy 3.81 -1.6129)
				(xy 3.81 4.2926) (xy 2.54 4.2926) (xy 2.54 4.953)
			)
			(stroke
				(width 0)
				(type default)
			)
			(fill no)
			(layer "F.CrtYd")
		)
		(fp_rect
			(start 2.54 4.2926)
			(end 3.81 -4.2926)
			(stroke
				(width 0)
				(type default)
			)
			(fill no)
			(layer "F.Fab")
		)
		(fp_rect
			(start -2.54 4.953)
			(end 2.54 -4.953)
			(stroke
				(width 0)
				(type default)
			)
			(fill no)
			(layer "F.Fab")
		)
		(fp_rect
			(start -3.81 4.2926)
			(end -2.54 -4.2926)
			(stroke
				(width 0)
				(type default)
			)
			(fill no)
			(layer "F.Fab")
		)
		(pad "1" smd rect
			(at 0 -3.1496 180)
			(size 2.413 2.286)
			(layers "F.Cu" "F.Mask" "F.Paste")
			(net "P12V")
		)
		(pad "2" smd rect
			(at 0 3.1496 180)
			(size 2.413 2.286)
			(layers "F.Cu" "F.Mask" "F.Paste")
			(net "GND")
		)
		(zone
			(layer "F.Cu")
			(hatch none 0.5)
			(connect_pads
				(clearance 0)
			)
			(min_thickness 0.25)
			(keepout
				(tracks allowed)
				(vias not_allowed)
				(pads allowed)
				(copperpour not_allowed)
				(footprints allowed)
			)
			(placement
				(enabled no)
				(sheetname "")
			)
			(fill
				(thermal_gap 0.5)
				(thermal_bridge_width 0.5)
				(island_removal_mode 0)
			)
			(polygon
				(pts
					(xy 35.521392 -287.592262) (xy 35.521392 -284.683962) (xy 38.543992 -284.683962) (xy 38.543992 -287.579562)
					(xy 38.543992 -287.909762) (xy 35.521392 -287.909762)
				)
			)
		)
		(zone
			(layer "F.Cu")
			(hatch none 0.5)
			(connect_pads
				(clearance 0)
			)
			(min_thickness 0.25)
			(keepout
				(tracks allowed)
				(vias not_allowed)
				(pads allowed)
				(copperpour not_allowed)
				(footprints allowed)
			)
			(placement
				(enabled no)
				(sheetname "")
			)
			(fill
				(thermal_gap 0.5)
				(thermal_bridge_width 0.5)
				(island_removal_mode 0)
			)
			(polygon
				(pts
					(xy 38.543992 -293.878762) (xy 35.521392 -293.878762) (xy 35.521392 -290.983162) (xy 35.521392 -290.652962)
					(xy 38.543992 -290.652962) (xy 38.543992 -290.983162)
				)
			)
		)
	)
	(footprint ""
		(layer "F.Cu")
		(at 4.040124 -306.660042 -90)
		(property "Reference" "CN3"
			(at 0 0 270)
			(layer "F.SilkS")
			(hide yes)
			(effects
				(font
					(size 1.27 1.27)
				)
			)
		)
		(property "Value" "JWT-CON5-42-GP"
			(at -7.8105 2.9591 270)
			(unlocked yes)
			(layer "F.Fab")
			(hide yes)
			(effects
				(font
					(size 1.016 1.016)
					(thickness 0.1524)
				)
			)
		)
		(property "Device Type" "A2541WR0-1TX5PA-6T-0E"
			(at -7.8105 1.4351 270)
			(unlocked yes)
			(layer "F.Fab")
			(hide yes)
			(effects
				(font
					(size 1.016 1.016)
					(thickness 0.1524)
				)
			)
		)
		(duplicate_pad_numbers_are_jumpers no)
		(fp_line
			(start -6.604 10.287)
			(end 6.604 10.287)
			(stroke
				(width 0.1524)
				(type default)
			)
			(layer "F.SilkS")
		)
		(fp_line
			(start 6.604 10.287)
			(end 6.604 -0.9652)
			(stroke
				(width 0.1524)
				(type default)
			)
			(layer "F.SilkS")
		)
		(fp_line
			(start -6.604 -0.9652)
			(end -6.604 10.287)
			(stroke
				(width 0.1524)
				(type default)
			)
			(layer "F.SilkS")
		)
		(fp_line
			(start 6.604 -0.9652)
			(end -6.604 -0.9652)
			(stroke
				(width 0.1524)
				(type default)
			)
			(layer "F.SilkS")
		)
		(fp_line
			(start -6.731 -1.0922)
			(end -6.731 0.1778)
			(stroke
				(width 0.4064)
				(type default)
			)
			(layer "F.SilkS")
		)
		(fp_line
			(start -5.461 -1.0922)
			(end -6.731 -1.0922)
			(stroke
				(width 0.4064)
				(type default)
			)
			(layer "F.SilkS")
		)
		(fp_circle
			(center -5.08 0)
			(end -5.08 -1.0668)
			(stroke
				(width 0.3048)
				(type default)
			)
			(fill no)
			(layer "F.SilkS")
		)
		(fp_circle
			(center -2.54 0)
			(end -2.54 -1.0668)
			(stroke
				(width 0.3048)
				(type default)
			)
			(fill no)
			(layer "F.SilkS")
		)
		(fp_circle
			(center 0 0)
			(end 0 -1.0668)
			(stroke
				(width 0.3048)
				(type default)
			)
			(fill no)
			(layer "F.SilkS")
		)
		(fp_circle
			(center 2.54 0)
			(end 2.54 -1.0668)
			(stroke
				(width 0.3048)
				(type default)
			)
			(fill no)
			(layer "F.SilkS")
		)
		(fp_circle
			(center 5.08 0)
			(end 5.08 -1.0668)
			(stroke
				(width 0.3048)
				(type default)
			)
			(fill no)
			(layer "F.SilkS")
		)
		(fp_rect
			(start -6.35 10.033)
			(end 6.35 -0.3302)
			(stroke
				(width 0)
				(type default)
			)
			(fill no)
			(layer "F.CrtYd")
		)
		(fp_poly
			(pts
				(xy -6.35 -0.3302) (xy 6.858 -0.3302) (xy 6.858 -1.2192) (xy -6.858 -1.2192) (xy -6.858 10.541)
				(xy 6.858 10.541) (xy 6.858 -0.3175) (xy 6.35 -0.3175) (xy 6.35 10.033) (xy -6.35 10.033)
			)
			(stroke
				(width 0)
				(type default)
			)
			(fill no)
			(layer "F.CrtYd")
		)
		(fp_rect
			(start -6.858 10.541)
			(end 6.858 -1.2192)
			(stroke
				(width 0)
				(type default)
			)
			(fill no)
			(layer "F.Fab")
		)
		(pad "1" thru_hole circle
			(at -5.08 0 270)
			(size 1.4224 1.4224)
			(drill 1.016)
			(layers "*.Cu" "*.Mask")
			(remove_unused_layers no)
			(net "GND")
			(clearance 0.1524)
			(thermal_gap 0.1524)
		)
		(pad "2" thru_hole circle
			(at -2.54 0 270)
			(size 1.4224 1.4224)
			(drill 1.016)
			(layers "*.Cu" "*.Mask")
			(remove_unused_layers no)
			(net "P12V_FAN3")
			(clearance 0.1524)
			(thermal_gap 0.1524)
		)
		(pad "3" thru_hole circle
			(at 0 0 270)
			(size 1.4224 1.4224)
			(drill 1.016)
			(layers "*.Cu" "*.Mask")
			(remove_unused_layers no)
			(net "FAN_TACH6")
			(clearance 0.1524)
			(thermal_gap 0.1524)
		)
		(pad "4" thru_hole circle
			(at 2.54 0 270)
			(size 1.4224 1.4224)
			(drill 1.016)
			(layers "*.Cu" "*.Mask")
			(remove_unused_layers no)
			(net "PWM_OUT_FAN3_NET")
			(clearance 0.1524)
			(thermal_gap 0.1524)
		)
		(pad "5" thru_hole circle
			(at 5.08 0 270)
			(size 1.4224 1.4224)
			(drill 1.016)
			(layers "*.Cu" "*.Mask")
			(remove_unused_layers no)
			(net "FAN_TACH5")
			(clearance 0.1524)
			(thermal_gap 0.1524)
		)
	)
	(footprint ""
		(layer "F.Cu")
		(at 31.571692 -481.559362 180)
		(property "Reference" "TC18"
			(at 0 0 180)
			(layer "F.SilkS")
			(hide yes)
			(effects
				(font
					(size 1.27 1.27)
				)
			)
		)
		(property "Value" "ST15U25VDM-1-GP"
			(at 0 -9.6012 180)
			(unlocked yes)
			(layer "F.Fab")
			(hide yes)
			(effects
				(font
					(size 1.016 1.016)
					(thickness 0.1524)
				)
			)
		)
		(property "Device Type" "CT7343H79"
			(at 0 -11.1252 180)
			(unlocked yes)
			(layer "F.Fab")
			(hide yes)
			(effects
				(font
					(size 1.016 1.016)
					(thickness 0.1524)
				)
			)
		)
		(duplicate_pad_numbers_are_jumpers no)
		(fp_line
			(start 2.286 4.8768)
			(end -2.286 4.8768)
			(stroke
				(width 0.1524)
				(type default)
			)
			(layer "F.SilkS")
		)
		(fp_line
			(start 2.286 2.032)
			(end 2.286 4.8768)
			(stroke
				(width 0.1524)
				(type default)
			)
			(layer "F.SilkS")
		)
		(fp_line
			(start 2.286 -2.032)
			(end 2.286 -4.8768)
			(stroke
				(width 0.1524)
				(type default)
			)
			(layer "F.SilkS")
		)
		(fp_line
			(start 2.286 -4.8768)
			(end -2.286 -4.8768)
			(stroke
				(width 0.1524)
				(type default)
			)
			(layer "F.SilkS")
		)
		(fp_line
			(start 2.1082 -4.699)
			(end -2.1082 -4.699)
			(stroke
				(width 0.508)
				(type default)
			)
			(layer "F.SilkS")
		)
		(fp_line
			(start -2.286 4.8768)
			(end -2.286 2.032)
			(stroke
				(width 0.1524)
				(type default)
			)
			(layer "F.SilkS")
		)
		(fp_line
			(start -2.286 -4.8768)
			(end -2.286 -2.032)
			(stroke
				(width 0.1524)
				(type default)
			)
			(layer "F.SilkS")
		)
		(fp_rect
			(start -2.1463 3.6449)
			(end 2.1463 -3.6449)
			(stroke
				(width 0)
				(type default)
			)
			(fill no)
			(layer "F.CrtYd")
		)
		(fp_poly
			(pts
				(xy -2.54 4.953) (xy -2.54 4.2926) (xy -3.81 4.2926) (xy -3.81 -4.2926) (xy -2.54 -4.2926) (xy -2.54 -4.953)
				(xy 2.54 -4.953) (xy 2.54 -4.2926) (xy 3.81 -4.2926) (xy 3.81 -1.6256) (xy 2.1463 -1.6256) (xy 2.1463 -3.6449)
				(xy -2.1463 -3.6449) (xy -2.1463 3.6449) (xy 2.1463 3.6449) (xy 2.1463 -1.6129) (xy 3.81 -1.6129)
				(xy 3.81 4.2926) (xy 2.54 4.2926) (xy 2.54 4.953)
			)
			(stroke
				(width 0)
				(type default)
			)
			(fill no)
			(layer "F.CrtYd")
		)
		(fp_rect
			(start 2.54 4.2926)
			(end 3.81 -4.2926)
			(stroke
				(width 0)
				(type default)
			)
			(fill no)
			(layer "F.Fab")
		)
		(fp_rect
			(start -2.54 4.953)
			(end 2.54 -4.953)
			(stroke
				(width 0)
				(type default)
			)
			(fill no)
			(layer "F.Fab")
		)
		(fp_rect
			(start -3.81 4.2926)
			(end -2.54 -4.2926)
			(stroke
				(width 0)
				(type default)
			)
			(fill no)
			(layer "F.Fab")
		)
		(pad "1" smd rect
			(at 0 -3.1496 180)
			(size 2.413 2.286)
			(layers "F.Cu" "F.Mask" "F.Paste")
			(net "P12V")
		)
		(pad "2" smd rect
			(at 0 3.1496 180)
			(size 2.413 2.286)
			(layers "F.Cu" "F.Mask" "F.Paste")
			(net "GND")
		)
		(zone
			(layer "F.Cu")
			(hatch none 0.5)
			(connect_pads
				(clearance 0)
			)
			(min_thickness 0.25)
			(keepout
				(tracks allowed)
				(vias not_allowed)
				(pads allowed)
				(copperpour not_allowed)
				(footprints allowed)
			)
			(placement
				(enabled no)
				(sheetname "")
			)
			(fill
				(thermal_gap 0.5)
				(thermal_bridge_width 0.5)
				(island_removal_mode 0)
			)
			(polygon
				(pts
					(xy 30.060392 -479.870262) (xy 30.060392 -476.961962) (xy 33.082992 -476.961962) (xy 33.082992 -479.857562)
					(xy 33.082992 -480.187762) (xy 30.060392 -480.187762)
				)
			)
		)
		(zone
			(layer "F.Cu")
			(hatch none 0.5)
			(connect_pads
				(clearance 0)
			)
			(min_thickness 0.25)
			(keepout
				(tracks allowed)
				(vias not_allowed)
				(pads allowed)
				(copperpour not_allowed)
				(footprints allowed)
			)
			(placement
				(enabled no)
				(sheetname "")
			)
			(fill
				(thermal_gap 0.5)
				(thermal_bridge_width 0.5)
				(island_removal_mode 0)
			)
			(polygon
				(pts
					(xy 33.082992 -486.156762) (xy 30.060392 -486.156762) (xy 30.060392 -483.261162) (xy 30.060392 -482.930962)
					(xy 33.082992 -482.930962) (xy 33.082992 -483.261162)
				)
			)
		)
	)
	(footprint ""
		(layer "F.Cu")
		(at 21.6408 -290.322 -90)
		(property "Reference" "C44"
			(at 0 0 270)
			(layer "F.SilkS")
			(hide yes)
			(effects
				(font
					(size 1.27 1.27)
				)
			)
		)
		(property "Value" "SCD1U16V2KX-3GP"
			(at 1.1811 -2.7051 270)
			(unlocked yes)
			(layer "F.Fab")
			(hide yes)
			(effects
				(font
					(size 1.016 1.016)
					(thickness 0.1524)
				)
			)
		)
		(property "Device Type" "C402H22"
			(at 1.1811 -4.2291 270)
			(unlocked yes)
			(layer "F.Fab")
			(hide yes)
			(effects
				(font
					(size 1.016 1.016)
					(thickness 0.1524)
				)
			)
		)
		(duplicate_pad_numbers_are_jumpers no)
		(fp_rect
			(start -0.4318 0.9525)
			(end 0.4318 -0.9525)
			(stroke
				(width 0)
				(type default)
			)
			(fill no)
			(layer "F.CrtYd")
		)
		(fp_rect
			(start -0.4318 0.9525)
			(end 0.4318 -0.9525)
			(stroke
				(width 0)
				(type default)
			)
			(fill no)
			(layer "F.Fab")
		)
		(pad "1" smd custom
			(at 0 -0.4445 270)
			(size 0.1524 0.1524)
			(layers "F.Cu" "F.Mask" "F.Paste")
			(net "FAN_TACH4")
			(options
				(clearance outline)
				(anchor circle)
			)
			(primitives
				(gr_poly
					(pts
						(arc
							(start 0.3048 -0.2032)
							(mid 0.275042 -0.275042)
							(end 0.2032 -0.3048)
						)
						(arc
							(start -0.2032 -0.3048)
							(mid -0.275042 -0.275042)
							(end -0.3048 -0.2032)
						)
						(arc
							(start -0.3048 0.2032)
							(mid -0.275042 0.275042)
							(end -0.2032 0.3048)
						)
						(arc
							(start 0.2032 0.3048)
							(mid 0.275042 0.275042)
							(end 0.3048 0.2032)
						)
					)
					(width 0)
					(fill yes)
				)
			)
		)
		(pad "2" smd custom
			(at 0 0.4445 270)
			(size 0.1524 0.1524)
			(layers "F.Cu" "F.Mask" "F.Paste")
			(net "GND")
			(options
				(clearance outline)
				(anchor circle)
			)
			(primitives
				(gr_poly
					(pts
						(arc
							(start 0.3048 -0.2032)
							(mid 0.275042 -0.275042)
							(end 0.2032 -0.3048)
						)
						(arc
							(start -0.2032 -0.3048)
							(mid -0.275042 -0.275042)
							(end -0.3048 -0.2032)
						)
						(arc
							(start -0.3048 0.2032)
							(mid -0.275042 0.275042)
							(end -0.2032 0.3048)
						)
						(arc
							(start 0.2032 0.3048)
							(mid 0.275042 0.275042)
							(end 0.3048 0.2032)
						)
					)
					(width 0)
					(fill yes)
				)
			)
		)
	)
	(footprint ""
		(layer "F.Cu")
		(at 12.2428 -54.2036 90)
		(property "Reference" "R62"
			(at 0 0 90)
			(layer "F.SilkS")
			(hide yes)
			(effects
				(font
					(size 1.27 1.27)
				)
			)
		)
		(property "Value" "0R2J-2-GP"
			(at 0.064008 -3.993896 90)
			(unlocked yes)
			(layer "F.Fab")
			(hide yes)
			(effects
				(font
					(size 1.016 1.016)
					(thickness 0.1524)
				)
			)
		)
		(property "Device Type" "R402H16"
			(at 0.064008 -5.517896 90)
			(unlocked yes)
			(layer "F.Fab")
			(hide yes)
			(effects
				(font
					(size 1.016 1.016)
					(thickness 0.1524)
				)
			)
		)
		(duplicate_pad_numbers_are_jumpers no)
		(fp_line
			(start 0.508 -0.9398)
			(end -0.508 -0.9398)
			(stroke
				(width 0.1524)
				(type default)
			)
			(layer "F.SilkS")
		)
		(fp_line
			(start -0.508 -0.9398)
			(end -0.508 0.9398)
			(stroke
				(width 0.1524)
				(type default)
			)
			(layer "F.SilkS")
		)
		(fp_rect
			(start -0.508 0.9398)
			(end 0.508 -0.9398)
			(stroke
				(width 0)
				(type default)
			)
			(fill no)
			(layer "F.CrtYd")
		)
		(fp_rect
			(start -0.508 0.9398)
			(end 0.508 -0.9398)
			(stroke
				(width 0)
				(type default)
			)
			(fill no)
			(layer "F.Fab")
		)
		(pad "1" smd custom
			(at 0 -0.4445 90)
			(size 0.1397 0.1397)
			(layers "F.Cu" "F.Mask" "F.Paste")
			(net "SELF_TRAY_PRESENT_UPPER")
			(options
				(clearance outline)
				(anchor circle)
			)
			(primitives
				(gr_poly
					(pts
						(arc
							(start -0.1778 -0.2794)
							(mid -0.249642 -0.249642)
							(end -0.2794 -0.1778)
						)
						(arc
							(start -0.2794 0.1778)
							(mid -0.249642 0.249642)
							(end -0.1778 0.2794)
						)
						(arc
							(start 0.1778 0.2794)
							(mid 0.249642 0.249642)
							(end 0.2794 0.1778)
						)
						(arc
							(start 0.2794 -0.1778)
							(mid 0.249642 -0.249642)
							(end 0.1778 -0.2794)
						)
					)
					(width 0)
					(fill yes)
				)
			)
		)
		(pad "2" smd custom
			(at 0 0.4445 90)
			(size 0.1397 0.1397)
			(layers "F.Cu" "F.Mask" "F.Paste")
			(net "PEER_TRAY PRESENT_LOWER")
			(options
				(clearance outline)
				(anchor circle)
			)
			(primitives
				(gr_poly
					(pts
						(arc
							(start -0.1778 -0.2794)
							(mid -0.249642 -0.249642)
							(end -0.2794 -0.1778)
						)
						(arc
							(start -0.2794 0.1778)
							(mid -0.249642 0.249642)
							(end -0.1778 0.2794)
						)
						(arc
							(start 0.1778 0.2794)
							(mid 0.249642 0.249642)
							(end 0.2794 0.1778)
						)
						(arc
							(start 0.2794 -0.1778)
							(mid 0.249642 -0.249642)
							(end 0.1778 -0.2794)
						)
					)
					(width 0)
					(fill yes)
				)
			)
		)
	)
	(footprint ""
		(layer "F.Cu")
		(at 39.243 -174.117)
		(property "Reference" "PR44"
			(at 0 0 0)
			(layer "F.SilkS")
			(hide yes)
			(effects
				(font
					(size 1.27 1.27)
				)
			)
		)
		(property "Value" "1KR2F-3-GP"
			(at 0.064008 -3.993896 0)
			(unlocked yes)
			(layer "F.Fab")
			(hide yes)
			(effects
				(font
					(size 1.016 1.016)
					(thickness 0.1524)
				)
			)
		)
		(property "Device Type" "R402H16"
			(at 0.064008 -5.517896 0)
			(unlocked yes)
			(layer "F.Fab")
			(hide yes)
			(effects
				(font
					(size 1.016 1.016)
					(thickness 0.1524)
				)
			)
		)
		(duplicate_pad_numbers_are_jumpers no)
		(fp_line
			(start -0.508 -0.9398)
			(end -0.508 0.9398)
			(stroke
				(width 0.1524)
				(type default)
			)
			(layer "F.SilkS")
		)
		(fp_line
			(start 0.508 -0.9398)
			(end -0.508 -0.9398)
			(stroke
				(width 0.1524)
				(type default)
			)
			(layer "F.SilkS")
		)
		(fp_rect
			(start -0.508 0.9398)
			(end 0.508 -0.9398)
			(stroke
				(width 0)
				(type default)
			)
			(fill no)
			(layer "F.CrtYd")
		)
		(fp_rect
			(start -0.508 0.9398)
			(end 0.508 -0.9398)
			(stroke
				(width 0)
				(type default)
			)
			(fill no)
			(layer "F.Fab")
		)
		(pad "1" smd custom
			(at 0 -0.4445)
			(size 0.1397 0.1397)
			(layers "F.Cu" "F.Mask" "F.Paste")
			(net "TEMP_ALM#")
			(options
				(clearance outline)
				(anchor circle)
			)
			(primitives
				(gr_poly
					(pts
						(arc
							(start -0.1778 -0.2794)
							(mid -0.249642 -0.249642)
							(end -0.2794 -0.1778)
						)
						(arc
							(start -0.2794 0.1778)
							(mid -0.249642 0.249642)
							(end -0.1778 0.2794)
						)
						(arc
							(start 0.1778 0.2794)
							(mid 0.249642 0.249642)
							(end 0.2794 0.1778)
						)
						(arc
							(start 0.2794 -0.1778)
							(mid 0.249642 -0.249642)
							(end 0.1778 -0.2794)
						)
					)
					(width 0)
					(fill yes)
				)
			)
		)
		(pad "2" smd custom
			(at 0 0.4445)
			(size 0.1397 0.1397)
			(layers "F.Cu" "F.Mask" "F.Paste")
			(net "TEMP_ALM#_IN")
			(options
				(clearance outline)
				(anchor circle)
			)
			(primitives
				(gr_poly
					(pts
						(arc
							(start -0.1778 -0.2794)
							(mid -0.249642 -0.249642)
							(end -0.2794 -0.1778)
						)
						(arc
							(start -0.2794 0.1778)
							(mid -0.249642 0.249642)
							(end -0.1778 0.2794)
						)
						(arc
							(start 0.1778 0.2794)
							(mid 0.249642 0.249642)
							(end 0.2794 0.1778)
						)
						(arc
							(start 0.2794 -0.1778)
							(mid 0.249642 -0.249642)
							(end 0.1778 -0.2794)
						)
					)
					(width 0)
					(fill yes)
				)
			)
		)
	)
	(footprint ""
		(layer "F.Cu")
		(at 17.91589 -175.540924 180)
		(property "Reference" "C10"
			(at 0 0 180)
			(layer "F.SilkS")
			(hide yes)
			(effects
				(font
					(size 1.27 1.27)
				)
			)
		)
		(property "Value" "SCD1U50V3KX-GP"
			(at 0 -2.8194 180)
			(unlocked yes)
			(layer "F.Fab")
			(hide yes)
			(effects
				(font
					(size 1.016 1.016)
					(thickness 0.1524)
				)
			)
		)
		(property "Device Type" "C603H36"
			(at 0 -4.3434 180)
			(unlocked yes)
			(layer "F.Fab")
			(hide yes)
			(effects
				(font
					(size 1.016 1.016)
					(thickness 0.1524)
				)
			)
		)
		(duplicate_pad_numbers_are_jumpers no)
		(fp_line
			(start 0.508 0)
			(end -0.508 0)
			(stroke
				(width 0.2032)
				(type default)
			)
			(layer "F.SilkS")
		)
		(fp_rect
			(start -0.5842 1.3335)
			(end 0.5842 -1.3335)
			(stroke
				(width 0)
				(type default)
			)
			(fill no)
			(layer "F.CrtYd")
		)
		(fp_rect
			(start -0.5842 1.3335)
			(end 0.5842 -1.3335)
			(stroke
				(width 0)
				(type default)
			)
			(fill no)
			(layer "F.Fab")
		)
		(pad "1" smd custom
			(at 0 -0.762 180)
			(size 0.2159 0.2159)
			(layers "F.Cu" "F.Mask" "F.Paste")
			(net "P3V3")
			(options
				(clearance outline)
				(anchor circle)
			)
			(primitives
				(gr_poly
					(pts
						(arc
							(start -0.3302 -0.4318)
							(mid -0.402042 -0.402042)
							(end -0.4318 -0.3302)
						)
						(arc
							(start -0.4318 0.3302)
							(mid -0.402042 0.402042)
							(end -0.3302 0.4318)
						)
						(arc
							(start 0.3302 0.4318)
							(mid 0.402042 0.402042)
							(end 0.4318 0.3302)
						)
						(arc
							(start 0.4318 -0.3302)
							(mid 0.402042 -0.402042)
							(end 0.3302 -0.4318)
						)
					)
					(width 0)
					(fill yes)
				)
			)
		)
		(pad "2" smd custom
			(at 0 0.762 180)
			(size 0.2159 0.2159)
			(layers "F.Cu" "F.Mask" "F.Paste")
			(net "GND")
			(options
				(clearance outline)
				(anchor circle)
			)
			(primitives
				(gr_poly
					(pts
						(arc
							(start -0.3302 -0.4318)
							(mid -0.402042 -0.402042)
							(end -0.4318 -0.3302)
						)
						(arc
							(start -0.4318 0.3302)
							(mid -0.402042 0.402042)
							(end -0.3302 0.4318)
						)
						(arc
							(start 0.3302 0.4318)
							(mid 0.402042 0.402042)
							(end 0.4318 0.3302)
						)
						(arc
							(start 0.4318 -0.3302)
							(mid 0.402042 -0.402042)
							(end 0.3302 -0.4318)
						)
					)
					(width 0)
					(fill yes)
				)
			)
		)
	)
	(footprint ""
		(layer "F.Cu")
		(at 39.123366 -156.22651 90)
		(property "Reference" "R6"
			(at 0 0 90)
			(layer "F.SilkS")
			(hide yes)
			(effects
				(font
					(size 1.27 1.27)
				)
			)
		)
		(property "Value" "0R2J-2-GP"
			(at 0.064008 -3.993896 90)
			(unlocked yes)
			(layer "F.Fab")
			(hide yes)
			(effects
				(font
					(size 1.016 1.016)
					(thickness 0.1524)
				)
			)
		)
		(property "Device Type" "R402H16"
			(at 0.064008 -5.517896 90)
			(unlocked yes)
			(layer "F.Fab")
			(hide yes)
			(effects
				(font
					(size 1.016 1.016)
					(thickness 0.1524)
				)
			)
		)
		(duplicate_pad_numbers_are_jumpers no)
		(fp_line
			(start 0.508 -0.9398)
			(end -0.508 -0.9398)
			(stroke
				(width 0.1524)
				(type default)
			)
			(layer "F.SilkS")
		)
		(fp_line
			(start -0.508 -0.9398)
			(end -0.508 0.9398)
			(stroke
				(width 0.1524)
				(type default)
			)
			(layer "F.SilkS")
		)
		(fp_rect
			(start -0.508 0.9398)
			(end 0.508 -0.9398)
			(stroke
				(width 0)
				(type default)
			)
			(fill no)
			(layer "F.CrtYd")
		)
		(fp_rect
			(start -0.508 0.9398)
			(end 0.508 -0.9398)
			(stroke
				(width 0)
				(type default)
			)
			(fill no)
			(layer "F.Fab")
		)
		(pad "1" smd custom
			(at 0 -0.4445 90)
			(size 0.1397 0.1397)
			(layers "F.Cu" "F.Mask" "F.Paste")
			(net "NCT7904_SMI")
			(options
				(clearance outline)
				(anchor circle)
			)
			(primitives
				(gr_poly
					(pts
						(arc
							(start -0.1778 -0.2794)
							(mid -0.249642 -0.249642)
							(end -0.2794 -0.1778)
						)
						(arc
							(start -0.2794 0.1778)
							(mid -0.249642 0.249642)
							(end -0.1778 0.2794)
						)
						(arc
							(start 0.1778 0.2794)
							(mid 0.249642 0.249642)
							(end 0.2794 0.1778)
						)
						(arc
							(start 0.2794 -0.1778)
							(mid 0.249642 -0.249642)
							(end 0.1778 -0.2794)
						)
					)
					(width 0)
					(fill yes)
				)
			)
		)
		(pad "2" smd custom
			(at 0 0.4445 90)
			(size 0.1397 0.1397)
			(layers "F.Cu" "F.Mask" "F.Paste")
			(net "TEMP_ALM#")
			(options
				(clearance outline)
				(anchor circle)
			)
			(primitives
				(gr_poly
					(pts
						(arc
							(start -0.1778 -0.2794)
							(mid -0.249642 -0.249642)
							(end -0.2794 -0.1778)
						)
						(arc
							(start -0.2794 0.1778)
							(mid -0.249642 0.249642)
							(end -0.1778 0.2794)
						)
						(arc
							(start 0.1778 0.2794)
							(mid 0.249642 0.249642)
							(end 0.2794 0.1778)
						)
						(arc
							(start 0.2794 -0.1778)
							(mid 0.249642 -0.249642)
							(end 0.1778 -0.2794)
						)
					)
					(width 0)
					(fill yes)
				)
			)
		)
	)
	(footprint ""
		(layer "F.Cu")
		(at 35.3314 -254.3556 180)
		(property "Reference" "R107"
			(at 0 0 180)
			(layer "F.SilkS")
			(hide yes)
			(effects
				(font
					(size 1.27 1.27)
				)
			)
		)
		(property "Value" "0R2J-2-GP"
			(at 0.064008 -3.993896 180)
			(unlocked yes)
			(layer "F.Fab")
			(hide yes)
			(effects
				(font
					(size 1.016 1.016)
					(thickness 0.1524)
				)
			)
		)
		(property "Device Type" "R402H16"
			(at 0.064008 -5.517896 180)
			(unlocked yes)
			(layer "F.Fab")
			(hide yes)
			(effects
				(font
					(size 1.016 1.016)
					(thickness 0.1524)
				)
			)
		)
		(duplicate_pad_numbers_are_jumpers no)
		(fp_line
			(start 0.508 -0.9398)
			(end -0.508 -0.9398)
			(stroke
				(width 0.1524)
				(type default)
			)
			(layer "F.SilkS")
		)
		(fp_line
			(start -0.508 -0.9398)
			(end -0.508 0.9398)
			(stroke
				(width 0.1524)
				(type default)
			)
			(layer "F.SilkS")
		)
		(fp_rect
			(start -0.508 0.9398)
			(end 0.508 -0.9398)
			(stroke
				(width 0)
				(type default)
			)
			(fill no)
			(layer "F.CrtYd")
		)
		(fp_rect
			(start -0.508 0.9398)
			(end 0.508 -0.9398)
			(stroke
				(width 0)
				(type default)
			)
			(fill no)
			(layer "F.Fab")
		)
		(pad "1" smd custom
			(at 0 -0.4445 180)
			(size 0.1397 0.1397)
			(layers "F.Cu" "F.Mask" "F.Paste")
			(net "I2C_C_SCL_LEDDRV")
			(options
				(clearance outline)
				(anchor circle)
			)
			(primitives
				(gr_poly
					(pts
						(arc
							(start -0.1778 -0.2794)
							(mid -0.249642 -0.249642)
							(end -0.2794 -0.1778)
						)
						(arc
							(start -0.2794 0.1778)
							(mid -0.249642 0.249642)
							(end -0.1778 0.2794)
						)
						(arc
							(start 0.1778 0.2794)
							(mid 0.249642 0.249642)
							(end 0.2794 0.1778)
						)
						(arc
							(start 0.2794 -0.1778)
							(mid 0.249642 -0.249642)
							(end 0.1778 -0.2794)
						)
					)
					(width 0)
					(fill yes)
				)
			)
		)
		(pad "2" smd custom
			(at 0 0.4445 180)
			(size 0.1397 0.1397)
			(layers "F.Cu" "F.Mask" "F.Paste")
			(net "I2C_C_SCL")
			(options
				(clearance outline)
				(anchor circle)
			)
			(primitives
				(gr_poly
					(pts
						(arc
							(start -0.1778 -0.2794)
							(mid -0.249642 -0.249642)
							(end -0.2794 -0.1778)
						)
						(arc
							(start -0.2794 0.1778)
							(mid -0.249642 0.249642)
							(end -0.1778 0.2794)
						)
						(arc
							(start 0.1778 0.2794)
							(mid 0.249642 0.249642)
							(end 0.2794 0.1778)
						)
						(arc
							(start 0.2794 -0.1778)
							(mid 0.249642 -0.249642)
							(end 0.1778 -0.2794)
						)
					)
					(width 0)
					(fill yes)
				)
			)
		)
	)
	(footprint ""
		(layer "F.Cu")
		(at 32.85109 -167.723566 180)
		(property "Reference" "R7"
			(at 0 0 180)
			(layer "F.SilkS")
			(hide yes)
			(effects
				(font
					(size 1.27 1.27)
				)
			)
		)
		(property "Value" "0R2J-2-GP"
			(at 0.064008 -3.993896 180)
			(unlocked yes)
			(layer "F.Fab")
			(hide yes)
			(effects
				(font
					(size 1.016 1.016)
					(thickness 0.1524)
				)
			)
		)
		(property "Device Type" "R402H16"
			(at 0.064008 -5.517896 180)
			(unlocked yes)
			(layer "F.Fab")
			(hide yes)
			(effects
				(font
					(size 1.016 1.016)
					(thickness 0.1524)
				)
			)
		)
		(duplicate_pad_numbers_are_jumpers no)
		(fp_line
			(start 0.508 -0.9398)
			(end -0.508 -0.9398)
			(stroke
				(width 0.1524)
				(type default)
			)
			(layer "F.SilkS")
		)
		(fp_line
			(start -0.508 -0.9398)
			(end -0.508 0.9398)
			(stroke
				(width 0.1524)
				(type default)
			)
			(layer "F.SilkS")
		)
		(fp_rect
			(start -0.508 0.9398)
			(end 0.508 -0.9398)
			(stroke
				(width 0)
				(type default)
			)
			(fill no)
			(layer "F.CrtYd")
		)
		(fp_rect
			(start -0.508 0.9398)
			(end 0.508 -0.9398)
			(stroke
				(width 0)
				(type default)
			)
			(fill no)
			(layer "F.Fab")
		)
		(pad "1" smd custom
			(at 0 -0.4445 180)
			(size 0.1397 0.1397)
			(layers "F.Cu" "F.Mask" "F.Paste")
			(net "NCT7904_RSTOUT")
			(options
				(clearance outline)
				(anchor circle)
			)
			(primitives
				(gr_poly
					(pts
						(arc
							(start -0.1778 -0.2794)
							(mid -0.249642 -0.249642)
							(end -0.2794 -0.1778)
						)
						(arc
							(start -0.2794 0.1778)
							(mid -0.249642 0.249642)
							(end -0.1778 0.2794)
						)
						(arc
							(start 0.1778 0.2794)
							(mid 0.249642 0.249642)
							(end 0.2794 0.1778)
						)
						(arc
							(start 0.2794 -0.1778)
							(mid 0.249642 -0.249642)
							(end 0.1778 -0.2794)
						)
					)
					(width 0)
					(fill yes)
				)
			)
		)
		(pad "2" smd custom
			(at 0 0.4445 180)
			(size 0.1397 0.1397)
			(layers "F.Cu" "F.Mask" "F.Paste")
			(net "TEMP_ALM#")
			(options
				(clearance outline)
				(anchor circle)
			)
			(primitives
				(gr_poly
					(pts
						(arc
							(start -0.1778 -0.2794)
							(mid -0.249642 -0.249642)
							(end -0.2794 -0.1778)
						)
						(arc
							(start -0.2794 0.1778)
							(mid -0.249642 0.249642)
							(end -0.1778 0.2794)
						)
						(arc
							(start 0.1778 0.2794)
							(mid 0.249642 0.249642)
							(end 0.2794 0.1778)
						)
						(arc
							(start 0.2794 -0.1778)
							(mid 0.249642 -0.249642)
							(end 0.1778 -0.2794)
						)
					)
					(width 0)
					(fill yes)
				)
			)
		)
	)
	(footprint ""
		(layer "F.Cu")
		(at 19.431 -111.76)
		(property "Reference" "PQ11"
			(at 0 0 0)
			(layer "F.SilkS")
			(hide yes)
			(effects
				(font
					(size 1.27 1.27)
				)
			)
		)
		(property "Value" "PH0925CL-GP"
			(at -4.2799 -0.4572 0)
			(unlocked yes)
			(layer "F.Fab")
			(hide yes)
			(effects
				(font
					(size 1.016 1.016)
					(thickness 0.1524)
				)
			)
		)
		(property "Device Type" "LFPAK-5PH48-U"
			(at -4.2799 -1.9812 0)
			(unlocked yes)
			(layer "F.Fab")
			(hide yes)
			(effects
				(font
					(size 1.016 1.016)
					(thickness 0.1524)
				)
			)
		)
		(duplicate_pad_numbers_are_jumpers no)
		(fp_line
			(start -2.7559 -6.5532)
			(end -2.7559 1.0668)
			(stroke
				(width 0.1524)
				(type default)
			)
			(layer "F.SilkS")
		)
		(fp_line
			(start -2.7559 1.0668)
			(end 2.7559 1.0668)
			(stroke
				(width 0.1524)
				(type default)
			)
			(layer "F.SilkS")
		)
		(fp_line
			(start -1.7272 1.1684)
			(end -2.1082 1.1684)
			(stroke
				(width 0.3302)
				(type default)
			)
			(layer "F.SilkS")
		)
		(fp_line
			(start 2.7559 -6.5532)
			(end -2.7559 -6.5532)
			(stroke
				(width 0.1524)
				(type default)
			)
			(layer "F.SilkS")
		)
		(fp_line
			(start 2.7559 1.0668)
			(end 2.7559 -6.5532)
			(stroke
				(width 0.1524)
				(type default)
			)
			(layer "F.SilkS")
		)
		(fp_poly
			(pts
				(xy -2.3368 1.5748) (xy -1.905 1.143) (xy -1.4732 1.5748)
			)
			(stroke
				(width 0)
				(type default)
			)
			(fill yes)
			(layer "F.SilkS")
		)
		(fp_poly
			(pts
				(xy -2.5019 -4.02971) (xy -0.3302 -4.02971) (xy -0.3302 -6.30301) (xy -2.5019 -6.30301)
			)
			(stroke
				(width 0)
				(type default)
			)
			(fill yes)
			(layer "F.Paste")
		)
		(fp_poly
			(pts
				(xy -2.5019 -1.09601) (xy -0.3302 -1.09601) (xy -0.3302 -3.36931) (xy -2.5019 -3.36931)
			)
			(stroke
				(width 0)
				(type default)
			)
			(fill yes)
			(layer "F.Paste")
		)
		(fp_poly
			(pts
				(xy 0.3302 -4.02971) (xy 2.5019 -4.02971) (xy 2.5019 -6.30301) (xy 0.3302 -6.30301)
			)
			(stroke
				(width 0)
				(type default)
			)
			(fill yes)
			(layer "F.Paste")
		)
		(fp_poly
			(pts
				(xy 0.3302 -1.09601) (xy 2.5019 -1.09601) (xy 2.5019 -3.36931) (xy 0.3302 -3.36931)
			)
			(stroke
				(width 0)
				(type default)
			)
			(fill yes)
			(layer "F.Paste")
		)
		(fp_rect
			(start -2.4511 0.3048)
			(end 2.4511 -5.6896)
			(stroke
				(width 0)
				(type default)
			)
			(fill no)
			(layer "F.CrtYd")
		)
		(fp_poly
			(pts
				(xy -3.0099 1.3208) (xy -3.0099 -6.8072) (xy 3.0099 -6.8072) (xy 3.0099 -1.016) (xy 2.4511 -1.016)
				(xy 2.4511 -5.6896) (xy -2.4511 -5.6896) (xy -2.4511 0.3048) (xy 2.4511 0.3048) (xy 2.4511 -1.0033)
				(xy 3.0099 -1.0033) (xy 3.0099 1.3208)
			)
			(stroke
				(width 0)
				(type default)
			)
			(fill no)
			(layer "F.CrtYd")
		)
		(fp_rect
			(start -3.0099 1.3208)
			(end 3.0099 -6.8072)
			(stroke
				(width 0)
				(type default)
			)
			(fill no)
			(layer "F.Fab")
		)
		(pad "1" smd rect
			(at -1.905 0)
			(size 0.762 1.6256)
			(layers "F.Cu" "F.Mask" "F.Paste")
			(net "P12VU")
		)
		(pad "2" smd rect
			(at -0.635 0)
			(size 0.762 1.6256)
			(layers "F.Cu" "F.Mask" "F.Paste")
			(net "P12VU")
		)
		(pad "3" smd rect
			(at 0.635 0)
			(size 0.762 1.6256)
			(layers "F.Cu" "F.Mask" "F.Paste")
			(net "P12VU")
		)
		(pad "4" smd rect
			(at 1.905 0)
			(size 0.762 1.6256)
			(layers "F.Cu" "F.Mask" "F.Paste")
			(net "P12VU_2490_GATE_DRV_2")
		)
		(pad "5" smd rect
			(at 0 -3.69951)
			(size 5.0038 5.207)
			(layers "F.Cu" "F.Mask" "F.Paste")
			(net "P12VU_NET")
		)
	)
	(footprint ""
		(layer "F.Cu")
		(at 6.1214 -174.7774 180)
		(property "Reference" "C53"
			(at 0 0 180)
			(layer "F.SilkS")
			(hide yes)
			(effects
				(font
					(size 1.27 1.27)
				)
			)
		)
		(property "Value" "SC1U16V3KX-5GP"
			(at 0 -2.8194 180)
			(unlocked yes)
			(layer "F.Fab")
			(hide yes)
			(effects
				(font
					(size 1.016 1.016)
					(thickness 0.1524)
				)
			)
		)
		(property "Device Type" "C603H36"
			(at 0 -4.3434 180)
			(unlocked yes)
			(layer "F.Fab")
			(hide yes)
			(effects
				(font
					(size 1.016 1.016)
					(thickness 0.1524)
				)
			)
		)
		(duplicate_pad_numbers_are_jumpers no)
		(fp_line
			(start 0.508 0)
			(end -0.508 0)
			(stroke
				(width 0.2032)
				(type default)
			)
			(layer "F.SilkS")
		)
		(fp_rect
			(start -0.5842 1.3335)
			(end 0.5842 -1.3335)
			(stroke
				(width 0)
				(type default)
			)
			(fill no)
			(layer "F.CrtYd")
		)
		(fp_rect
			(start -0.5842 1.3335)
			(end 0.5842 -1.3335)
			(stroke
				(width 0)
				(type default)
			)
			(fill no)
			(layer "F.Fab")
		)
		(pad "1" smd custom
			(at 0 -0.762 180)
			(size 0.2159 0.2159)
			(layers "F.Cu" "F.Mask" "F.Paste")
			(net "P3V3")
			(options
				(clearance outline)
				(anchor circle)
			)
			(primitives
				(gr_poly
					(pts
						(arc
							(start -0.3302 -0.4318)
							(mid -0.402042 -0.402042)
							(end -0.4318 -0.3302)
						)
						(arc
							(start -0.4318 0.3302)
							(mid -0.402042 0.402042)
							(end -0.3302 0.4318)
						)
						(arc
							(start 0.3302 0.4318)
							(mid 0.402042 0.402042)
							(end 0.4318 0.3302)
						)
						(arc
							(start 0.4318 -0.3302)
							(mid 0.402042 -0.402042)
							(end 0.3302 -0.4318)
						)
					)
					(width 0)
					(fill yes)
				)
			)
		)
		(pad "2" smd custom
			(at 0 0.762 180)
			(size 0.2159 0.2159)
			(layers "F.Cu" "F.Mask" "F.Paste")
			(net "GND")
			(options
				(clearance outline)
				(anchor circle)
			)
			(primitives
				(gr_poly
					(pts
						(arc
							(start -0.3302 -0.4318)
							(mid -0.402042 -0.402042)
							(end -0.4318 -0.3302)
						)
						(arc
							(start -0.4318 0.3302)
							(mid -0.402042 0.402042)
							(end -0.3302 0.4318)
						)
						(arc
							(start 0.3302 0.4318)
							(mid 0.402042 0.402042)
							(end 0.4318 0.3302)
						)
						(arc
							(start 0.4318 -0.3302)
							(mid 0.402042 -0.402042)
							(end 0.3302 -0.4318)
						)
					)
					(width 0)
					(fill yes)
				)
			)
		)
	)
	(footprint ""
		(layer "F.Cu")
		(at 21.7678 -217.7288 90)
		(property "Reference" "R133"
			(at 0 0 90)
			(layer "F.SilkS")
			(hide yes)
			(effects
				(font
					(size 1.27 1.27)
				)
			)
		)
		(property "Value" "4K7R2F-GP"
			(at 0.064008 -3.993896 90)
			(unlocked yes)
			(layer "F.Fab")
			(hide yes)
			(effects
				(font
					(size 1.016 1.016)
					(thickness 0.1524)
				)
			)
		)
		(property "Device Type" "R402H16"
			(at 0.064008 -5.517896 90)
			(unlocked yes)
			(layer "F.Fab")
			(hide yes)
			(effects
				(font
					(size 1.016 1.016)
					(thickness 0.1524)
				)
			)
		)
		(duplicate_pad_numbers_are_jumpers no)
		(fp_line
			(start 0.508 -0.9398)
			(end -0.508 -0.9398)
			(stroke
				(width 0.1524)
				(type default)
			)
			(layer "F.SilkS")
		)
		(fp_line
			(start -0.508 -0.9398)
			(end -0.508 0.9398)
			(stroke
				(width 0.1524)
				(type default)
			)
			(layer "F.SilkS")
		)
		(fp_rect
			(start -0.508 0.9398)
			(end 0.508 -0.9398)
			(stroke
				(width 0)
				(type default)
			)
			(fill no)
			(layer "F.CrtYd")
		)
		(fp_rect
			(start -0.508 0.9398)
			(end 0.508 -0.9398)
			(stroke
				(width 0)
				(type default)
			)
			(fill no)
			(layer "F.Fab")
		)
		(pad "1" smd custom
			(at 0 -0.4445 90)
			(size 0.1397 0.1397)
			(layers "F.Cu" "F.Mask" "F.Paste")
			(net "P3V3")
			(options
				(clearance outline)
				(anchor circle)
			)
			(primitives
				(gr_poly
					(pts
						(arc
							(start -0.1778 -0.2794)
							(mid -0.249642 -0.249642)
							(end -0.2794 -0.1778)
						)
						(arc
							(start -0.2794 0.1778)
							(mid -0.249642 0.249642)
							(end -0.1778 0.2794)
						)
						(arc
							(start 0.1778 0.2794)
							(mid 0.249642 0.249642)
							(end 0.2794 0.1778)
						)
						(arc
							(start 0.2794 -0.1778)
							(mid 0.249642 -0.249642)
							(end 0.1778 -0.2794)
						)
					)
					(width 0)
					(fill yes)
				)
			)
		)
		(pad "2" smd custom
			(at 0 0.4445 90)
			(size 0.1397 0.1397)
			(layers "F.Cu" "F.Mask" "F.Paste")
			(net "PWM_OUT_FAN3")
			(options
				(clearance outline)
				(anchor circle)
			)
			(primitives
				(gr_poly
					(pts
						(arc
							(start -0.1778 -0.2794)
							(mid -0.249642 -0.249642)
							(end -0.2794 -0.1778)
						)
						(arc
							(start -0.2794 0.1778)
							(mid -0.249642 0.249642)
							(end -0.1778 0.2794)
						)
						(arc
							(start 0.1778 0.2794)
							(mid 0.249642 0.249642)
							(end 0.2794 0.1778)
						)
						(arc
							(start 0.2794 -0.1778)
							(mid 0.249642 -0.249642)
							(end 0.1778 -0.2794)
						)
					)
					(width 0)
					(fill yes)
				)
			)
		)
	)
	(footprint ""
		(layer "F.Cu")
		(at 45.522134 -155.83789 -90)
		(property "Reference" "L2"
			(at 0 0 270)
			(layer "F.SilkS")
			(hide yes)
			(effects
				(font
					(size 1.27 1.27)
				)
			)
		)
		(property "Value" "FCM1608CF-121T03-GP"
			(at -0.0254 -2.8956 270)
			(unlocked yes)
			(layer "F.Fab")
			(hide yes)
			(effects
				(font
					(size 1.016 1.016)
					(thickness 0.1524)
				)
			)
		)
		(property "Device Type" "L1608-UH38"
			(at -0.0254 -4.4196 270)
			(unlocked yes)
			(layer "F.Fab")
			(hide yes)
			(effects
				(font
					(size 1.016 1.016)
					(thickness 0.1524)
				)
			)
		)
		(duplicate_pad_numbers_are_jumpers no)
		(fp_line
			(start 0.254 0)
			(end -0.254 0)
			(stroke
				(width 0.2032)
				(type default)
			)
			(layer "F.SilkS")
		)
		(fp_rect
			(start -0.5842 1.3335)
			(end 0.5842 -1.3335)
			(stroke
				(width 0)
				(type default)
			)
			(fill no)
			(layer "F.CrtYd")
		)
		(fp_rect
			(start -0.5842 1.3335)
			(end 0.5842 -1.3335)
			(stroke
				(width 0)
				(type default)
			)
			(fill no)
			(layer "F.Fab")
		)
		(pad "1" smd custom
			(at 0 -0.762 270)
			(size 0.2159 0.2159)
			(layers "F.Cu" "F.Mask" "F.Paste")
			(net "P3V3")
			(options
				(clearance outline)
				(anchor circle)
			)
			(primitives
				(gr_poly
					(pts
						(arc
							(start -0.3302 -0.4318)
							(mid -0.402042 -0.402042)
							(end -0.4318 -0.3302)
						)
						(arc
							(start -0.4318 0.3302)
							(mid -0.402042 0.402042)
							(end -0.3302 0.4318)
						)
						(arc
							(start 0.3302 0.4318)
							(mid 0.402042 0.402042)
							(end 0.4318 0.3302)
						)
						(arc
							(start 0.4318 -0.3302)
							(mid 0.402042 -0.402042)
							(end 0.3302 -0.4318)
						)
					)
					(width 0)
					(fill yes)
				)
			)
		)
		(pad "2" smd custom
			(at 0 0.762 270)
			(size 0.2159 0.2159)
			(layers "F.Cu" "F.Mask" "F.Paste")
			(net "NCT7904_3VSB")
			(options
				(clearance outline)
				(anchor circle)
			)
			(primitives
				(gr_poly
					(pts
						(arc
							(start -0.3302 -0.4318)
							(mid -0.402042 -0.402042)
							(end -0.4318 -0.3302)
						)
						(arc
							(start -0.4318 0.3302)
							(mid -0.402042 0.402042)
							(end -0.3302 0.4318)
						)
						(arc
							(start 0.3302 0.4318)
							(mid 0.402042 0.402042)
							(end 0.4318 0.3302)
						)
						(arc
							(start 0.4318 -0.3302)
							(mid 0.402042 -0.402042)
							(end 0.3302 -0.4318)
						)
					)
					(width 0)
					(fill yes)
				)
			)
		)
	)
	(footprint ""
		(layer "F.Cu")
		(at 8.001 -417.9062 180)
		(property "Reference" "Q7"
			(at 0 0 180)
			(layer "F.SilkS")
			(hide yes)
			(effects
				(font
					(size 1.27 1.27)
				)
			)
		)
		(property "Value" "PMBS3904-1-GP"
			(at 0 -9.0932 180)
			(unlocked yes)
			(layer "F.Fab")
			(hide yes)
			(effects
				(font
					(size 1.016 1.016)
					(thickness 0.1524)
				)
			)
		)
		(property "Device Type" "SOT-23-10H44"
			(at 0 -10.6172 180)
			(unlocked yes)
			(layer "F.Fab")
			(hide yes)
			(effects
				(font
					(size 1.016 1.016)
					(thickness 0.1524)
				)
			)
		)
		(duplicate_pad_numbers_are_jumpers no)
		(fp_line
			(start 1.651 1.778)
			(end 1.651 -1.778)
			(stroke
				(width 0.1524)
				(type default)
			)
			(layer "F.SilkS")
		)
		(fp_line
			(start 1.651 -1.778)
			(end -1.651 -1.778)
			(stroke
				(width 0.1524)
				(type default)
			)
			(layer "F.SilkS")
		)
		(fp_line
			(start -0.635 1.8796)
			(end -1.7526 1.8796)
			(stroke
				(width 0.3302)
				(type default)
			)
			(layer "F.SilkS")
		)
		(fp_line
			(start -0.71628 2.15265)
			(end -1.26492 2.15265)
			(stroke
				(width 0.0127)
				(type default)
			)
			(layer "F.SilkS")
		)
		(fp_line
			(start -0.719074 2.145538)
			(end -1.265936 2.14122)
			(stroke
				(width 0.0127)
				(type default)
			)
			(layer "F.SilkS")
		)
		(fp_line
			(start -0.9906 1.86309)
			(end -0.701294 2.15265)
			(stroke
				(width 0.0127)
				(type default)
			)
			(layer "F.SilkS")
		)
		(fp_line
			(start -0.994156 1.8669)
			(end -0.987044 1.8669)
			(stroke
				(width 0.0127)
				(type default)
			)
			(layer "F.SilkS")
		)
		(fp_line
			(start -1.003808 1.876552)
			(end -0.977646 1.876552)
			(stroke
				(width 0.0127)
				(type default)
			)
			(layer "F.SilkS")
		)
		(fp_line
			(start -1.013206 1.88595)
			(end -0.967994 1.88595)
			(stroke
				(width 0.0127)
				(type default)
			)
			(layer "F.SilkS")
		)
		(fp_line
			(start -1.022858 1.895602)
			(end -0.958596 1.895602)
			(stroke
				(width 0.0127)
				(type default)
			)
			(layer "F.SilkS")
		)
		(fp_line
			(start -1.032256 1.905)
			(end -0.948944 1.905)
			(stroke
				(width 0.0127)
				(type default)
			)
			(layer "F.SilkS")
		)
		(fp_line
			(start -1.041908 1.914652)
			(end -0.939546 1.914652)
			(stroke
				(width 0.0127)
				(type default)
			)
			(layer "F.SilkS")
		)
		(fp_line
			(start -1.051306 1.92405)
			(end -0.929894 1.92405)
			(stroke
				(width 0.0127)
				(type default)
			)
			(layer "F.SilkS")
		)
		(fp_line
			(start -1.060958 1.933702)
			(end -0.920496 1.933702)
			(stroke
				(width 0.0127)
				(type default)
			)
			(layer "F.SilkS")
		)
		(fp_line
			(start -1.070356 1.9431)
			(end -0.910844 1.9431)
			(stroke
				(width 0.0127)
				(type default)
			)
			(layer "F.SilkS")
		)
		(fp_line
			(start -1.080008 1.952752)
			(end -0.901446 1.952752)
			(stroke
				(width 0.0127)
				(type default)
			)
			(layer "F.SilkS")
		)
		(fp_line
			(start -1.089406 1.96215)
			(end -0.891794 1.96215)
			(stroke
				(width 0.0127)
				(type default)
			)
			(layer "F.SilkS")
		)
		(fp_line
			(start -1.099058 1.971802)
			(end -0.882396 1.971802)
			(stroke
				(width 0.0127)
				(type default)
			)
			(layer "F.SilkS")
		)
		(fp_line
			(start -1.108456 1.9812)
			(end -0.872744 1.9812)
			(stroke
				(width 0.0127)
				(type default)
			)
			(layer "F.SilkS")
		)
		(fp_line
			(start -1.118108 1.990852)
			(end -0.863346 1.990852)
			(stroke
				(width 0.0127)
				(type default)
			)
			(layer "F.SilkS")
		)
		(fp_line
			(start -1.127506 2.00025)
			(end -0.853694 2.00025)
			(stroke
				(width 0.0127)
				(type default)
			)
			(layer "F.SilkS")
		)
		(fp_line
			(start -1.137158 2.009902)
			(end -0.844296 2.009902)
			(stroke
				(width 0.0127)
				(type default)
			)
			(layer "F.SilkS")
		)
		(fp_line
			(start -1.146556 2.0193)
			(end -0.834644 2.0193)
			(stroke
				(width 0.0127)
				(type default)
			)
			(layer "F.SilkS")
		)
		(fp_line
			(start -1.156208 2.028952)
			(end -0.825246 2.028952)
			(stroke
				(width 0.0127)
				(type default)
			)
			(layer "F.SilkS")
		)
		(fp_line
			(start -1.165606 2.03835)
			(end -0.815594 2.03835)
			(stroke
				(width 0.0127)
				(type default)
			)
			(layer "F.SilkS")
		)
		(fp_line
			(start -1.175258 2.048002)
			(end -0.806196 2.048002)
			(stroke
				(width 0.0127)
				(type default)
			)
			(layer "F.SilkS")
		)
		(fp_line
			(start -1.184656 2.0574)
			(end -0.796544 2.0574)
			(stroke
				(width 0.0127)
				(type default)
			)
			(layer "F.SilkS")
		)
		(fp_line
			(start -1.194308 2.067052)
			(end -0.787146 2.067052)
			(stroke
				(width 0.0127)
				(type default)
			)
			(layer "F.SilkS")
		)
		(fp_line
			(start -1.203706 2.07645)
			(end -0.777494 2.07645)
			(stroke
				(width 0.0127)
				(type default)
			)
			(layer "F.SilkS")
		)
		(fp_line
			(start -1.213358 2.086102)
			(end -0.768096 2.086102)
			(stroke
				(width 0.0127)
				(type default)
			)
			(layer "F.SilkS")
		)
		(fp_line
			(start -1.222756 2.0955)
			(end -0.758444 2.0955)
			(stroke
				(width 0.0127)
				(type default)
			)
			(layer "F.SilkS")
		)
		(fp_line
			(start -1.232408 2.105152)
			(end -0.749046 2.105152)
			(stroke
				(width 0.0127)
				(type default)
			)
			(layer "F.SilkS")
		)
		(fp_line
			(start -1.241806 2.11455)
			(end -0.739394 2.11455)
			(stroke
				(width 0.0127)
				(type default)
			)
			(layer "F.SilkS")
		)
		(fp_line
			(start -1.251458 2.124202)
			(end -0.729996 2.124202)
			(stroke
				(width 0.0127)
				(type default)
			)
			(layer "F.SilkS")
		)
		(fp_line
			(start -1.260856 2.1336)
			(end -0.720344 2.1336)
			(stroke
				(width 0.0127)
				(type default)
			)
			(layer "F.SilkS")
		)
		(fp_line
			(start -1.279144 2.15265)
			(end -0.701294 2.15265)
			(stroke
				(width 0.0127)
				(type default)
			)
			(layer "F.SilkS")
		)
		(fp_line
			(start -1.279398 2.152142)
			(end -0.9906 1.86309)
			(stroke
				(width 0.0127)
				(type default)
			)
			(layer "F.SilkS")
		)
		(fp_line
			(start -1.651 1.778)
			(end 1.651 1.778)
			(stroke
				(width 0.1524)
				(type default)
			)
			(layer "F.SilkS")
		)
		(fp_line
			(start -1.651 -1.778)
			(end -1.651 1.778)
			(stroke
				(width 0.1524)
				(type default)
			)
			(layer "F.SilkS")
		)
		(fp_line
			(start -1.7526 1.8796)
			(end -1.7526 0.9906)
			(stroke
				(width 0.3302)
				(type default)
			)
			(layer "F.SilkS")
		)
		(fp_poly
			(pts
				(xy -1.285748 2.159) (xy -1.285748 1.8796) (xy -1.778 1.8796) (xy -1.778 -1.8796) (xy 1.778 -1.8796)
				(xy 1.778 1.8796) (xy -0.694944 1.8796) (xy -0.694944 2.159)
			)
			(stroke
				(width 0)
				(type default)
			)
			(fill no)
			(layer "F.CrtYd")
		)
		(fp_poly
			(pts
				(xy -1.285748 2.159) (xy -1.285748 1.8796) (xy -1.778 1.8796) (xy -1.778 -1.8796) (xy 1.778 -1.8796)
				(xy 1.778 1.8796) (xy -0.694944 1.8796) (xy -0.694944 2.159)
			)
			(stroke
				(width 0)
				(type default)
			)
			(fill no)
			(layer "F.Fab")
		)
		(pad "1" smd rect
			(at -0.98425 0.9525 180)
			(size 0.762 1.143)
			(layers "F.Cu" "F.Mask" "F.Paste")
			(net "LED_DR_LED1_B")
		)
		(pad "2" smd rect
			(at 0.98425 0.9525 180)
			(size 0.762 1.143)
			(layers "F.Cu" "F.Mask" "F.Paste")
			(net "GND")
		)
		(pad "3" smd rect
			(at 0 -0.9525 180)
			(size 0.762 1.143)
			(layers "F.Cu" "F.Mask" "F.Paste")
			(net "LED_DR_LED1_BLUE")
		)
	)
	(footprint ""
		(layer "F.Cu")
		(at 14.8844 -46.5582 -90)
		(property "Reference" "R174"
			(at 0 0 270)
			(layer "F.SilkS")
			(hide yes)
			(effects
				(font
					(size 1.27 1.27)
				)
			)
		)
		(property "Value" "0R2J-2-GP"
			(at 0.064008 -3.993896 270)
			(unlocked yes)
			(layer "F.Fab")
			(hide yes)
			(effects
				(font
					(size 1.016 1.016)
					(thickness 0.1524)
				)
			)
		)
		(property "Device Type" "R402H16"
			(at 0.064008 -5.517896 270)
			(unlocked yes)
			(layer "F.Fab")
			(hide yes)
			(effects
				(font
					(size 1.016 1.016)
					(thickness 0.1524)
				)
			)
		)
		(duplicate_pad_numbers_are_jumpers no)
		(fp_line
			(start -0.508 -0.9398)
			(end -0.508 0.9398)
			(stroke
				(width 0.1524)
				(type default)
			)
			(layer "F.SilkS")
		)
		(fp_line
			(start 0.508 -0.9398)
			(end -0.508 -0.9398)
			(stroke
				(width 0.1524)
				(type default)
			)
			(layer "F.SilkS")
		)
		(fp_rect
			(start -0.508 0.9398)
			(end 0.508 -0.9398)
			(stroke
				(width 0)
				(type default)
			)
			(fill no)
			(layer "F.CrtYd")
		)
		(fp_rect
			(start -0.508 0.9398)
			(end 0.508 -0.9398)
			(stroke
				(width 0)
				(type default)
			)
			(fill no)
			(layer "F.Fab")
		)
		(pad "1" smd custom
			(at 0 -0.4445 270)
			(size 0.1397 0.1397)
			(layers "F.Cu" "F.Mask" "F.Paste")
			(net "SELF_2A_HB")
			(options
				(clearance outline)
				(anchor circle)
			)
			(primitives
				(gr_poly
					(pts
						(arc
							(start -0.1778 -0.2794)
							(mid -0.249642 -0.249642)
							(end -0.2794 -0.1778)
						)
						(arc
							(start -0.2794 0.1778)
							(mid -0.249642 0.249642)
							(end -0.1778 0.2794)
						)
						(arc
							(start 0.1778 0.2794)
							(mid 0.249642 0.249642)
							(end 0.2794 0.1778)
						)
						(arc
							(start 0.2794 -0.1778)
							(mid 0.249642 -0.249642)
							(end 0.1778 -0.2794)
						)
					)
					(width 0)
					(fill yes)
				)
			)
		)
		(pad "2" smd custom
			(at 0 0.4445 270)
			(size 0.1397 0.1397)
			(layers "F.Cu" "F.Mask" "F.Paste")
			(net "SEB_PEER_1A_HB")
			(options
				(clearance outline)
				(anchor circle)
			)
			(primitives
				(gr_poly
					(pts
						(arc
							(start -0.1778 -0.2794)
							(mid -0.249642 -0.249642)
							(end -0.2794 -0.1778)
						)
						(arc
							(start -0.2794 0.1778)
							(mid -0.249642 0.249642)
							(end -0.1778 0.2794)
						)
						(arc
							(start 0.1778 0.2794)
							(mid 0.249642 0.249642)
							(end 0.2794 0.1778)
						)
						(arc
							(start 0.2794 -0.1778)
							(mid 0.249642 -0.249642)
							(end 0.1778 -0.2794)
						)
					)
					(width 0)
					(fill yes)
				)
			)
		)
	)
	(footprint ""
		(layer "F.Cu")
		(at 33.71469 -150.730966 180)
		(property "Reference" "TP9"
			(at 0 0 180)
			(layer "F.SilkS")
			(hide yes)
			(effects
				(font
					(size 1.27 1.27)
				)
			)
		)
		(property "Value" "TPAD32-GP"
			(at 0 -3.166364 180)
			(unlocked yes)
			(layer "F.Fab")
			(hide yes)
			(effects
				(font
					(size 1.016 1.016)
					(thickness 0.1524)
				)
			)
		)
		(property "Device Type" "TPAD32"
			(at 0 -4.690618 180)
			(unlocked yes)
			(layer "F.Fab")
			(hide yes)
			(effects
				(font
					(size 1.016 1.016)
					(thickness 0.1524)
				)
			)
		)
		(duplicate_pad_numbers_are_jumpers no)
		(fp_poly
			(pts
				(arc
					(start 0.7112 0)
					(mid -0.7112 0)
					(end 0.7112 0)
				)
			)
			(stroke
				(width 0)
				(type default)
			)
			(fill no)
			(layer "F.CrtYd")
		)
		(fp_poly
			(pts
				(arc
					(start 0.7112 0)
					(mid -0.7112 0)
					(end 0.7112 0)
				)
			)
			(stroke
				(width 0)
				(type default)
			)
			(fill no)
			(layer "F.Fab")
		)
		(pad "1" smd circle
			(at 0 0 180)
			(size 0.8128 0.8128)
			(layers "F.Cu" "F.Mask" "F.Paste")
			(net "NCT7904_VSEN10")
		)
	)
	(footprint ""
		(layer "F.Cu")
		(at 12.2428 -55.2196 -90)
		(property "Reference" "R63"
			(at 0 0 270)
			(layer "F.SilkS")
			(hide yes)
			(effects
				(font
					(size 1.27 1.27)
				)
			)
		)
		(property "Value" "0R2J-2-GP"
			(at 0.064008 -3.993896 270)
			(unlocked yes)
			(layer "F.Fab")
			(hide yes)
			(effects
				(font
					(size 1.016 1.016)
					(thickness 0.1524)
				)
			)
		)
		(property "Device Type" "R402H16"
			(at 0.064008 -5.517896 270)
			(unlocked yes)
			(layer "F.Fab")
			(hide yes)
			(effects
				(font
					(size 1.016 1.016)
					(thickness 0.1524)
				)
			)
		)
		(duplicate_pad_numbers_are_jumpers no)
		(fp_line
			(start -0.508 -0.9398)
			(end -0.508 0.9398)
			(stroke
				(width 0.1524)
				(type default)
			)
			(layer "F.SilkS")
		)
		(fp_line
			(start 0.508 -0.9398)
			(end -0.508 -0.9398)
			(stroke
				(width 0.1524)
				(type default)
			)
			(layer "F.SilkS")
		)
		(fp_rect
			(start -0.508 0.9398)
			(end 0.508 -0.9398)
			(stroke
				(width 0)
				(type default)
			)
			(fill no)
			(layer "F.CrtYd")
		)
		(fp_rect
			(start -0.508 0.9398)
			(end 0.508 -0.9398)
			(stroke
				(width 0)
				(type default)
			)
			(fill no)
			(layer "F.Fab")
		)
		(pad "1" smd custom
			(at 0 -0.4445 270)
			(size 0.1397 0.1397)
			(layers "F.Cu" "F.Mask" "F.Paste")
			(net "SELF_TRAY_PRESENT_LOWER")
			(options
				(clearance outline)
				(anchor circle)
			)
			(primitives
				(gr_poly
					(pts
						(arc
							(start -0.1778 -0.2794)
							(mid -0.249642 -0.249642)
							(end -0.2794 -0.1778)
						)
						(arc
							(start -0.2794 0.1778)
							(mid -0.249642 0.249642)
							(end -0.1778 0.2794)
						)
						(arc
							(start 0.1778 0.2794)
							(mid 0.249642 0.249642)
							(end 0.2794 0.1778)
						)
						(arc
							(start 0.2794 -0.1778)
							(mid 0.249642 -0.249642)
							(end 0.1778 -0.2794)
						)
					)
					(width 0)
					(fill yes)
				)
			)
		)
		(pad "2" smd custom
			(at 0 0.4445 270)
			(size 0.1397 0.1397)
			(layers "F.Cu" "F.Mask" "F.Paste")
			(net "PEER_TRAY PRESENT_UPPER")
			(options
				(clearance outline)
				(anchor circle)
			)
			(primitives
				(gr_poly
					(pts
						(arc
							(start -0.1778 -0.2794)
							(mid -0.249642 -0.249642)
							(end -0.2794 -0.1778)
						)
						(arc
							(start -0.2794 0.1778)
							(mid -0.249642 0.249642)
							(end -0.1778 0.2794)
						)
						(arc
							(start 0.1778 0.2794)
							(mid 0.249642 0.249642)
							(end 0.2794 0.1778)
						)
						(arc
							(start 0.2794 -0.1778)
							(mid 0.249642 -0.249642)
							(end 0.1778 -0.2794)
						)
					)
					(width 0)
					(fill yes)
				)
			)
		)
	)
	(footprint ""
		(layer "F.Cu")
		(at 29.1084 -170.3324 90)
		(property "Reference" "R176"
			(at 0 0 90)
			(layer "F.SilkS")
			(hide yes)
			(effects
				(font
					(size 1.27 1.27)
				)
			)
		)
		(property "Value" "0R2J-2-GP"
			(at 0.064008 -3.993896 90)
			(unlocked yes)
			(layer "F.Fab")
			(hide yes)
			(effects
				(font
					(size 1.016 1.016)
					(thickness 0.1524)
				)
			)
		)
		(property "Device Type" "R402H16"
			(at 0.064008 -5.517896 90)
			(unlocked yes)
			(layer "F.Fab")
			(hide yes)
			(effects
				(font
					(size 1.016 1.016)
					(thickness 0.1524)
				)
			)
		)
		(duplicate_pad_numbers_are_jumpers no)
		(fp_line
			(start 0.508 -0.9398)
			(end -0.508 -0.9398)
			(stroke
				(width 0.1524)
				(type default)
			)
			(layer "F.SilkS")
		)
		(fp_line
			(start -0.508 -0.9398)
			(end -0.508 0.9398)
			(stroke
				(width 0.1524)
				(type default)
			)
			(layer "F.SilkS")
		)
		(fp_rect
			(start -0.508 0.9398)
			(end 0.508 -0.9398)
			(stroke
				(width 0)
				(type default)
			)
			(fill no)
			(layer "F.CrtYd")
		)
		(fp_rect
			(start -0.508 0.9398)
			(end 0.508 -0.9398)
			(stroke
				(width 0)
				(type default)
			)
			(fill no)
			(layer "F.Fab")
		)
		(pad "1" smd custom
			(at 0 -0.4445 90)
			(size 0.1397 0.1397)
			(layers "F.Cu" "F.Mask" "F.Paste")
			(net "PWM_OUT")
			(options
				(clearance outline)
				(anchor circle)
			)
			(primitives
				(gr_poly
					(pts
						(arc
							(start -0.1778 -0.2794)
							(mid -0.249642 -0.249642)
							(end -0.2794 -0.1778)
						)
						(arc
							(start -0.2794 0.1778)
							(mid -0.249642 0.249642)
							(end -0.1778 0.2794)
						)
						(arc
							(start 0.1778 0.2794)
							(mid 0.249642 0.249642)
							(end 0.2794 0.1778)
						)
						(arc
							(start 0.2794 -0.1778)
							(mid 0.249642 -0.249642)
							(end 0.1778 -0.2794)
						)
					)
					(width 0)
					(fill yes)
				)
			)
		)
		(pad "2" smd custom
			(at 0 0.4445 90)
			(size 0.1397 0.1397)
			(layers "F.Cu" "F.Mask" "F.Paste")
			(net "PWM_BUFFER_IN_FAN1_FAN2")
			(options
				(clearance outline)
				(anchor circle)
			)
			(primitives
				(gr_poly
					(pts
						(arc
							(start -0.1778 -0.2794)
							(mid -0.249642 -0.249642)
							(end -0.2794 -0.1778)
						)
						(arc
							(start -0.2794 0.1778)
							(mid -0.249642 0.249642)
							(end -0.1778 0.2794)
						)
						(arc
							(start 0.1778 0.2794)
							(mid 0.249642 0.249642)
							(end 0.2794 0.1778)
						)
						(arc
							(start 0.2794 -0.1778)
							(mid 0.249642 -0.249642)
							(end 0.1778 -0.2794)
						)
					)
					(width 0)
					(fill yes)
				)
			)
		)
	)
	(footprint ""
		(layer "F.Cu")
		(at 14.8844 -45.5422 90)
		(property "Reference" "R114"
			(at 0 0 90)
			(layer "F.SilkS")
			(hide yes)
			(effects
				(font
					(size 1.27 1.27)
				)
			)
		)
		(property "Value" "470R2F-GP"
			(at 0.064008 -3.993896 90)
			(unlocked yes)
			(layer "F.Fab")
			(hide yes)
			(effects
				(font
					(size 1.016 1.016)
					(thickness 0.1524)
				)
			)
		)
		(property "Device Type" "R402H16"
			(at 0.064008 -5.517896 90)
			(unlocked yes)
			(layer "F.Fab")
			(hide yes)
			(effects
				(font
					(size 1.016 1.016)
					(thickness 0.1524)
				)
			)
		)
		(duplicate_pad_numbers_are_jumpers no)
		(fp_line
			(start 0.508 -0.9398)
			(end -0.508 -0.9398)
			(stroke
				(width 0.1524)
				(type default)
			)
			(layer "F.SilkS")
		)
		(fp_line
			(start -0.508 -0.9398)
			(end -0.508 0.9398)
			(stroke
				(width 0.1524)
				(type default)
			)
			(layer "F.SilkS")
		)
		(fp_rect
			(start -0.508 0.9398)
			(end 0.508 -0.9398)
			(stroke
				(width 0)
				(type default)
			)
			(fill no)
			(layer "F.CrtYd")
		)
		(fp_rect
			(start -0.508 0.9398)
			(end 0.508 -0.9398)
			(stroke
				(width 0)
				(type default)
			)
			(fill no)
			(layer "F.Fab")
		)
		(pad "1" smd custom
			(at 0 -0.4445 90)
			(size 0.1397 0.1397)
			(layers "F.Cu" "F.Mask" "F.Paste")
			(net "SEB_PEER_1A_HB")
			(options
				(clearance outline)
				(anchor circle)
			)
			(primitives
				(gr_poly
					(pts
						(arc
							(start -0.1778 -0.2794)
							(mid -0.249642 -0.249642)
							(end -0.2794 -0.1778)
						)
						(arc
							(start -0.2794 0.1778)
							(mid -0.249642 0.249642)
							(end -0.1778 0.2794)
						)
						(arc
							(start 0.1778 0.2794)
							(mid 0.249642 0.249642)
							(end 0.2794 0.1778)
						)
						(arc
							(start 0.2794 -0.1778)
							(mid 0.249642 -0.249642)
							(end 0.1778 -0.2794)
						)
					)
					(width 0)
					(fill yes)
				)
			)
		)
		(pad "2" smd custom
			(at 0 0.4445 90)
			(size 0.1397 0.1397)
			(layers "F.Cu" "F.Mask" "F.Paste")
			(net "GND")
			(options
				(clearance outline)
				(anchor circle)
			)
			(primitives
				(gr_poly
					(pts
						(arc
							(start -0.1778 -0.2794)
							(mid -0.249642 -0.249642)
							(end -0.2794 -0.1778)
						)
						(arc
							(start -0.2794 0.1778)
							(mid -0.249642 0.249642)
							(end -0.1778 0.2794)
						)
						(arc
							(start 0.1778 0.2794)
							(mid 0.249642 0.249642)
							(end 0.2794 0.1778)
						)
						(arc
							(start 0.2794 -0.1778)
							(mid 0.249642 -0.249642)
							(end 0.1778 -0.2794)
						)
					)
					(width 0)
					(fill yes)
				)
			)
		)
	)
	(footprint ""
		(layer "F.Cu")
		(at 36.659566 -152.08631 90)
		(property "Reference" "TP14"
			(at 0 0 90)
			(layer "F.SilkS")
			(hide yes)
			(effects
				(font
					(size 1.27 1.27)
				)
			)
		)
		(property "Value" "TPAD32-GP"
			(at 0 -3.166364 90)
			(unlocked yes)
			(layer "F.Fab")
			(hide yes)
			(effects
				(font
					(size 1.016 1.016)
					(thickness 0.1524)
				)
			)
		)
		(property "Device Type" "TPAD32"
			(at 0 -4.690618 90)
			(unlocked yes)
			(layer "F.Fab")
			(hide yes)
			(effects
				(font
					(size 1.016 1.016)
					(thickness 0.1524)
				)
			)
		)
		(duplicate_pad_numbers_are_jumpers no)
		(fp_poly
			(pts
				(arc
					(start 0.7112 0)
					(mid -0.7112 0)
					(end 0.7112 0)
				)
			)
			(stroke
				(width 0)
				(type default)
			)
			(fill no)
			(layer "F.CrtYd")
		)
		(fp_poly
			(pts
				(arc
					(start 0.7112 0)
					(mid -0.7112 0)
					(end 0.7112 0)
				)
			)
			(stroke
				(width 0)
				(type default)
			)
			(fill no)
			(layer "F.Fab")
		)
		(pad "1" smd circle
			(at 0 0 90)
			(size 0.8128 0.8128)
			(layers "F.Cu" "F.Mask" "F.Paste")
			(net "NCT7904_VSEN14")
		)
	)
	(footprint ""
		(layer "F.Cu")
		(at 14.224 -157.353 180)
		(property "Reference" "R181"
			(at 0 0 180)
			(layer "F.SilkS")
			(hide yes)
			(effects
				(font
					(size 1.27 1.27)
				)
			)
		)
		(property "Value" "0R1206-PAD-1-GP"
			(at 0 -5.0292 180)
			(unlocked yes)
			(layer "F.Fab")
			(hide yes)
			(effects
				(font
					(size 1.016 1.016)
					(thickness 0.1524)
				)
			)
		)
		(property "Device Type" "0R1206-PAD-1"
			(at 0 -6.5532 180)
			(unlocked yes)
			(layer "F.Fab")
			(hide yes)
			(effects
				(font
					(size 1.016 1.016)
					(thickness 0.1524)
				)
			)
		)
		(duplicate_pad_numbers_are_jumpers no)
		(fp_line
			(start 1.016 2.2352)
			(end 1.016 -2.2352)
			(stroke
				(width 0.1524)
				(type default)
			)
			(layer "F.SilkS")
		)
		(fp_line
			(start 1.016 -2.2352)
			(end -1.016 -2.2352)
			(stroke
				(width 0.1524)
				(type default)
			)
			(layer "F.SilkS")
		)
		(fp_line
			(start -1.016 2.2352)
			(end 1.016 2.2352)
			(stroke
				(width 0.1524)
				(type default)
			)
			(layer "F.SilkS")
		)
		(fp_line
			(start -1.016 -2.2352)
			(end -1.016 2.2352)
			(stroke
				(width 0.1524)
				(type default)
			)
			(layer "F.SilkS")
		)
		(fp_rect
			(start -1.0922 2.3114)
			(end 1.0922 -2.3114)
			(stroke
				(width 0)
				(type default)
			)
			(fill no)
			(layer "F.CrtYd")
		)
		(fp_poly
			(pts
				(xy -1.0922 -2.3114) (xy 1.0922 -2.3114) (xy 1.0922 2.3114) (xy -1.0922 2.3114)
			)
			(stroke
				(width 0)
				(type default)
			)
			(fill no)
			(layer "F.Fab")
		)
		(pad "1" smd rect
			(at 0 -1.397 180)
			(size 1.651 2.0574)
			(drill
				(offset 0 0.3937)
			)
			(layers "F.Cu" "F.Mask" "F.Paste")
			(net "P12V_FAN5")
		)
		(pad "2" smd rect
			(at 0 1.397 180)
			(size 1.651 2.0574)
			(drill
				(offset 0 -0.3937)
			)
			(layers "F.Cu" "F.Mask" "F.Paste")
			(net "P12V")
		)
	)
	(footprint ""
		(layer "F.Cu")
		(at 30.3784 -210.8454 180)
		(property "Reference" "R139"
			(at 0 0 180)
			(layer "F.SilkS")
			(hide yes)
			(effects
				(font
					(size 1.27 1.27)
				)
			)
		)
		(property "Value" "0R2J-2-GP"
			(at 0.064008 -3.993896 180)
			(unlocked yes)
			(layer "F.Fab")
			(hide yes)
			(effects
				(font
					(size 1.016 1.016)
					(thickness 0.1524)
				)
			)
		)
		(property "Device Type" "R402H16"
			(at 0.064008 -5.517896 180)
			(unlocked yes)
			(layer "F.Fab")
			(hide yes)
			(effects
				(font
					(size 1.016 1.016)
					(thickness 0.1524)
				)
			)
		)
		(duplicate_pad_numbers_are_jumpers no)
		(fp_line
			(start 0.508 -0.9398)
			(end -0.508 -0.9398)
			(stroke
				(width 0.1524)
				(type default)
			)
			(layer "F.SilkS")
		)
		(fp_line
			(start -0.508 -0.9398)
			(end -0.508 0.9398)
			(stroke
				(width 0.1524)
				(type default)
			)
			(layer "F.SilkS")
		)
		(fp_rect
			(start -0.508 0.9398)
			(end 0.508 -0.9398)
			(stroke
				(width 0)
				(type default)
			)
			(fill no)
			(layer "F.CrtYd")
		)
		(fp_rect
			(start -0.508 0.9398)
			(end 0.508 -0.9398)
			(stroke
				(width 0)
				(type default)
			)
			(fill no)
			(layer "F.Fab")
		)
		(pad "1" smd custom
			(at 0 -0.4445 180)
			(size 0.1397 0.1397)
			(layers "F.Cu" "F.Mask" "F.Paste")
			(net "PWM_OUT_FAN4_NET")
			(options
				(clearance outline)
				(anchor circle)
			)
			(primitives
				(gr_poly
					(pts
						(arc
							(start -0.1778 -0.2794)
							(mid -0.249642 -0.249642)
							(end -0.2794 -0.1778)
						)
						(arc
							(start -0.2794 0.1778)
							(mid -0.249642 0.249642)
							(end -0.1778 0.2794)
						)
						(arc
							(start 0.1778 0.2794)
							(mid 0.249642 0.249642)
							(end 0.2794 0.1778)
						)
						(arc
							(start 0.2794 -0.1778)
							(mid 0.249642 -0.249642)
							(end 0.1778 -0.2794)
						)
					)
					(width 0)
					(fill yes)
				)
			)
		)
		(pad "2" smd custom
			(at 0 0.4445 180)
			(size 0.1397 0.1397)
			(layers "F.Cu" "F.Mask" "F.Paste")
			(net "PWM_OUT_FAN4")
			(options
				(clearance outline)
				(anchor circle)
			)
			(primitives
				(gr_poly
					(pts
						(arc
							(start -0.1778 -0.2794)
							(mid -0.249642 -0.249642)
							(end -0.2794 -0.1778)
						)
						(arc
							(start -0.2794 0.1778)
							(mid -0.249642 0.249642)
							(end -0.1778 0.2794)
						)
						(arc
							(start 0.1778 0.2794)
							(mid 0.249642 0.249642)
							(end 0.2794 0.1778)
						)
						(arc
							(start 0.2794 -0.1778)
							(mid 0.249642 -0.249642)
							(end 0.1778 -0.2794)
						)
					)
					(width 0)
					(fill yes)
				)
			)
		)
	)
	(footprint ""
		(layer "F.Cu")
		(at 25.527 -361.188)
		(property "Reference" "PR9"
			(at 0 0 0)
			(layer "F.SilkS")
			(hide yes)
			(effects
				(font
					(size 1.27 1.27)
				)
			)
		)
		(property "Value" "0R2J-2-GP"
			(at 0.064008 -3.993896 0)
			(unlocked yes)
			(layer "F.Fab")
			(hide yes)
			(effects
				(font
					(size 1.016 1.016)
					(thickness 0.1524)
				)
			)
		)
		(property "Device Type" "R402H16"
			(at 0.064008 -5.517896 0)
			(unlocked yes)
			(layer "F.Fab")
			(hide yes)
			(effects
				(font
					(size 1.016 1.016)
					(thickness 0.1524)
				)
			)
		)
		(duplicate_pad_numbers_are_jumpers no)
		(fp_line
			(start -0.508 -0.9398)
			(end -0.508 0.9398)
			(stroke
				(width 0.1524)
				(type default)
			)
			(layer "F.SilkS")
		)
		(fp_line
			(start 0.508 -0.9398)
			(end -0.508 -0.9398)
			(stroke
				(width 0.1524)
				(type default)
			)
			(layer "F.SilkS")
		)
		(fp_rect
			(start -0.508 0.9398)
			(end 0.508 -0.9398)
			(stroke
				(width 0)
				(type default)
			)
			(fill no)
			(layer "F.CrtYd")
		)
		(fp_rect
			(start -0.508 0.9398)
			(end 0.508 -0.9398)
			(stroke
				(width 0)
				(type default)
			)
			(fill no)
			(layer "F.Fab")
		)
		(pad "1" smd custom
			(at 0 -0.4445)
			(size 0.1397 0.1397)
			(layers "F.Cu" "F.Mask" "F.Paste")
			(net "ADM1276_LATCH#")
			(options
				(clearance outline)
				(anchor circle)
			)
			(primitives
				(gr_poly
					(pts
						(arc
							(start -0.1778 -0.2794)
							(mid -0.249642 -0.249642)
							(end -0.2794 -0.1778)
						)
						(arc
							(start -0.2794 0.1778)
							(mid -0.249642 0.249642)
							(end -0.1778 0.2794)
						)
						(arc
							(start 0.1778 0.2794)
							(mid 0.249642 0.249642)
							(end 0.2794 0.1778)
						)
						(arc
							(start 0.2794 -0.1778)
							(mid 0.249642 -0.249642)
							(end 0.1778 -0.2794)
						)
					)
					(width 0)
					(fill yes)
				)
			)
		)
		(pad "2" smd custom
			(at 0 0.4445)
			(size 0.1397 0.1397)
			(layers "F.Cu" "F.Mask" "F.Paste")
			(net "ADM1276_UV")
			(options
				(clearance outline)
				(anchor circle)
			)
			(primitives
				(gr_poly
					(pts
						(arc
							(start -0.1778 -0.2794)
							(mid -0.249642 -0.249642)
							(end -0.2794 -0.1778)
						)
						(arc
							(start -0.2794 0.1778)
							(mid -0.249642 0.249642)
							(end -0.1778 0.2794)
						)
						(arc
							(start 0.1778 0.2794)
							(mid 0.249642 0.249642)
							(end 0.2794 0.1778)
						)
						(arc
							(start 0.2794 -0.1778)
							(mid 0.249642 -0.249642)
							(end 0.1778 -0.2794)
						)
					)
					(width 0)
					(fill yes)
				)
			)
		)
	)
	(footprint ""
		(layer "F.Cu")
		(at 15.9004 -62.865 180)
		(property "Reference" "R61"
			(at 0 0 180)
			(layer "F.SilkS")
			(hide yes)
			(effects
				(font
					(size 1.27 1.27)
				)
			)
		)
		(property "Value" "4K7R2F-GP"
			(at 0.064008 -3.993896 180)
			(unlocked yes)
			(layer "F.Fab")
			(hide yes)
			(effects
				(font
					(size 1.016 1.016)
					(thickness 0.1524)
				)
			)
		)
		(property "Device Type" "R402H16"
			(at 0.064008 -5.517896 180)
			(unlocked yes)
			(layer "F.Fab")
			(hide yes)
			(effects
				(font
					(size 1.016 1.016)
					(thickness 0.1524)
				)
			)
		)
		(duplicate_pad_numbers_are_jumpers no)
		(fp_line
			(start 0.508 -0.9398)
			(end -0.508 -0.9398)
			(stroke
				(width 0.1524)
				(type default)
			)
			(layer "F.SilkS")
		)
		(fp_line
			(start -0.508 -0.9398)
			(end -0.508 0.9398)
			(stroke
				(width 0.1524)
				(type default)
			)
			(layer "F.SilkS")
		)
		(fp_rect
			(start -0.508 0.9398)
			(end 0.508 -0.9398)
			(stroke
				(width 0)
				(type default)
			)
			(fill no)
			(layer "F.CrtYd")
		)
		(fp_rect
			(start -0.508 0.9398)
			(end 0.508 -0.9398)
			(stroke
				(width 0)
				(type default)
			)
			(fill no)
			(layer "F.Fab")
		)
		(pad "1" smd custom
			(at 0 -0.4445 180)
			(size 0.1397 0.1397)
			(layers "F.Cu" "F.Mask" "F.Paste")
			(net "P3V3")
			(options
				(clearance outline)
				(anchor circle)
			)
			(primitives
				(gr_poly
					(pts
						(arc
							(start -0.1778 -0.2794)
							(mid -0.249642 -0.249642)
							(end -0.2794 -0.1778)
						)
						(arc
							(start -0.2794 0.1778)
							(mid -0.249642 0.249642)
							(end -0.1778 0.2794)
						)
						(arc
							(start 0.1778 0.2794)
							(mid 0.249642 0.249642)
							(end 0.2794 0.1778)
						)
						(arc
							(start 0.2794 -0.1778)
							(mid 0.249642 -0.249642)
							(end 0.1778 -0.2794)
						)
					)
					(width 0)
					(fill yes)
				)
			)
		)
		(pad "2" smd custom
			(at 0 0.4445 180)
			(size 0.1397 0.1397)
			(layers "F.Cu" "F.Mask" "F.Paste")
			(net "I2C_C_SCL_CONN_R")
			(options
				(clearance outline)
				(anchor circle)
			)
			(primitives
				(gr_poly
					(pts
						(arc
							(start -0.1778 -0.2794)
							(mid -0.249642 -0.249642)
							(end -0.2794 -0.1778)
						)
						(arc
							(start -0.2794 0.1778)
							(mid -0.249642 0.249642)
							(end -0.1778 0.2794)
						)
						(arc
							(start 0.1778 0.2794)
							(mid 0.249642 0.249642)
							(end 0.2794 0.1778)
						)
						(arc
							(start 0.2794 -0.1778)
							(mid 0.249642 -0.249642)
							(end 0.1778 -0.2794)
						)
					)
					(width 0)
					(fill yes)
				)
			)
		)
	)
	(footprint ""
		(layer "F.Cu")
		(at 40.851074 -362.859574 180)
		(property "Reference" "PR41"
			(at 0 0 180)
			(layer "F.SilkS")
			(hide yes)
			(effects
				(font
					(size 1.27 1.27)
				)
			)
		)
		(property "Value" "1KR2F-3-GP"
			(at 0.064008 -3.993896 180)
			(unlocked yes)
			(layer "F.Fab")
			(hide yes)
			(effects
				(font
					(size 1.016 1.016)
					(thickness 0.1524)
				)
			)
		)
		(property "Device Type" "R402H16"
			(at 0.064008 -5.517896 180)
			(unlocked yes)
			(layer "F.Fab")
			(hide yes)
			(effects
				(font
					(size 1.016 1.016)
					(thickness 0.1524)
				)
			)
		)
		(duplicate_pad_numbers_are_jumpers no)
		(fp_line
			(start 0.508 -0.9398)
			(end -0.508 -0.9398)
			(stroke
				(width 0.1524)
				(type default)
			)
			(layer "F.SilkS")
		)
		(fp_line
			(start -0.508 -0.9398)
			(end -0.508 0.9398)
			(stroke
				(width 0.1524)
				(type default)
			)
			(layer "F.SilkS")
		)
		(fp_rect
			(start -0.508 0.9398)
			(end 0.508 -0.9398)
			(stroke
				(width 0)
				(type default)
			)
			(fill no)
			(layer "F.CrtYd")
		)
		(fp_rect
			(start -0.508 0.9398)
			(end 0.508 -0.9398)
			(stroke
				(width 0)
				(type default)
			)
			(fill no)
			(layer "F.Fab")
		)
		(pad "1" smd custom
			(at 0 -0.4445 180)
			(size 0.1397 0.1397)
			(layers "F.Cu" "F.Mask" "F.Paste")
			(net "TEMP_ALM#_JP_1")
			(options
				(clearance outline)
				(anchor circle)
			)
			(primitives
				(gr_poly
					(pts
						(arc
							(start -0.1778 -0.2794)
							(mid -0.249642 -0.249642)
							(end -0.2794 -0.1778)
						)
						(arc
							(start -0.2794 0.1778)
							(mid -0.249642 0.249642)
							(end -0.1778 0.2794)
						)
						(arc
							(start 0.1778 0.2794)
							(mid 0.249642 0.249642)
							(end 0.2794 0.1778)
						)
						(arc
							(start 0.2794 -0.1778)
							(mid 0.249642 -0.249642)
							(end 0.1778 -0.2794)
						)
					)
					(width 0)
					(fill yes)
				)
			)
		)
		(pad "2" smd custom
			(at 0 0.4445 180)
			(size 0.1397 0.1397)
			(layers "F.Cu" "F.Mask" "F.Paste")
			(net "ADM1276_LATCH#")
			(options
				(clearance outline)
				(anchor circle)
			)
			(primitives
				(gr_poly
					(pts
						(arc
							(start -0.1778 -0.2794)
							(mid -0.249642 -0.249642)
							(end -0.2794 -0.1778)
						)
						(arc
							(start -0.2794 0.1778)
							(mid -0.249642 0.249642)
							(end -0.1778 0.2794)
						)
						(arc
							(start 0.1778 0.2794)
							(mid 0.249642 0.249642)
							(end 0.2794 0.1778)
						)
						(arc
							(start 0.2794 -0.1778)
							(mid 0.249642 -0.249642)
							(end 0.1778 -0.2794)
						)
					)
					(width 0)
					(fill yes)
				)
			)
		)
	)
	(footprint ""
		(layer "F.Cu")
		(at 43.019726 -366.069626)
		(property "Reference" "PQ6"
			(at 0 0 0)
			(layer "F.SilkS")
			(hide yes)
			(effects
				(font
					(size 1.27 1.27)
				)
			)
		)
		(property "Value" "PMBS3904-1-GP"
			(at 0 -9.0932 0)
			(unlocked yes)
			(layer "F.Fab")
			(hide yes)
			(effects
				(font
					(size 1.016 1.016)
					(thickness 0.1524)
				)
			)
		)
		(property "Device Type" "SOT-23-10H44"
			(at 0 -10.6172 0)
			(unlocked yes)
			(layer "F.Fab")
			(hide yes)
			(effects
				(font
					(size 1.016 1.016)
					(thickness 0.1524)
				)
			)
		)
		(duplicate_pad_numbers_are_jumpers no)
		(fp_line
			(start -1.7526 1.8796)
			(end -1.7526 0.9906)
			(stroke
				(width 0.3302)
				(type default)
			)
			(layer "F.SilkS")
		)
		(fp_line
			(start -1.651 -1.778)
			(end -1.651 1.778)
			(stroke
				(width 0.1524)
				(type default)
			)
			(layer "F.SilkS")
		)
		(fp_line
			(start -1.651 1.778)
			(end 1.651 1.778)
			(stroke
				(width 0.1524)
				(type default)
			)
			(layer "F.SilkS")
		)
		(fp_line
			(start -1.279398 2.152142)
			(end -0.9906 1.86309)
			(stroke
				(width 0.0127)
				(type default)
			)
			(layer "F.SilkS")
		)
		(fp_line
			(start -1.279144 2.15265)
			(end -0.701294 2.15265)
			(stroke
				(width 0.0127)
				(type default)
			)
			(layer "F.SilkS")
		)
		(fp_line
			(start -1.260856 2.1336)
			(end -0.720344 2.1336)
			(stroke
				(width 0.0127)
				(type default)
			)
			(layer "F.SilkS")
		)
		(fp_line
			(start -1.251458 2.124202)
			(end -0.729996 2.124202)
			(stroke
				(width 0.0127)
				(type default)
			)
			(layer "F.SilkS")
		)
		(fp_line
			(start -1.241806 2.11455)
			(end -0.739394 2.11455)
			(stroke
				(width 0.0127)
				(type default)
			)
			(layer "F.SilkS")
		)
		(fp_line
			(start -1.232408 2.105152)
			(end -0.749046 2.105152)
			(stroke
				(width 0.0127)
				(type default)
			)
			(layer "F.SilkS")
		)
		(fp_line
			(start -1.222756 2.0955)
			(end -0.758444 2.0955)
			(stroke
				(width 0.0127)
				(type default)
			)
			(layer "F.SilkS")
		)
		(fp_line
			(start -1.213358 2.086102)
			(end -0.768096 2.086102)
			(stroke
				(width 0.0127)
				(type default)
			)
			(layer "F.SilkS")
		)
		(fp_line
			(start -1.203706 2.07645)
			(end -0.777494 2.07645)
			(stroke
				(width 0.0127)
				(type default)
			)
			(layer "F.SilkS")
		)
		(fp_line
			(start -1.194308 2.067052)
			(end -0.787146 2.067052)
			(stroke
				(width 0.0127)
				(type default)
			)
			(layer "F.SilkS")
		)
		(fp_line
			(start -1.184656 2.0574)
			(end -0.796544 2.0574)
			(stroke
				(width 0.0127)
				(type default)
			)
			(layer "F.SilkS")
		)
		(fp_line
			(start -1.175258 2.048002)
			(end -0.806196 2.048002)
			(stroke
				(width 0.0127)
				(type default)
			)
			(layer "F.SilkS")
		)
		(fp_line
			(start -1.165606 2.03835)
			(end -0.815594 2.03835)
			(stroke
				(width 0.0127)
				(type default)
			)
			(layer "F.SilkS")
		)
		(fp_line
			(start -1.156208 2.028952)
			(end -0.825246 2.028952)
			(stroke
				(width 0.0127)
				(type default)
			)
			(layer "F.SilkS")
		)
		(fp_line
			(start -1.146556 2.0193)
			(end -0.834644 2.0193)
			(stroke
				(width 0.0127)
				(type default)
			)
			(layer "F.SilkS")
		)
		(fp_line
			(start -1.137158 2.009902)
			(end -0.844296 2.009902)
			(stroke
				(width 0.0127)
				(type default)
			)
			(layer "F.SilkS")
		)
		(fp_line
			(start -1.127506 2.00025)
			(end -0.853694 2.00025)
			(stroke
				(width 0.0127)
				(type default)
			)
			(layer "F.SilkS")
		)
		(fp_line
			(start -1.118108 1.990852)
			(end -0.863346 1.990852)
			(stroke
				(width 0.0127)
				(type default)
			)
			(layer "F.SilkS")
		)
		(fp_line
			(start -1.108456 1.9812)
			(end -0.872744 1.9812)
			(stroke
				(width 0.0127)
				(type default)
			)
			(layer "F.SilkS")
		)
		(fp_line
			(start -1.099058 1.971802)
			(end -0.882396 1.971802)
			(stroke
				(width 0.0127)
				(type default)
			)
			(layer "F.SilkS")
		)
		(fp_line
			(start -1.089406 1.96215)
			(end -0.891794 1.96215)
			(stroke
				(width 0.0127)
				(type default)
			)
			(layer "F.SilkS")
		)
		(fp_line
			(start -1.080008 1.952752)
			(end -0.901446 1.952752)
			(stroke
				(width 0.0127)
				(type default)
			)
			(layer "F.SilkS")
		)
		(fp_line
			(start -1.070356 1.9431)
			(end -0.910844 1.9431)
			(stroke
				(width 0.0127)
				(type default)
			)
			(layer "F.SilkS")
		)
		(fp_line
			(start -1.060958 1.933702)
			(end -0.920496 1.933702)
			(stroke
				(width 0.0127)
				(type default)
			)
			(layer "F.SilkS")
		)
		(fp_line
			(start -1.051306 1.92405)
			(end -0.929894 1.92405)
			(stroke
				(width 0.0127)
				(type default)
			)
			(layer "F.SilkS")
		)
		(fp_line
			(start -1.041908 1.914652)
			(end -0.939546 1.914652)
			(stroke
				(width 0.0127)
				(type default)
			)
			(layer "F.SilkS")
		)
		(fp_line
			(start -1.032256 1.905)
			(end -0.948944 1.905)
			(stroke
				(width 0.0127)
				(type default)
			)
			(layer "F.SilkS")
		)
		(fp_line
			(start -1.022858 1.895602)
			(end -0.958596 1.895602)
			(stroke
				(width 0.0127)
				(type default)
			)
			(layer "F.SilkS")
		)
		(fp_line
			(start -1.013206 1.88595)
			(end -0.967994 1.88595)
			(stroke
				(width 0.0127)
				(type default)
			)
			(layer "F.SilkS")
		)
		(fp_line
			(start -1.003808 1.876552)
			(end -0.977646 1.876552)
			(stroke
				(width 0.0127)
				(type default)
			)
			(layer "F.SilkS")
		)
		(fp_line
			(start -0.994156 1.8669)
			(end -0.987044 1.8669)
			(stroke
				(width 0.0127)
				(type default)
			)
			(layer "F.SilkS")
		)
		(fp_line
			(start -0.9906 1.86309)
			(end -0.701294 2.15265)
			(stroke
				(width 0.0127)
				(type default)
			)
			(layer "F.SilkS")
		)
		(fp_line
			(start -0.719074 2.145538)
			(end -1.265936 2.14122)
			(stroke
				(width 0.0127)
				(type default)
			)
			(layer "F.SilkS")
		)
		(fp_line
			(start -0.71628 2.15265)
			(end -1.26492 2.15265)
			(stroke
				(width 0.0127)
				(type default)
			)
			(layer "F.SilkS")
		)
		(fp_line
			(start -0.635 1.8796)
			(end -1.7526 1.8796)
			(stroke
				(width 0.3302)
				(type default)
			)
			(layer "F.SilkS")
		)
		(fp_line
			(start 1.651 -1.778)
			(end -1.651 -1.778)
			(stroke
				(width 0.1524)
				(type default)
			)
			(layer "F.SilkS")
		)
		(fp_line
			(start 1.651 1.778)
			(end 1.651 -1.778)
			(stroke
				(width 0.1524)
				(type default)
			)
			(layer "F.SilkS")
		)
		(fp_poly
			(pts
				(xy -1.285748 2.159) (xy -1.285748 1.8796) (xy -1.778 1.8796) (xy -1.778 -1.8796) (xy 1.778 -1.8796)
				(xy 1.778 1.8796) (xy -0.694944 1.8796) (xy -0.694944 2.159)
			)
			(stroke
				(width 0)
				(type default)
			)
			(fill no)
			(layer "F.CrtYd")
		)
		(fp_poly
			(pts
				(xy -1.285748 2.159) (xy -1.285748 1.8796) (xy -1.778 1.8796) (xy -1.778 -1.8796) (xy 1.778 -1.8796)
				(xy 1.778 1.8796) (xy -0.694944 1.8796) (xy -0.694944 2.159)
			)
			(stroke
				(width 0)
				(type default)
			)
			(fill no)
			(layer "F.Fab")
		)
		(pad "1" smd rect
			(at -0.98425 0.9525)
			(size 0.762 1.143)
			(layers "F.Cu" "F.Mask" "F.Paste")
			(net "ADM1276_LATCH#")
		)
		(pad "2" smd rect
			(at 0.98425 0.9525)
			(size 0.762 1.143)
			(layers "F.Cu" "F.Mask" "F.Paste")
			(net "GND")
		)
		(pad "3" smd rect
			(at 0 -0.9525)
			(size 0.762 1.143)
			(layers "F.Cu" "F.Mask" "F.Paste")
			(net "TEMP_ALM#_REVERSE")
		)
	)
	(footprint ""
		(layer "F.Cu")
		(at 32.424624 -175.80991 90)
		(property "Reference" "R19"
			(at 0 0 90)
			(layer "F.SilkS")
			(hide yes)
			(effects
				(font
					(size 1.27 1.27)
				)
			)
		)
		(property "Value" "100KR2F-L1-GP"
			(at 0.064008 -3.993896 90)
			(unlocked yes)
			(layer "F.Fab")
			(hide yes)
			(effects
				(font
					(size 1.016 1.016)
					(thickness 0.1524)
				)
			)
		)
		(property "Device Type" "R402H16"
			(at 0.064008 -5.517896 90)
			(unlocked yes)
			(layer "F.Fab")
			(hide yes)
			(effects
				(font
					(size 1.016 1.016)
					(thickness 0.1524)
				)
			)
		)
		(duplicate_pad_numbers_are_jumpers no)
		(fp_line
			(start 0.508 -0.9398)
			(end -0.508 -0.9398)
			(stroke
				(width 0.1524)
				(type default)
			)
			(layer "F.SilkS")
		)
		(fp_line
			(start -0.508 -0.9398)
			(end -0.508 0.9398)
			(stroke
				(width 0.1524)
				(type default)
			)
			(layer "F.SilkS")
		)
		(fp_rect
			(start -0.508 0.9398)
			(end 0.508 -0.9398)
			(stroke
				(width 0)
				(type default)
			)
			(fill no)
			(layer "F.CrtYd")
		)
		(fp_rect
			(start -0.508 0.9398)
			(end 0.508 -0.9398)
			(stroke
				(width 0)
				(type default)
			)
			(fill no)
			(layer "F.Fab")
		)
		(pad "1" smd custom
			(at 0 -0.4445 90)
			(size 0.1397 0.1397)
			(layers "F.Cu" "F.Mask" "F.Paste")
			(net "PWM_EXP_2A")
			(options
				(clearance outline)
				(anchor circle)
			)
			(primitives
				(gr_poly
					(pts
						(arc
							(start -0.1778 -0.2794)
							(mid -0.249642 -0.249642)
							(end -0.2794 -0.1778)
						)
						(arc
							(start -0.2794 0.1778)
							(mid -0.249642 0.249642)
							(end -0.1778 0.2794)
						)
						(arc
							(start 0.1778 0.2794)
							(mid 0.249642 0.249642)
							(end 0.2794 0.1778)
						)
						(arc
							(start 0.2794 -0.1778)
							(mid 0.249642 -0.249642)
							(end 0.1778 -0.2794)
						)
					)
					(width 0)
					(fill yes)
				)
			)
		)
		(pad "2" smd custom
			(at 0 0.4445 90)
			(size 0.1397 0.1397)
			(layers "F.Cu" "F.Mask" "F.Paste")
			(net "GND")
			(options
				(clearance outline)
				(anchor circle)
			)
			(primitives
				(gr_poly
					(pts
						(arc
							(start -0.1778 -0.2794)
							(mid -0.249642 -0.249642)
							(end -0.2794 -0.1778)
						)
						(arc
							(start -0.2794 0.1778)
							(mid -0.249642 0.249642)
							(end -0.1778 0.2794)
						)
						(arc
							(start 0.1778 0.2794)
							(mid 0.249642 0.249642)
							(end 0.2794 0.1778)
						)
						(arc
							(start 0.2794 -0.1778)
							(mid 0.249642 -0.249642)
							(end 0.1778 -0.2794)
						)
					)
					(width 0)
					(fill yes)
				)
			)
		)
	)
	(footprint ""
		(layer "F.Cu")
		(at 43.8658 -382.9558 -90)
		(property "Reference" "D14"
			(at 0 0 270)
			(layer "F.SilkS")
			(hide yes)
			(effects
				(font
					(size 1.27 1.27)
				)
			)
		)
		(property "Value" "MBRS340T3G-GP"
			(at 0 -10.6172 270)
			(unlocked yes)
			(layer "F.Fab")
			(hide yes)
			(effects
				(font
					(size 1.016 1.016)
					(thickness 0.1524)
				)
			)
		)
		(property "Device Type" "D8059AKH101"
			(at 0 -12.1412 270)
			(unlocked yes)
			(layer "F.Fab")
			(hide yes)
			(effects
				(font
					(size 1.016 1.016)
					(thickness 0.1524)
				)
			)
		)
		(duplicate_pad_numbers_are_jumpers no)
		(fp_line
			(start 3.175 5.2832)
			(end -3.175 5.2832)
			(stroke
				(width 0.508)
				(type default)
			)
			(layer "F.SilkS")
		)
		(fp_line
			(start -3.175 5.1054)
			(end -3.175 -5.1054)
			(stroke
				(width 0.1524)
				(type default)
			)
			(layer "F.SilkS")
		)
		(fp_line
			(start 3.175 5.1054)
			(end -3.175 5.1054)
			(stroke
				(width 0.1524)
				(type default)
			)
			(layer "F.SilkS")
		)
		(fp_line
			(start -3.175 -5.1054)
			(end 3.175 -5.1054)
			(stroke
				(width 0.1524)
				(type default)
			)
			(layer "F.SilkS")
		)
		(fp_line
			(start 3.175 -5.1054)
			(end 3.175 5.1054)
			(stroke
				(width 0.1524)
				(type default)
			)
			(layer "F.SilkS")
		)
		(fp_rect
			(start -3.429 5.1816)
			(end 3.429 -5.1816)
			(stroke
				(width 0)
				(type default)
			)
			(fill no)
			(layer "F.CrtYd")
		)
		(fp_poly
			(pts
				(xy -3.429 -5.1816) (xy 3.429 -5.1816) (xy 3.429 5.1816) (xy -3.429 5.1816)
			)
			(stroke
				(width 0)
				(type default)
			)
			(fill no)
			(layer "F.Fab")
		)
		(pad "A" smd rect
			(at 0 -3.77571 270)
			(size 3.2512 2.159)
			(layers "F.Cu" "F.Mask" "F.Paste")
			(net "GND")
		)
		(pad "K" smd rect
			(at 0 3.77571 270)
			(size 3.2512 2.159)
			(layers "F.Cu" "F.Mask" "F.Paste")
			(net "P12V")
		)
	)
	(footprint ""
		(layer "F.Cu")
		(at 19.1008 -187.8838)
		(property "Reference" "C37"
			(at 0 0 0)
			(layer "F.SilkS")
			(hide yes)
			(effects
				(font
					(size 1.27 1.27)
				)
			)
		)
		(property "Value" "SCD1U16V2KX-3GP"
			(at 1.1811 -2.7051 0)
			(unlocked yes)
			(layer "F.Fab")
			(hide yes)
			(effects
				(font
					(size 1.016 1.016)
					(thickness 0.1524)
				)
			)
		)
		(property "Device Type" "C402H22"
			(at 1.1811 -4.2291 0)
			(unlocked yes)
			(layer "F.Fab")
			(hide yes)
			(effects
				(font
					(size 1.016 1.016)
					(thickness 0.1524)
				)
			)
		)
		(duplicate_pad_numbers_are_jumpers no)
		(fp_rect
			(start -0.4318 0.9525)
			(end 0.4318 -0.9525)
			(stroke
				(width 0)
				(type default)
			)
			(fill no)
			(layer "F.CrtYd")
		)
		(fp_rect
			(start -0.4318 0.9525)
			(end 0.4318 -0.9525)
			(stroke
				(width 0)
				(type default)
			)
			(fill no)
			(layer "F.Fab")
		)
		(pad "1" smd custom
			(at 0 -0.4445)
			(size 0.1524 0.1524)
			(layers "F.Cu" "F.Mask" "F.Paste")
			(net "FAN_TACH8")
			(options
				(clearance outline)
				(anchor circle)
			)
			(primitives
				(gr_poly
					(pts
						(arc
							(start 0.3048 -0.2032)
							(mid 0.275042 -0.275042)
							(end 0.2032 -0.3048)
						)
						(arc
							(start -0.2032 -0.3048)
							(mid -0.275042 -0.275042)
							(end -0.3048 -0.2032)
						)
						(arc
							(start -0.3048 0.2032)
							(mid -0.275042 0.275042)
							(end -0.2032 0.3048)
						)
						(arc
							(start 0.2032 0.3048)
							(mid 0.275042 0.275042)
							(end 0.3048 0.2032)
						)
					)
					(width 0)
					(fill yes)
				)
			)
		)
		(pad "2" smd custom
			(at 0 0.4445)
			(size 0.1524 0.1524)
			(layers "F.Cu" "F.Mask" "F.Paste")
			(net "GND")
			(options
				(clearance outline)
				(anchor circle)
			)
			(primitives
				(gr_poly
					(pts
						(arc
							(start 0.3048 -0.2032)
							(mid 0.275042 -0.275042)
							(end 0.2032 -0.3048)
						)
						(arc
							(start -0.2032 -0.3048)
							(mid -0.275042 -0.275042)
							(end -0.3048 -0.2032)
						)
						(arc
							(start -0.3048 0.2032)
							(mid -0.275042 0.275042)
							(end -0.2032 0.3048)
						)
						(arc
							(start 0.2032 0.3048)
							(mid 0.275042 0.275042)
							(end 0.3048 0.2032)
						)
					)
					(width 0)
					(fill yes)
				)
			)
		)
	)
	(footprint ""
		(layer "F.Cu")
		(at 22.352 -186.2836 -90)
		(property "Reference" "R81"
			(at 0 0 270)
			(layer "F.SilkS")
			(hide yes)
			(effects
				(font
					(size 1.27 1.27)
				)
			)
		)
		(property "Value" "4K7R2F-GP"
			(at 0.064008 -3.993896 270)
			(unlocked yes)
			(layer "F.Fab")
			(hide yes)
			(effects
				(font
					(size 1.016 1.016)
					(thickness 0.1524)
				)
			)
		)
		(property "Device Type" "R402H16"
			(at 0.064008 -5.517896 270)
			(unlocked yes)
			(layer "F.Fab")
			(hide yes)
			(effects
				(font
					(size 1.016 1.016)
					(thickness 0.1524)
				)
			)
		)
		(duplicate_pad_numbers_are_jumpers no)
		(fp_line
			(start -0.508 -0.9398)
			(end -0.508 0.9398)
			(stroke
				(width 0.1524)
				(type default)
			)
			(layer "F.SilkS")
		)
		(fp_line
			(start 0.508 -0.9398)
			(end -0.508 -0.9398)
			(stroke
				(width 0.1524)
				(type default)
			)
			(layer "F.SilkS")
		)
		(fp_rect
			(start -0.508 0.9398)
			(end 0.508 -0.9398)
			(stroke
				(width 0)
				(type default)
			)
			(fill no)
			(layer "F.CrtYd")
		)
		(fp_rect
			(start -0.508 0.9398)
			(end 0.508 -0.9398)
			(stroke
				(width 0)
				(type default)
			)
			(fill no)
			(layer "F.Fab")
		)
		(pad "1" smd custom
			(at 0 -0.4445 270)
			(size 0.1397 0.1397)
			(layers "F.Cu" "F.Mask" "F.Paste")
			(net "P12V")
			(options
				(clearance outline)
				(anchor circle)
			)
			(primitives
				(gr_poly
					(pts
						(arc
							(start -0.1778 -0.2794)
							(mid -0.249642 -0.249642)
							(end -0.2794 -0.1778)
						)
						(arc
							(start -0.2794 0.1778)
							(mid -0.249642 0.249642)
							(end -0.1778 0.2794)
						)
						(arc
							(start 0.1778 0.2794)
							(mid 0.249642 0.249642)
							(end 0.2794 0.1778)
						)
						(arc
							(start 0.2794 -0.1778)
							(mid 0.249642 -0.249642)
							(end 0.1778 -0.2794)
						)
					)
					(width 0)
					(fill yes)
				)
			)
		)
		(pad "2" smd custom
			(at 0 0.4445 270)
			(size 0.1397 0.1397)
			(layers "F.Cu" "F.Mask" "F.Paste")
			(net "FAN_TACH8")
			(options
				(clearance outline)
				(anchor circle)
			)
			(primitives
				(gr_poly
					(pts
						(arc
							(start -0.1778 -0.2794)
							(mid -0.249642 -0.249642)
							(end -0.2794 -0.1778)
						)
						(arc
							(start -0.2794 0.1778)
							(mid -0.249642 0.249642)
							(end -0.1778 0.2794)
						)
						(arc
							(start 0.1778 0.2794)
							(mid 0.249642 0.249642)
							(end 0.2794 0.1778)
						)
						(arc
							(start 0.2794 -0.1778)
							(mid 0.249642 -0.249642)
							(end 0.1778 -0.2794)
						)
					)
					(width 0)
					(fill yes)
				)
			)
		)
	)
	(footprint ""
		(layer "F.Cu")
		(at 23.622 -363.601 -90)
		(property "Reference" "PC5"
			(at 0 0 270)
			(layer "F.SilkS")
			(hide yes)
			(effects
				(font
					(size 1.27 1.27)
				)
			)
		)
		(property "Value" "SCD01U25V2KX-3GP"
			(at 1.1811 -2.7051 270)
			(unlocked yes)
			(layer "F.Fab")
			(hide yes)
			(effects
				(font
					(size 1.016 1.016)
					(thickness 0.1524)
				)
			)
		)
		(property "Device Type" "C402H22"
			(at 1.1811 -4.2291 270)
			(unlocked yes)
			(layer "F.Fab")
			(hide yes)
			(effects
				(font
					(size 1.016 1.016)
					(thickness 0.1524)
				)
			)
		)
		(duplicate_pad_numbers_are_jumpers no)
		(fp_rect
			(start -0.4318 0.9525)
			(end 0.4318 -0.9525)
			(stroke
				(width 0)
				(type default)
			)
			(fill no)
			(layer "F.CrtYd")
		)
		(fp_rect
			(start -0.4318 0.9525)
			(end 0.4318 -0.9525)
			(stroke
				(width 0)
				(type default)
			)
			(fill no)
			(layer "F.Fab")
		)
		(pad "1" smd custom
			(at 0 -0.4445 270)
			(size 0.1524 0.1524)
			(layers "F.Cu" "F.Mask" "F.Paste")
			(net "ADM1276_TIMER")
			(options
				(clearance outline)
				(anchor circle)
			)
			(primitives
				(gr_poly
					(pts
						(arc
							(start 0.3048 -0.2032)
							(mid 0.275042 -0.275042)
							(end 0.2032 -0.3048)
						)
						(arc
							(start -0.2032 -0.3048)
							(mid -0.275042 -0.275042)
							(end -0.3048 -0.2032)
						)
						(arc
							(start -0.3048 0.2032)
							(mid -0.275042 0.275042)
							(end -0.2032 0.3048)
						)
						(arc
							(start 0.2032 0.3048)
							(mid 0.275042 0.275042)
							(end 0.3048 0.2032)
						)
					)
					(width 0)
					(fill yes)
				)
			)
		)
		(pad "2" smd custom
			(at 0 0.4445 270)
			(size 0.1524 0.1524)
			(layers "F.Cu" "F.Mask" "F.Paste")
			(net "GND")
			(options
				(clearance outline)
				(anchor circle)
			)
			(primitives
				(gr_poly
					(pts
						(arc
							(start 0.3048 -0.2032)
							(mid 0.275042 -0.275042)
							(end 0.2032 -0.3048)
						)
						(arc
							(start -0.2032 -0.3048)
							(mid -0.275042 -0.275042)
							(end -0.3048 -0.2032)
						)
						(arc
							(start -0.3048 0.2032)
							(mid -0.275042 0.275042)
							(end -0.2032 0.3048)
						)
						(arc
							(start 0.2032 0.3048)
							(mid 0.275042 0.275042)
							(end 0.3048 0.2032)
						)
					)
					(width 0)
					(fill yes)
				)
			)
		)
	)
	(footprint ""
		(layer "F.Cu")
		(at 24.384 -237.871)
		(property "Reference" "PC43"
			(at 0 0 0)
			(layer "F.SilkS")
			(hide yes)
			(effects
				(font
					(size 1.27 1.27)
				)
			)
		)
		(property "Value" "SC22U16V6MX-GP"
			(at -0.0762 -5.1308 0)
			(unlocked yes)
			(layer "F.Fab")
			(hide yes)
			(effects
				(font
					(size 1.016 1.016)
					(thickness 0.1524)
				)
			)
		)
		(property "Device Type" "C1206H71"
			(at -0.127 -6.6548 0)
			(unlocked yes)
			(layer "F.Fab")
			(hide yes)
			(effects
				(font
					(size 1.016 1.016)
					(thickness 0.1524)
				)
			)
		)
		(duplicate_pad_numbers_are_jumpers no)
		(fp_line
			(start -1.016 -2.2352)
			(end 1.016 -2.2352)
			(stroke
				(width 0.1524)
				(type default)
			)
			(layer "F.SilkS")
		)
		(fp_line
			(start -1.016 -0.8382)
			(end -1.016 -2.2352)
			(stroke
				(width 0.1524)
				(type default)
			)
			(layer "F.SilkS")
		)
		(fp_line
			(start -1.016 2.2352)
			(end -1.016 0.8382)
			(stroke
				(width 0.1524)
				(type default)
			)
			(layer "F.SilkS")
		)
		(fp_line
			(start 1.016 -2.2352)
			(end 1.016 -0.8382)
			(stroke
				(width 0.1524)
				(type default)
			)
			(layer "F.SilkS")
		)
		(fp_line
			(start 1.016 0.8382)
			(end 1.016 2.2352)
			(stroke
				(width 0.1524)
				(type default)
			)
			(layer "F.SilkS")
		)
		(fp_line
			(start 1.016 2.2352)
			(end -1.016 2.2352)
			(stroke
				(width 0.1524)
				(type default)
			)
			(layer "F.SilkS")
		)
		(fp_rect
			(start -1.0922 2.3114)
			(end 1.0922 -2.3114)
			(stroke
				(width 0)
				(type default)
			)
			(fill no)
			(layer "F.CrtYd")
		)
		(fp_poly
			(pts
				(xy 1.0922 -2.3114) (xy 1.0922 2.3114) (xy -1.0922 2.3114) (xy -1.0922 -2.3114)
			)
			(stroke
				(width 0)
				(type default)
			)
			(fill no)
			(layer "F.Fab")
		)
		(pad "1" smd rect
			(at 0 -1.397)
			(size 1.651 1.27)
			(layers "F.Cu" "F.Mask" "F.Paste")
			(net "P3V3_LX_COPPER")
		)
		(pad "2" smd rect
			(at 0 1.397)
			(size 1.651 1.27)
			(layers "F.Cu" "F.Mask" "F.Paste")
			(net "GND")
		)
	)
	(footprint ""
		(layer "F.Cu")
		(at 33.91789 -167.723566 180)
		(property "Reference" "R11"
			(at 0 0 180)
			(layer "F.SilkS")
			(hide yes)
			(effects
				(font
					(size 1.27 1.27)
				)
			)
		)
		(property "Value" "100KR2J-1-GP"
			(at 0.064008 -3.993896 180)
			(unlocked yes)
			(layer "F.Fab")
			(hide yes)
			(effects
				(font
					(size 1.016 1.016)
					(thickness 0.1524)
				)
			)
		)
		(property "Device Type" "R402H16"
			(at 0.064008 -5.517896 180)
			(unlocked yes)
			(layer "F.Fab")
			(hide yes)
			(effects
				(font
					(size 1.016 1.016)
					(thickness 0.1524)
				)
			)
		)
		(duplicate_pad_numbers_are_jumpers no)
		(fp_line
			(start 0.508 -0.9398)
			(end -0.508 -0.9398)
			(stroke
				(width 0.1524)
				(type default)
			)
			(layer "F.SilkS")
		)
		(fp_line
			(start -0.508 -0.9398)
			(end -0.508 0.9398)
			(stroke
				(width 0.1524)
				(type default)
			)
			(layer "F.SilkS")
		)
		(fp_rect
			(start -0.508 0.9398)
			(end 0.508 -0.9398)
			(stroke
				(width 0)
				(type default)
			)
			(fill no)
			(layer "F.CrtYd")
		)
		(fp_rect
			(start -0.508 0.9398)
			(end 0.508 -0.9398)
			(stroke
				(width 0)
				(type default)
			)
			(fill no)
			(layer "F.Fab")
		)
		(pad "1" smd custom
			(at 0 -0.4445 180)
			(size 0.1397 0.1397)
			(layers "F.Cu" "F.Mask" "F.Paste")
			(net "NCT7904_ADR")
			(options
				(clearance outline)
				(anchor circle)
			)
			(primitives
				(gr_poly
					(pts
						(arc
							(start -0.1778 -0.2794)
							(mid -0.249642 -0.249642)
							(end -0.2794 -0.1778)
						)
						(arc
							(start -0.2794 0.1778)
							(mid -0.249642 0.249642)
							(end -0.1778 0.2794)
						)
						(arc
							(start 0.1778 0.2794)
							(mid 0.249642 0.249642)
							(end 0.2794 0.1778)
						)
						(arc
							(start 0.2794 -0.1778)
							(mid 0.249642 -0.249642)
							(end 0.1778 -0.2794)
						)
					)
					(width 0)
					(fill yes)
				)
			)
		)
		(pad "2" smd custom
			(at 0 0.4445 180)
			(size 0.1397 0.1397)
			(layers "F.Cu" "F.Mask" "F.Paste")
			(net "GND")
			(options
				(clearance outline)
				(anchor circle)
			)
			(primitives
				(gr_poly
					(pts
						(arc
							(start -0.1778 -0.2794)
							(mid -0.249642 -0.249642)
							(end -0.2794 -0.1778)
						)
						(arc
							(start -0.2794 0.1778)
							(mid -0.249642 0.249642)
							(end -0.1778 0.2794)
						)
						(arc
							(start 0.1778 0.2794)
							(mid 0.249642 0.249642)
							(end 0.2794 0.1778)
						)
						(arc
							(start 0.2794 -0.1778)
							(mid 0.249642 -0.249642)
							(end 0.1778 -0.2794)
						)
					)
					(width 0)
					(fill yes)
				)
			)
		)
	)
	(footprint ""
		(layer "F.Cu")
		(at 22.352 -188.0616 90)
		(property "Reference" "D6"
			(at 0 0 90)
			(layer "F.SilkS")
			(hide yes)
			(effects
				(font
					(size 1.27 1.27)
				)
			)
		)
		(property "Value" "BAS16H-GP"
			(at 0 -5.5372 90)
			(unlocked yes)
			(layer "F.Fab")
			(hide yes)
			(effects
				(font
					(size 1.016 1.016)
					(thickness 0.1524)
				)
			)
		)
		(property "Device Type" "SOD123AKH48"
			(at 0 -7.0612 90)
			(unlocked yes)
			(layer "F.Fab")
			(hide yes)
			(effects
				(font
					(size 1.016 1.016)
					(thickness 0.1524)
				)
			)
		)
		(duplicate_pad_numbers_are_jumpers no)
		(fp_line
			(start 1.016 -2.667)
			(end -1.016 -2.667)
			(stroke
				(width 0.1524)
				(type default)
			)
			(layer "F.SilkS")
		)
		(fp_line
			(start -1.016 -2.667)
			(end -1.016 2.667)
			(stroke
				(width 0.1524)
				(type default)
			)
			(layer "F.SilkS")
		)
		(fp_line
			(start 1.016 2.667)
			(end 1.016 -2.667)
			(stroke
				(width 0.1524)
				(type default)
			)
			(layer "F.SilkS")
		)
		(fp_line
			(start -1.016 2.667)
			(end 1.016 2.667)
			(stroke
				(width 0.1524)
				(type default)
			)
			(layer "F.SilkS")
		)
		(fp_line
			(start 0.889 2.921)
			(end -0.889 2.921)
			(stroke
				(width 0.508)
				(type default)
			)
			(layer "F.SilkS")
		)
		(fp_rect
			(start -1.143 3.175)
			(end 1.143 -2.794)
			(stroke
				(width 0)
				(type default)
			)
			(fill no)
			(layer "F.CrtYd")
		)
		(fp_poly
			(pts
				(xy -1.143 -2.794) (xy 1.143 -2.794) (xy 1.143 3.175) (xy -1.143 3.175)
			)
			(stroke
				(width 0)
				(type default)
			)
			(fill no)
			(layer "F.Fab")
		)
		(pad "A" smd rect
			(at 0 -1.6891 90)
			(size 0.889 1.397)
			(layers "F.Cu" "F.Mask" "F.Paste")
			(net "FAN_TACH8")
		)
		(pad "K" smd rect
			(at 0 1.6891 90)
			(size 0.889 1.397)
			(layers "F.Cu" "F.Mask" "F.Paste")
			(net "P12V")
		)
	)
	(footprint ""
		(layer "F.Cu")
		(at 15.5702 -259.2324 -90)
		(property "Reference" "R88"
			(at 0 0 270)
			(layer "F.SilkS")
			(hide yes)
			(effects
				(font
					(size 1.27 1.27)
				)
			)
		)
		(property "Value" "10KR2F-2-GP"
			(at 0.064008 -3.993896 270)
			(unlocked yes)
			(layer "F.Fab")
			(hide yes)
			(effects
				(font
					(size 1.016 1.016)
					(thickness 0.1524)
				)
			)
		)
		(property "Device Type" "R402H16"
			(at 0.064008 -5.517896 270)
			(unlocked yes)
			(layer "F.Fab")
			(hide yes)
			(effects
				(font
					(size 1.016 1.016)
					(thickness 0.1524)
				)
			)
		)
		(duplicate_pad_numbers_are_jumpers no)
		(fp_line
			(start -0.508 -0.9398)
			(end -0.508 0.9398)
			(stroke
				(width 0.1524)
				(type default)
			)
			(layer "F.SilkS")
		)
		(fp_line
			(start 0.508 -0.9398)
			(end -0.508 -0.9398)
			(stroke
				(width 0.1524)
				(type default)
			)
			(layer "F.SilkS")
		)
		(fp_rect
			(start -0.508 0.9398)
			(end 0.508 -0.9398)
			(stroke
				(width 0)
				(type default)
			)
			(fill no)
			(layer "F.CrtYd")
		)
		(fp_rect
			(start -0.508 0.9398)
			(end 0.508 -0.9398)
			(stroke
				(width 0)
				(type default)
			)
			(fill no)
			(layer "F.Fab")
		)
		(pad "1" smd custom
			(at 0 -0.4445 270)
			(size 0.1397 0.1397)
			(layers "F.Cu" "F.Mask" "F.Paste")
			(net "FANIN_6")
			(options
				(clearance outline)
				(anchor circle)
			)
			(primitives
				(gr_poly
					(pts
						(arc
							(start -0.1778 -0.2794)
							(mid -0.249642 -0.249642)
							(end -0.2794 -0.1778)
						)
						(arc
							(start -0.2794 0.1778)
							(mid -0.249642 0.249642)
							(end -0.1778 0.2794)
						)
						(arc
							(start 0.1778 0.2794)
							(mid 0.249642 0.249642)
							(end 0.2794 0.1778)
						)
						(arc
							(start 0.2794 -0.1778)
							(mid 0.249642 -0.249642)
							(end 0.1778 -0.2794)
						)
					)
					(width 0)
					(fill yes)
				)
			)
		)
		(pad "2" smd custom
			(at 0 0.4445 270)
			(size 0.1397 0.1397)
			(layers "F.Cu" "F.Mask" "F.Paste")
			(net "GND")
			(options
				(clearance outline)
				(anchor circle)
			)
			(primitives
				(gr_poly
					(pts
						(arc
							(start -0.1778 -0.2794)
							(mid -0.249642 -0.249642)
							(end -0.2794 -0.1778)
						)
						(arc
							(start -0.2794 0.1778)
							(mid -0.249642 0.249642)
							(end -0.1778 0.2794)
						)
						(arc
							(start 0.1778 0.2794)
							(mid 0.249642 0.249642)
							(end 0.2794 0.1778)
						)
						(arc
							(start 0.2794 -0.1778)
							(mid 0.249642 -0.249642)
							(end 0.1778 -0.2794)
						)
					)
					(width 0)
					(fill yes)
				)
			)
		)
	)
	(footprint ""
		(layer "F.Cu")
		(at 43.9166 -106.2736 90)
		(property "Reference" "TC7"
			(at 0 0 90)
			(layer "F.SilkS")
			(hide yes)
			(effects
				(font
					(size 1.27 1.27)
				)
			)
		)
		(property "Value" "ST68U16VDM-1-GP"
			(at 0 -9.6012 90)
			(unlocked yes)
			(layer "F.Fab")
			(hide yes)
			(effects
				(font
					(size 1.016 1.016)
					(thickness 0.1524)
				)
			)
		)
		(property "Device Type" "CT7343H79"
			(at 0 -11.1252 90)
			(unlocked yes)
			(layer "F.Fab")
			(hide yes)
			(effects
				(font
					(size 1.016 1.016)
					(thickness 0.1524)
				)
			)
		)
		(duplicate_pad_numbers_are_jumpers no)
		(fp_line
			(start 2.286 -4.8768)
			(end -2.286 -4.8768)
			(stroke
				(width 0.1524)
				(type default)
			)
			(layer "F.SilkS")
		)
		(fp_line
			(start -2.286 -4.8768)
			(end -2.286 -2.032)
			(stroke
				(width 0.1524)
				(type default)
			)
			(layer "F.SilkS")
		)
		(fp_line
			(start 2.1082 -4.699)
			(end -2.1082 -4.699)
			(stroke
				(width 0.508)
				(type default)
			)
			(layer "F.SilkS")
		)
		(fp_line
			(start 2.286 -2.032)
			(end 2.286 -4.8768)
			(stroke
				(width 0.1524)
				(type default)
			)
			(layer "F.SilkS")
		)
		(fp_line
			(start 2.286 2.032)
			(end 2.286 4.8768)
			(stroke
				(width 0.1524)
				(type default)
			)
			(layer "F.SilkS")
		)
		(fp_line
			(start 2.286 4.8768)
			(end -2.286 4.8768)
			(stroke
				(width 0.1524)
				(type default)
			)
			(layer "F.SilkS")
		)
		(fp_line
			(start -2.286 4.8768)
			(end -2.286 2.032)
			(stroke
				(width 0.1524)
				(type default)
			)
			(layer "F.SilkS")
		)
		(fp_rect
			(start -2.1463 3.6449)
			(end 2.1463 -3.6449)
			(stroke
				(width 0)
				(type default)
			)
			(fill no)
			(layer "F.CrtYd")
		)
		(fp_poly
			(pts
				(xy -2.54 4.953) (xy -2.54 4.2926) (xy -3.81 4.2926) (xy -3.81 -4.2926) (xy -2.54 -4.2926) (xy -2.54 -4.953)
				(xy 2.54 -4.953) (xy 2.54 -4.2926) (xy 3.81 -4.2926) (xy 3.81 -1.6256) (xy 2.1463 -1.6256) (xy 2.1463 -3.6449)
				(xy -2.1463 -3.6449) (xy -2.1463 3.6449) (xy 2.1463 3.6449) (xy 2.1463 -1.6129) (xy 3.81 -1.6129)
				(xy 3.81 4.2926) (xy 2.54 4.2926) (xy 2.54 4.953)
			)
			(stroke
				(width 0)
				(type default)
			)
			(fill no)
			(layer "F.CrtYd")
		)
		(fp_rect
			(start 2.54 4.2926)
			(end 3.81 -4.2926)
			(stroke
				(width 0)
				(type default)
			)
			(fill no)
			(layer "F.Fab")
		)
		(fp_rect
			(start -3.81 4.2926)
			(end -2.54 -4.2926)
			(stroke
				(width 0)
				(type default)
			)
			(fill no)
			(layer "F.Fab")
		)
		(fp_rect
			(start -2.54 4.953)
			(end 2.54 -4.953)
			(stroke
				(width 0)
				(type default)
			)
			(fill no)
			(layer "F.Fab")
		)
		(pad "1" smd rect
			(at 0 -3.1496 90)
			(size 2.413 2.286)
			(layers "F.Cu" "F.Mask" "F.Paste")
			(net "P12VL")
		)
		(pad "2" smd rect
			(at 0 3.1496 90)
			(size 2.413 2.286)
			(layers "F.Cu" "F.Mask" "F.Paste")
			(net "GND")
		)
		(zone
			(layer "F.Cu")
			(hatch none 0.5)
			(connect_pads
				(clearance 0)
			)
			(min_thickness 0.25)
			(keepout
				(tracks allowed)
				(vias not_allowed)
				(pads allowed)
				(copperpour not_allowed)
				(footprints allowed)
			)
			(placement
				(enabled no)
				(sheetname "")
			)
			(fill
				(thermal_gap 0.5)
				(thermal_bridge_width 0.5)
				(island_removal_mode 0)
			)
			(polygon
				(pts
					(xy 42.2275 -107.7849) (xy 39.3192 -107.7849) (xy 39.3192 -104.7623) (xy 42.2148 -104.7623) (xy 42.545 -104.7623)
					(xy 42.545 -107.7849)
				)
			)
		)
		(zone
			(layer "F.Cu")
			(hatch none 0.5)
			(connect_pads
				(clearance 0)
			)
			(min_thickness 0.25)
			(keepout
				(tracks allowed)
				(vias not_allowed)
				(pads allowed)
				(copperpour not_allowed)
				(footprints allowed)
			)
			(placement
				(enabled no)
				(sheetname "")
			)
			(fill
				(thermal_gap 0.5)
				(thermal_bridge_width 0.5)
				(island_removal_mode 0)
			)
			(polygon
				(pts
					(xy 48.514 -104.7623) (xy 48.514 -107.7849) (xy 45.6184 -107.7849) (xy 45.2882 -107.7849) (xy 45.2882 -104.7623)
					(xy 45.6184 -104.7623)
				)
			)
		)
	)
	(footprint ""
		(layer "F.Cu")
		(at 21.766784 -215.519 90)
		(property "Reference" "R131"
			(at 0 0 90)
			(layer "F.SilkS")
			(hide yes)
			(effects
				(font
					(size 1.27 1.27)
				)
			)
		)
		(property "Value" "4K7R2F-GP"
			(at 0.064008 -3.993896 90)
			(unlocked yes)
			(layer "F.Fab")
			(hide yes)
			(effects
				(font
					(size 1.016 1.016)
					(thickness 0.1524)
				)
			)
		)
		(property "Device Type" "R402H16"
			(at 0.064008 -5.517896 90)
			(unlocked yes)
			(layer "F.Fab")
			(hide yes)
			(effects
				(font
					(size 1.016 1.016)
					(thickness 0.1524)
				)
			)
		)
		(duplicate_pad_numbers_are_jumpers no)
		(fp_line
			(start 0.508 -0.9398)
			(end -0.508 -0.9398)
			(stroke
				(width 0.1524)
				(type default)
			)
			(layer "F.SilkS")
		)
		(fp_line
			(start -0.508 -0.9398)
			(end -0.508 0.9398)
			(stroke
				(width 0.1524)
				(type default)
			)
			(layer "F.SilkS")
		)
		(fp_rect
			(start -0.508 0.9398)
			(end 0.508 -0.9398)
			(stroke
				(width 0)
				(type default)
			)
			(fill no)
			(layer "F.CrtYd")
		)
		(fp_rect
			(start -0.508 0.9398)
			(end 0.508 -0.9398)
			(stroke
				(width 0)
				(type default)
			)
			(fill no)
			(layer "F.Fab")
		)
		(pad "1" smd custom
			(at 0 -0.4445 90)
			(size 0.1397 0.1397)
			(layers "F.Cu" "F.Mask" "F.Paste")
			(net "P3V3")
			(options
				(clearance outline)
				(anchor circle)
			)
			(primitives
				(gr_poly
					(pts
						(arc
							(start -0.1778 -0.2794)
							(mid -0.249642 -0.249642)
							(end -0.2794 -0.1778)
						)
						(arc
							(start -0.2794 0.1778)
							(mid -0.249642 0.249642)
							(end -0.1778 0.2794)
						)
						(arc
							(start 0.1778 0.2794)
							(mid 0.249642 0.249642)
							(end 0.2794 0.1778)
						)
						(arc
							(start 0.2794 -0.1778)
							(mid 0.249642 -0.249642)
							(end 0.1778 -0.2794)
						)
					)
					(width 0)
					(fill yes)
				)
			)
		)
		(pad "2" smd custom
			(at 0 0.4445 90)
			(size 0.1397 0.1397)
			(layers "F.Cu" "F.Mask" "F.Paste")
			(net "PWM_OUT_FAN5")
			(options
				(clearance outline)
				(anchor circle)
			)
			(primitives
				(gr_poly
					(pts
						(arc
							(start -0.1778 -0.2794)
							(mid -0.249642 -0.249642)
							(end -0.2794 -0.1778)
						)
						(arc
							(start -0.2794 0.1778)
							(mid -0.249642 0.249642)
							(end -0.1778 0.2794)
						)
						(arc
							(start 0.1778 0.2794)
							(mid 0.249642 0.249642)
							(end 0.2794 0.1778)
						)
						(arc
							(start 0.2794 -0.1778)
							(mid 0.249642 -0.249642)
							(end 0.1778 -0.2794)
						)
					)
					(width 0)
					(fill yes)
				)
			)
		)
	)
	(footprint ""
		(layer "F.Cu")
		(at 16.2814 -231.4194)
		(property "Reference" "R115"
			(at 0 0 0)
			(layer "F.SilkS")
			(hide yes)
			(effects
				(font
					(size 1.27 1.27)
				)
			)
		)
		(property "Value" "2KR2F-3-GP"
			(at 0.064008 -3.993896 0)
			(unlocked yes)
			(layer "F.Fab")
			(hide yes)
			(effects
				(font
					(size 1.016 1.016)
					(thickness 0.1524)
				)
			)
		)
		(property "Device Type" "R402H16"
			(at 0.064008 -5.517896 0)
			(unlocked yes)
			(layer "F.Fab")
			(hide yes)
			(effects
				(font
					(size 1.016 1.016)
					(thickness 0.1524)
				)
			)
		)
		(duplicate_pad_numbers_are_jumpers no)
		(fp_line
			(start -0.508 -0.9398)
			(end -0.508 0.9398)
			(stroke
				(width 0.1524)
				(type default)
			)
			(layer "F.SilkS")
		)
		(fp_line
			(start 0.508 -0.9398)
			(end -0.508 -0.9398)
			(stroke
				(width 0.1524)
				(type default)
			)
			(layer "F.SilkS")
		)
		(fp_rect
			(start -0.508 0.9398)
			(end 0.508 -0.9398)
			(stroke
				(width 0)
				(type default)
			)
			(fill no)
			(layer "F.CrtYd")
		)
		(fp_rect
			(start -0.508 0.9398)
			(end 0.508 -0.9398)
			(stroke
				(width 0)
				(type default)
			)
			(fill no)
			(layer "F.Fab")
		)
		(pad "1" smd custom
			(at 0 -0.4445)
			(size 0.1397 0.1397)
			(layers "F.Cu" "F.Mask" "F.Paste")
			(net "LED_DR_LED3")
			(options
				(clearance outline)
				(anchor circle)
			)
			(primitives
				(gr_poly
					(pts
						(arc
							(start -0.1778 -0.2794)
							(mid -0.249642 -0.249642)
							(end -0.2794 -0.1778)
						)
						(arc
							(start -0.2794 0.1778)
							(mid -0.249642 0.249642)
							(end -0.1778 0.2794)
						)
						(arc
							(start 0.1778 0.2794)
							(mid 0.249642 0.249642)
							(end 0.2794 0.1778)
						)
						(arc
							(start 0.2794 -0.1778)
							(mid 0.249642 -0.249642)
							(end 0.1778 -0.2794)
						)
					)
					(width 0)
					(fill yes)
				)
			)
		)
		(pad "2" smd custom
			(at 0 0.4445)
			(size 0.1397 0.1397)
			(layers "F.Cu" "F.Mask" "F.Paste")
			(net "LED_DR_LED3_B")
			(options
				(clearance outline)
				(anchor circle)
			)
			(primitives
				(gr_poly
					(pts
						(arc
							(start -0.1778 -0.2794)
							(mid -0.249642 -0.249642)
							(end -0.2794 -0.1778)
						)
						(arc
							(start -0.2794 0.1778)
							(mid -0.249642 0.249642)
							(end -0.1778 0.2794)
						)
						(arc
							(start 0.1778 0.2794)
							(mid 0.249642 0.249642)
							(end 0.2794 0.1778)
						)
						(arc
							(start 0.2794 -0.1778)
							(mid 0.249642 -0.249642)
							(end 0.1778 -0.2794)
						)
					)
					(width 0)
					(fill yes)
				)
			)
		)
	)
	(footprint ""
		(layer "F.Cu")
		(at 22.479508 -286.917638)
		(property "Reference" "D10"
			(at 0 0 0)
			(layer "F.SilkS")
			(hide yes)
			(effects
				(font
					(size 1.27 1.27)
				)
			)
		)
		(property "Value" "BAS16H-GP"
			(at 0 -5.5372 0)
			(unlocked yes)
			(layer "F.Fab")
			(hide yes)
			(effects
				(font
					(size 1.016 1.016)
					(thickness 0.1524)
				)
			)
		)
		(property "Device Type" "SOD123AKH48"
			(at 0 -7.0612 0)
			(unlocked yes)
			(layer "F.Fab")
			(hide yes)
			(effects
				(font
					(size 1.016 1.016)
					(thickness 0.1524)
				)
			)
		)
		(duplicate_pad_numbers_are_jumpers no)
		(fp_line
			(start -1.016 -2.667)
			(end -1.016 2.667)
			(stroke
				(width 0.1524)
				(type default)
			)
			(layer "F.SilkS")
		)
		(fp_line
			(start -1.016 2.667)
			(end 1.016 2.667)
			(stroke
				(width 0.1524)
				(type default)
			)
			(layer "F.SilkS")
		)
		(fp_line
			(start 0.889 2.921)
			(end -0.889 2.921)
			(stroke
				(width 0.508)
				(type default)
			)
			(layer "F.SilkS")
		)
		(fp_line
			(start 1.016 -2.667)
			(end -1.016 -2.667)
			(stroke
				(width 0.1524)
				(type default)
			)
			(layer "F.SilkS")
		)
		(fp_line
			(start 1.016 2.667)
			(end 1.016 -2.667)
			(stroke
				(width 0.1524)
				(type default)
			)
			(layer "F.SilkS")
		)
		(fp_rect
			(start -1.143 3.175)
			(end 1.143 -2.794)
			(stroke
				(width 0)
				(type default)
			)
			(fill no)
			(layer "F.CrtYd")
		)
		(fp_poly
			(pts
				(xy -1.143 -2.794) (xy 1.143 -2.794) (xy 1.143 3.175) (xy -1.143 3.175)
			)
			(stroke
				(width 0)
				(type default)
			)
			(fill no)
			(layer "F.Fab")
		)
		(pad "A" smd rect
			(at 0 -1.6891)
			(size 0.889 1.397)
			(layers "F.Cu" "F.Mask" "F.Paste")
			(net "FAN_TACH4")
		)
		(pad "K" smd rect
			(at 0 1.6891)
			(size 0.889 1.397)
			(layers "F.Cu" "F.Mask" "F.Paste")
			(net "P12V")
		)
	)
	(footprint ""
		(layer "F.Cu")
		(at 38.5826 -356.921816)
		(property "Reference" "PQ14"
			(at 0 0 0)
			(layer "F.SilkS")
			(hide yes)
			(effects
				(font
					(size 1.27 1.27)
				)
			)
		)
		(property "Value" "PMBS3904-1-GP"
			(at 0 -9.0932 0)
			(unlocked yes)
			(layer "F.Fab")
			(hide yes)
			(effects
				(font
					(size 1.016 1.016)
					(thickness 0.1524)
				)
			)
		)
		(property "Device Type" "SOT-23-10H44"
			(at 0 -10.6172 0)
			(unlocked yes)
			(layer "F.Fab")
			(hide yes)
			(effects
				(font
					(size 1.016 1.016)
					(thickness 0.1524)
				)
			)
		)
		(duplicate_pad_numbers_are_jumpers no)
		(fp_line
			(start -1.7526 1.8796)
			(end -1.7526 0.9906)
			(stroke
				(width 0.3302)
				(type default)
			)
			(layer "F.SilkS")
		)
		(fp_line
			(start -1.651 -1.778)
			(end -1.651 1.778)
			(stroke
				(width 0.1524)
				(type default)
			)
			(layer "F.SilkS")
		)
		(fp_line
			(start -1.651 1.778)
			(end 1.651 1.778)
			(stroke
				(width 0.1524)
				(type default)
			)
			(layer "F.SilkS")
		)
		(fp_line
			(start -1.279398 2.152142)
			(end -0.9906 1.86309)
			(stroke
				(width 0.0127)
				(type default)
			)
			(layer "F.SilkS")
		)
		(fp_line
			(start -1.279144 2.15265)
			(end -0.701294 2.15265)
			(stroke
				(width 0.0127)
				(type default)
			)
			(layer "F.SilkS")
		)
		(fp_line
			(start -1.260856 2.1336)
			(end -0.720344 2.1336)
			(stroke
				(width 0.0127)
				(type default)
			)
			(layer "F.SilkS")
		)
		(fp_line
			(start -1.251458 2.124202)
			(end -0.729996 2.124202)
			(stroke
				(width 0.0127)
				(type default)
			)
			(layer "F.SilkS")
		)
		(fp_line
			(start -1.241806 2.11455)
			(end -0.739394 2.11455)
			(stroke
				(width 0.0127)
				(type default)
			)
			(layer "F.SilkS")
		)
		(fp_line
			(start -1.232408 2.105152)
			(end -0.749046 2.105152)
			(stroke
				(width 0.0127)
				(type default)
			)
			(layer "F.SilkS")
		)
		(fp_line
			(start -1.222756 2.0955)
			(end -0.758444 2.0955)
			(stroke
				(width 0.0127)
				(type default)
			)
			(layer "F.SilkS")
		)
		(fp_line
			(start -1.213358 2.086102)
			(end -0.768096 2.086102)
			(stroke
				(width 0.0127)
				(type default)
			)
			(layer "F.SilkS")
		)
		(fp_line
			(start -1.203706 2.07645)
			(end -0.777494 2.07645)
			(stroke
				(width 0.0127)
				(type default)
			)
			(layer "F.SilkS")
		)
		(fp_line
			(start -1.194308 2.067052)
			(end -0.787146 2.067052)
			(stroke
				(width 0.0127)
				(type default)
			)
			(layer "F.SilkS")
		)
		(fp_line
			(start -1.184656 2.0574)
			(end -0.796544 2.0574)
			(stroke
				(width 0.0127)
				(type default)
			)
			(layer "F.SilkS")
		)
		(fp_line
			(start -1.175258 2.048002)
			(end -0.806196 2.048002)
			(stroke
				(width 0.0127)
				(type default)
			)
			(layer "F.SilkS")
		)
		(fp_line
			(start -1.165606 2.03835)
			(end -0.815594 2.03835)
			(stroke
				(width 0.0127)
				(type default)
			)
			(layer "F.SilkS")
		)
		(fp_line
			(start -1.156208 2.028952)
			(end -0.825246 2.028952)
			(stroke
				(width 0.0127)
				(type default)
			)
			(layer "F.SilkS")
		)
		(fp_line
			(start -1.146556 2.0193)
			(end -0.834644 2.0193)
			(stroke
				(width 0.0127)
				(type default)
			)
			(layer "F.SilkS")
		)
		(fp_line
			(start -1.137158 2.009902)
			(end -0.844296 2.009902)
			(stroke
				(width 0.0127)
				(type default)
			)
			(layer "F.SilkS")
		)
		(fp_line
			(start -1.127506 2.00025)
			(end -0.853694 2.00025)
			(stroke
				(width 0.0127)
				(type default)
			)
			(layer "F.SilkS")
		)
		(fp_line
			(start -1.118108 1.990852)
			(end -0.863346 1.990852)
			(stroke
				(width 0.0127)
				(type default)
			)
			(layer "F.SilkS")
		)
		(fp_line
			(start -1.108456 1.9812)
			(end -0.872744 1.9812)
			(stroke
				(width 0.0127)
				(type default)
			)
			(layer "F.SilkS")
		)
		(fp_line
			(start -1.099058 1.971802)
			(end -0.882396 1.971802)
			(stroke
				(width 0.0127)
				(type default)
			)
			(layer "F.SilkS")
		)
		(fp_line
			(start -1.089406 1.96215)
			(end -0.891794 1.96215)
			(stroke
				(width 0.0127)
				(type default)
			)
			(layer "F.SilkS")
		)
		(fp_line
			(start -1.080008 1.952752)
			(end -0.901446 1.952752)
			(stroke
				(width 0.0127)
				(type default)
			)
			(layer "F.SilkS")
		)
		(fp_line
			(start -1.070356 1.9431)
			(end -0.910844 1.9431)
			(stroke
				(width 0.0127)
				(type default)
			)
			(layer "F.SilkS")
		)
		(fp_line
			(start -1.060958 1.933702)
			(end -0.920496 1.933702)
			(stroke
				(width 0.0127)
				(type default)
			)
			(layer "F.SilkS")
		)
		(fp_line
			(start -1.051306 1.92405)
			(end -0.929894 1.92405)
			(stroke
				(width 0.0127)
				(type default)
			)
			(layer "F.SilkS")
		)
		(fp_line
			(start -1.041908 1.914652)
			(end -0.939546 1.914652)
			(stroke
				(width 0.0127)
				(type default)
			)
			(layer "F.SilkS")
		)
		(fp_line
			(start -1.032256 1.905)
			(end -0.948944 1.905)
			(stroke
				(width 0.0127)
				(type default)
			)
			(layer "F.SilkS")
		)
		(fp_line
			(start -1.022858 1.895602)
			(end -0.958596 1.895602)
			(stroke
				(width 0.0127)
				(type default)
			)
			(layer "F.SilkS")
		)
		(fp_line
			(start -1.013206 1.88595)
			(end -0.967994 1.88595)
			(stroke
				(width 0.0127)
				(type default)
			)
			(layer "F.SilkS")
		)
		(fp_line
			(start -1.003808 1.876552)
			(end -0.977646 1.876552)
			(stroke
				(width 0.0127)
				(type default)
			)
			(layer "F.SilkS")
		)
		(fp_line
			(start -0.994156 1.8669)
			(end -0.987044 1.8669)
			(stroke
				(width 0.0127)
				(type default)
			)
			(layer "F.SilkS")
		)
		(fp_line
			(start -0.9906 1.86309)
			(end -0.701294 2.15265)
			(stroke
				(width 0.0127)
				(type default)
			)
			(layer "F.SilkS")
		)
		(fp_line
			(start -0.719074 2.145538)
			(end -1.265936 2.14122)
			(stroke
				(width 0.0127)
				(type default)
			)
			(layer "F.SilkS")
		)
		(fp_line
			(start -0.71628 2.15265)
			(end -1.26492 2.15265)
			(stroke
				(width 0.0127)
				(type default)
			)
			(layer "F.SilkS")
		)
		(fp_line
			(start -0.635 1.8796)
			(end -1.7526 1.8796)
			(stroke
				(width 0.3302)
				(type default)
			)
			(layer "F.SilkS")
		)
		(fp_line
			(start 1.651 -1.778)
			(end -1.651 -1.778)
			(stroke
				(width 0.1524)
				(type default)
			)
			(layer "F.SilkS")
		)
		(fp_line
			(start 1.651 1.778)
			(end 1.651 -1.778)
			(stroke
				(width 0.1524)
				(type default)
			)
			(layer "F.SilkS")
		)
		(fp_poly
			(pts
				(xy -1.285748 2.159) (xy -1.285748 1.8796) (xy -1.778 1.8796) (xy -1.778 -1.8796) (xy 1.778 -1.8796)
				(xy 1.778 1.8796) (xy -0.694944 1.8796) (xy -0.694944 2.159)
			)
			(stroke
				(width 0)
				(type default)
			)
			(fill no)
			(layer "F.CrtYd")
		)
		(fp_poly
			(pts
				(xy -1.285748 2.159) (xy -1.285748 1.8796) (xy -1.778 1.8796) (xy -1.778 -1.8796) (xy 1.778 -1.8796)
				(xy 1.778 1.8796) (xy -0.694944 1.8796) (xy -0.694944 2.159)
			)
			(stroke
				(width 0)
				(type default)
			)
			(fill no)
			(layer "F.Fab")
		)
		(pad "1" smd rect
			(at -0.98425 0.9525)
			(size 0.762 1.143)
			(layers "F.Cu" "F.Mask" "F.Paste")
			(net "OTP_RETRY_B")
		)
		(pad "2" smd rect
			(at 0.98425 0.9525)
			(size 0.762 1.143)
			(layers "F.Cu" "F.Mask" "F.Paste")
			(net "GND")
		)
		(pad "3" smd rect
			(at 0 -0.9525)
			(size 0.762 1.143)
			(layers "F.Cu" "F.Mask" "F.Paste")
			(net "OTP_RETRY_C")
		)
	)
	(footprint ""
		(layer "F.Cu")
		(at 41.529 -183.185816)
		(property "Reference" "U8"
			(at 0 0 0)
			(layer "F.SilkS")
			(hide yes)
			(effects
				(font
					(size 1.27 1.27)
				)
			)
		)
		(property "Value" "TSAHC74PWR-GP"
			(at -7.112 -6.0579 0)
			(unlocked yes)
			(layer "F.Fab")
			(hide yes)
			(effects
				(font
					(size 1.016 1.016)
					(thickness 0.1524)
				)
			)
		)
		(property "Device Type" "TSOIC14H48"
			(at -7.112 -7.5819 0)
			(unlocked yes)
			(layer "F.Fab")
			(hide yes)
			(effects
				(font
					(size 1.016 1.016)
					(thickness 0.1524)
				)
			)
		)
		(duplicate_pad_numbers_are_jumpers no)
		(fp_line
			(start -2.9718 -1.778)
			(end 2.1336 -1.778)
			(stroke
				(width 0.1524)
				(type default)
			)
			(layer "F.SilkS")
		)
		(fp_line
			(start -2.9718 1.778)
			(end -2.9718 -1.778)
			(stroke
				(width 0.1524)
				(type default)
			)
			(layer "F.SilkS")
		)
		(fp_line
			(start -2.9337 -0.4699)
			(end -2.9083 -0.4699)
			(stroke
				(width 0.1524)
				(type default)
			)
			(layer "F.SilkS")
		)
		(fp_line
			(start -2.9083 -0.4699)
			(end -2.4384 0)
			(stroke
				(width 0.1524)
				(type default)
			)
			(layer "F.SilkS")
		)
		(fp_line
			(start -2.8956 0.4572)
			(end -2.921 0.4572)
			(stroke
				(width 0.1524)
				(type default)
			)
			(layer "F.SilkS")
		)
		(fp_line
			(start -2.794 3.8227)
			(end -2.794 1.7018)
			(stroke
				(width 0.508)
				(type default)
			)
			(layer "F.SilkS")
		)
		(fp_line
			(start -2.4384 0)
			(end -2.8956 0.4572)
			(stroke
				(width 0.1524)
				(type default)
			)
			(layer "F.SilkS")
		)
		(fp_line
			(start 2.1336 -1.778)
			(end 2.1336 1.778)
			(stroke
				(width 0.1524)
				(type default)
			)
			(layer "F.SilkS")
		)
		(fp_line
			(start 2.1336 1.778)
			(end -2.9718 1.778)
			(stroke
				(width 0.1524)
				(type default)
			)
			(layer "F.SilkS")
		)
		(fp_poly
			(pts
				(xy -2.1336 -1.7653) (xy 2.1336 -1.7653) (xy 2.1336 1.778) (xy -2.1336 1.778)
			)
			(stroke
				(width 0)
				(type default)
			)
			(fill yes)
			(layer "F.SilkS")
		)
		(fp_rect
			(start -2.5019 3.2004)
			(end 2.5019 -3.2004)
			(stroke
				(width 0)
				(type default)
			)
			(fill no)
			(layer "F.CrtYd")
		)
		(fp_poly
			(pts
				(xy -3.048 4.0894) (xy -3.048 -2.5781) (xy -2.5019 -2.5781) (xy -2.5019 3.2004) (xy 2.5019 3.2004)
				(xy 2.5019 -3.2004) (xy -2.5019 -3.2004) (xy -2.5019 -2.5908) (xy -3.048 -2.5908) (xy -3.048 -4.0894)
				(xy 3.048 -4.0894) (xy 3.048 4.0894)
			)
			(stroke
				(width 0)
				(type default)
			)
			(fill no)
			(layer "F.CrtYd")
		)
		(fp_rect
			(start -3.048 4.0894)
			(end 3.048 -4.0894)
			(stroke
				(width 0)
				(type default)
			)
			(fill no)
			(layer "F.Fab")
		)
		(pad "1" smd rect
			(at -1.94945 2.8194)
			(size 0.3556 1.524)
			(layers "F.Cu" "F.Mask" "F.Paste")
			(net "D_LATCH_CLR")
		)
		(pad "2" smd rect
			(at -1.30048 2.8194)
			(size 0.3556 1.524)
			(layers "F.Cu" "F.Mask" "F.Paste")
			(net "GND")
		)
		(pad "3" smd rect
			(at -0.65024 2.8194)
			(size 0.3556 1.524)
			(layers "F.Cu" "F.Mask" "F.Paste")
			(net "TEMP_ALM#_IN_D")
		)
		(pad "4" smd rect
			(at 0 2.8194)
			(size 0.3556 1.524)
			(layers "F.Cu" "F.Mask" "F.Paste")
			(net "D_LATCH_PRE#")
		)
		(pad "5" smd rect
			(at 0.65024 2.8194)
			(size 0.3556 1.524)
			(layers "F.Cu" "F.Mask" "F.Paste")
			(net "D_LATCH_Q")
		)
		(pad "6" smd rect
			(at 1.30048 2.8194)
			(size 0.3556 1.524)
			(layers "F.Cu" "F.Mask" "F.Paste")
			(net "D_LATCH_Q#")
		)
		(pad "7" smd rect
			(at 1.94945 2.8194)
			(size 0.3556 1.524)
			(layers "F.Cu" "F.Mask" "F.Paste")
			(net "GND")
		)
		(pad "8" smd rect
			(at 1.94945 -2.8194)
			(size 0.3556 1.524)
			(layers "F.Cu" "F.Mask" "F.Paste")
			(net "Net_57")
		)
		(pad "9" smd rect
			(at 1.30048 -2.8194)
			(size 0.3556 1.524)
			(layers "F.Cu" "F.Mask" "F.Paste")
			(net "Net_58")
		)
		(pad "10" smd rect
			(at 0.65024 -2.8194)
			(size 0.3556 1.524)
			(layers "F.Cu" "F.Mask" "F.Paste")
			(net "P3V3_AUX")
		)
		(pad "11" smd rect
			(at 0 -2.8194)
			(size 0.3556 1.524)
			(layers "F.Cu" "F.Mask" "F.Paste")
			(net "GND")
		)
		(pad "12" smd rect
			(at -0.65024 -2.8194)
			(size 0.3556 1.524)
			(layers "F.Cu" "F.Mask" "F.Paste")
			(net "GND")
		)
		(pad "13" smd rect
			(at -1.30048 -2.8194)
			(size 0.3556 1.524)
			(layers "F.Cu" "F.Mask" "F.Paste")
			(net "P3V3_AUX")
		)
		(pad "14" smd rect
			(at -1.94945 -2.8194)
			(size 0.3556 1.524)
			(layers "F.Cu" "F.Mask" "F.Paste")
			(net "P3V3_AUX")
		)
	)
	(footprint ""
		(layer "F.Cu")
		(at 25.654 -400.177)
		(property "Reference" "PQ1"
			(at 0 0 0)
			(layer "F.SilkS")
			(hide yes)
			(effects
				(font
					(size 1.27 1.27)
				)
			)
		)
		(property "Value" "PH0925CL-GP"
			(at -4.2799 -0.4572 0)
			(unlocked yes)
			(layer "F.Fab")
			(hide yes)
			(effects
				(font
					(size 1.016 1.016)
					(thickness 0.1524)
				)
			)
		)
		(property "Device Type" "LFPAK-5PH48-U"
			(at -4.2799 -1.9812 0)
			(unlocked yes)
			(layer "F.Fab")
			(hide yes)
			(effects
				(font
					(size 1.016 1.016)
					(thickness 0.1524)
				)
			)
		)
		(duplicate_pad_numbers_are_jumpers no)
		(fp_line
			(start -2.7559 -6.5532)
			(end -2.7559 1.0668)
			(stroke
				(width 0.1524)
				(type default)
			)
			(layer "F.SilkS")
		)
		(fp_line
			(start -2.7559 1.0668)
			(end 2.7559 1.0668)
			(stroke
				(width 0.1524)
				(type default)
			)
			(layer "F.SilkS")
		)
		(fp_line
			(start -1.7272 1.1684)
			(end -2.1082 1.1684)
			(stroke
				(width 0.3302)
				(type default)
			)
			(layer "F.SilkS")
		)
		(fp_line
			(start 2.7559 -6.5532)
			(end -2.7559 -6.5532)
			(stroke
				(width 0.1524)
				(type default)
			)
			(layer "F.SilkS")
		)
		(fp_line
			(start 2.7559 1.0668)
			(end 2.7559 -6.5532)
			(stroke
				(width 0.1524)
				(type default)
			)
			(layer "F.SilkS")
		)
		(fp_poly
			(pts
				(xy -2.3368 1.5748) (xy -1.905 1.143) (xy -1.4732 1.5748)
			)
			(stroke
				(width 0)
				(type default)
			)
			(fill yes)
			(layer "F.SilkS")
		)
		(fp_poly
			(pts
				(xy -2.5019 -4.02971) (xy -0.3302 -4.02971) (xy -0.3302 -6.30301) (xy -2.5019 -6.30301)
			)
			(stroke
				(width 0)
				(type default)
			)
			(fill yes)
			(layer "F.Paste")
		)
		(fp_poly
			(pts
				(xy -2.5019 -1.09601) (xy -0.3302 -1.09601) (xy -0.3302 -3.36931) (xy -2.5019 -3.36931)
			)
			(stroke
				(width 0)
				(type default)
			)
			(fill yes)
			(layer "F.Paste")
		)
		(fp_poly
			(pts
				(xy 0.3302 -4.02971) (xy 2.5019 -4.02971) (xy 2.5019 -6.30301) (xy 0.3302 -6.30301)
			)
			(stroke
				(width 0)
				(type default)
			)
			(fill yes)
			(layer "F.Paste")
		)
		(fp_poly
			(pts
				(xy 0.3302 -1.09601) (xy 2.5019 -1.09601) (xy 2.5019 -3.36931) (xy 0.3302 -3.36931)
			)
			(stroke
				(width 0)
				(type default)
			)
			(fill yes)
			(layer "F.Paste")
		)
		(fp_rect
			(start -2.4511 0.3048)
			(end 2.4511 -5.6896)
			(stroke
				(width 0)
				(type default)
			)
			(fill no)
			(layer "F.CrtYd")
		)
		(fp_poly
			(pts
				(xy -3.0099 1.3208) (xy -3.0099 -6.8072) (xy 3.0099 -6.8072) (xy 3.0099 -1.016) (xy 2.4511 -1.016)
				(xy 2.4511 -5.6896) (xy -2.4511 -5.6896) (xy -2.4511 0.3048) (xy 2.4511 0.3048) (xy 2.4511 -1.0033)
				(xy 3.0099 -1.0033) (xy 3.0099 1.3208)
			)
			(stroke
				(width 0)
				(type default)
			)
			(fill no)
			(layer "F.CrtYd")
		)
		(fp_rect
			(start -3.0099 1.3208)
			(end 3.0099 -6.8072)
			(stroke
				(width 0)
				(type default)
			)
			(fill no)
			(layer "F.Fab")
		)
		(pad "1" smd rect
			(at -1.905 0)
			(size 0.762 1.6256)
			(layers "F.Cu" "F.Mask" "F.Paste")
			(net "P12V")
		)
		(pad "2" smd rect
			(at -0.635 0)
			(size 0.762 1.6256)
			(layers "F.Cu" "F.Mask" "F.Paste")
			(net "P12V")
		)
		(pad "3" smd rect
			(at 0.635 0)
			(size 0.762 1.6256)
			(layers "F.Cu" "F.Mask" "F.Paste")
			(net "P12V")
		)
		(pad "4" smd rect
			(at 1.905 0)
			(size 0.762 1.6256)
			(layers "F.Cu" "F.Mask" "F.Paste")
			(net "ADM1276_GATE_DRV1")
		)
		(pad "5" smd rect
			(at 0 -3.69951)
			(size 5.0038 5.207)
			(layers "F.Cu" "F.Mask" "F.Paste")
			(net "P12V_SENSE_TRACE")
		)
	)
	(footprint ""
		(layer "F.Cu")
		(at 43.7134 -138.5062)
		(property "Reference" "PC95"
			(at 0 0 0)
			(layer "F.SilkS")
			(hide yes)
			(effects
				(font
					(size 1.27 1.27)
				)
			)
		)
		(property "Value" "SC10U25V5KX-GP"
			(at -0.0762 -6.1214 0)
			(unlocked yes)
			(layer "F.Fab")
			(hide yes)
			(effects
				(font
					(size 1.016 1.016)
					(thickness 0.1524)
				)
			)
		)
		(property "Device Type" "C805H56"
			(at -0.0762 -8.1534 0)
			(unlocked yes)
			(layer "F.Fab")
			(hide yes)
			(effects
				(font
					(size 1.016 1.016)
					(thickness 0.1524)
				)
			)
		)
		(duplicate_pad_numbers_are_jumpers no)
		(fp_line
			(start 0.635 0)
			(end -0.635 0)
			(stroke
				(width 0.508)
				(type default)
			)
			(layer "F.SilkS")
		)
		(fp_rect
			(start -0.9652 1.778)
			(end 0.9652 -1.778)
			(stroke
				(width 0)
				(type default)
			)
			(fill no)
			(layer "F.CrtYd")
		)
		(fp_poly
			(pts
				(xy -0.9652 -1.778) (xy 0.9652 -1.778) (xy 0.9652 1.778) (xy -0.9652 1.778)
			)
			(stroke
				(width 0)
				(type default)
			)
			(fill no)
			(layer "F.Fab")
		)
		(pad "1" smd rect
			(at 0 -0.9652)
			(size 1.397 1.143)
			(layers "F.Cu" "F.Mask" "F.Paste")
			(net "P12VL_2490_EN_2")
		)
		(pad "2" smd rect
			(at 0 0.9652)
			(size 1.397 1.143)
			(layers "F.Cu" "F.Mask" "F.Paste")
			(net "GND")
		)
	)
	(footprint ""
		(layer "F.Cu")
		(at 26.4922 -251.6632 -90)
		(property "Reference" "C13"
			(at 0 0 270)
			(layer "F.SilkS")
			(hide yes)
			(effects
				(font
					(size 1.27 1.27)
				)
			)
		)
		(property "Value" "SC1U16V3KX-5GP"
			(at 0 -2.8194 270)
			(unlocked yes)
			(layer "F.Fab")
			(hide yes)
			(effects
				(font
					(size 1.016 1.016)
					(thickness 0.1524)
				)
			)
		)
		(property "Device Type" "C603H36"
			(at 0 -4.3434 270)
			(unlocked yes)
			(layer "F.Fab")
			(hide yes)
			(effects
				(font
					(size 1.016 1.016)
					(thickness 0.1524)
				)
			)
		)
		(duplicate_pad_numbers_are_jumpers no)
		(fp_line
			(start 0.508 0)
			(end -0.508 0)
			(stroke
				(width 0.2032)
				(type default)
			)
			(layer "F.SilkS")
		)
		(fp_rect
			(start -0.5842 1.3335)
			(end 0.5842 -1.3335)
			(stroke
				(width 0)
				(type default)
			)
			(fill no)
			(layer "F.CrtYd")
		)
		(fp_rect
			(start -0.5842 1.3335)
			(end 0.5842 -1.3335)
			(stroke
				(width 0)
				(type default)
			)
			(fill no)
			(layer "F.Fab")
		)
		(pad "1" smd custom
			(at 0 -0.762 270)
			(size 0.2159 0.2159)
			(layers "F.Cu" "F.Mask" "F.Paste")
			(net "P3V3")
			(options
				(clearance outline)
				(anchor circle)
			)
			(primitives
				(gr_poly
					(pts
						(arc
							(start -0.3302 -0.4318)
							(mid -0.402042 -0.402042)
							(end -0.4318 -0.3302)
						)
						(arc
							(start -0.4318 0.3302)
							(mid -0.402042 0.402042)
							(end -0.3302 0.4318)
						)
						(arc
							(start 0.3302 0.4318)
							(mid 0.402042 0.402042)
							(end 0.4318 0.3302)
						)
						(arc
							(start 0.4318 -0.3302)
							(mid 0.402042 -0.402042)
							(end 0.3302 -0.4318)
						)
					)
					(width 0)
					(fill yes)
				)
			)
		)
		(pad "2" smd custom
			(at 0 0.762 270)
			(size 0.2159 0.2159)
			(layers "F.Cu" "F.Mask" "F.Paste")
			(net "GND")
			(options
				(clearance outline)
				(anchor circle)
			)
			(primitives
				(gr_poly
					(pts
						(arc
							(start -0.3302 -0.4318)
							(mid -0.402042 -0.402042)
							(end -0.4318 -0.3302)
						)
						(arc
							(start -0.4318 0.3302)
							(mid -0.402042 0.402042)
							(end -0.3302 0.4318)
						)
						(arc
							(start 0.3302 0.4318)
							(mid 0.402042 0.402042)
							(end 0.4318 0.3302)
						)
						(arc
							(start 0.4318 -0.3302)
							(mid 0.402042 -0.402042)
							(end 0.3302 -0.4318)
						)
					)
					(width 0)
					(fill yes)
				)
			)
		)
	)
	(footprint ""
		(layer "F.Cu")
		(at 8.9662 -106.2482 -90)
		(property "Reference" "TC2"
			(at 0 0 270)
			(layer "F.SilkS")
			(hide yes)
			(effects
				(font
					(size 1.27 1.27)
				)
			)
		)
		(property "Value" "ST68U16VDM-1-GP"
			(at 0 -9.6012 270)
			(unlocked yes)
			(layer "F.Fab")
			(hide yes)
			(effects
				(font
					(size 1.016 1.016)
					(thickness 0.1524)
				)
			)
		)
		(property "Device Type" "CT7343H79"
			(at 0 -11.1252 270)
			(unlocked yes)
			(layer "F.Fab")
			(hide yes)
			(effects
				(font
					(size 1.016 1.016)
					(thickness 0.1524)
				)
			)
		)
		(duplicate_pad_numbers_are_jumpers no)
		(fp_line
			(start -2.286 4.8768)
			(end -2.286 2.032)
			(stroke
				(width 0.1524)
				(type default)
			)
			(layer "F.SilkS")
		)
		(fp_line
			(start 2.286 4.8768)
			(end -2.286 4.8768)
			(stroke
				(width 0.1524)
				(type default)
			)
			(layer "F.SilkS")
		)
		(fp_line
			(start 2.286 2.032)
			(end 2.286 4.8768)
			(stroke
				(width 0.1524)
				(type default)
			)
			(layer "F.SilkS")
		)
		(fp_line
			(start 2.286 -2.032)
			(end 2.286 -4.8768)
			(stroke
				(width 0.1524)
				(type default)
			)
			(layer "F.SilkS")
		)
		(fp_line
			(start 2.1082 -4.699)
			(end -2.1082 -4.699)
			(stroke
				(width 0.508)
				(type default)
			)
			(layer "F.SilkS")
		)
		(fp_line
			(start -2.286 -4.8768)
			(end -2.286 -2.032)
			(stroke
				(width 0.1524)
				(type default)
			)
			(layer "F.SilkS")
		)
		(fp_line
			(start 2.286 -4.8768)
			(end -2.286 -4.8768)
			(stroke
				(width 0.1524)
				(type default)
			)
			(layer "F.SilkS")
		)
		(fp_rect
			(start -2.1463 3.6449)
			(end 2.1463 -3.6449)
			(stroke
				(width 0)
				(type default)
			)
			(fill no)
			(layer "F.CrtYd")
		)
		(fp_poly
			(pts
				(xy -2.54 4.953) (xy -2.54 4.2926) (xy -3.81 4.2926) (xy -3.81 -4.2926) (xy -2.54 -4.2926) (xy -2.54 -4.953)
				(xy 2.54 -4.953) (xy 2.54 -4.2926) (xy 3.81 -4.2926) (xy 3.81 -1.6256) (xy 2.1463 -1.6256) (xy 2.1463 -3.6449)
				(xy -2.1463 -3.6449) (xy -2.1463 3.6449) (xy 2.1463 3.6449) (xy 2.1463 -1.6129) (xy 3.81 -1.6129)
				(xy 3.81 4.2926) (xy 2.54 4.2926) (xy 2.54 4.953)
			)
			(stroke
				(width 0)
				(type default)
			)
			(fill no)
			(layer "F.CrtYd")
		)
		(fp_rect
			(start -2.54 4.953)
			(end 2.54 -4.953)
			(stroke
				(width 0)
				(type default)
			)
			(fill no)
			(layer "F.Fab")
		)
		(fp_rect
			(start -3.81 4.2926)
			(end -2.54 -4.2926)
			(stroke
				(width 0)
				(type default)
			)
			(fill no)
			(layer "F.Fab")
		)
		(fp_rect
			(start 2.54 4.2926)
			(end 3.81 -4.2926)
			(stroke
				(width 0)
				(type default)
			)
			(fill no)
			(layer "F.Fab")
		)
		(pad "1" smd rect
			(at 0 -3.1496 270)
			(size 2.413 2.286)
			(layers "F.Cu" "F.Mask" "F.Paste")
			(net "P12VU")
		)
		(pad "2" smd rect
			(at 0 3.1496 270)
			(size 2.413 2.286)
			(layers "F.Cu" "F.Mask" "F.Paste")
			(net "GND")
		)
		(zone
			(layer "F.Cu")
			(hatch none 0.5)
			(connect_pads
				(clearance 0)
			)
			(min_thickness 0.25)
			(keepout
				(tracks allowed)
				(vias not_allowed)
				(pads allowed)
				(copperpour not_allowed)
				(footprints allowed)
			)
			(placement
				(enabled no)
				(sheetname "")
			)
			(fill
				(thermal_gap 0.5)
				(thermal_bridge_width 0.5)
				(island_removal_mode 0)
			)
			(polygon
				(pts
					(xy 4.3688 -107.7595) (xy 4.3688 -104.7369) (xy 7.2644 -104.7369) (xy 7.5946 -104.7369) (xy 7.5946 -107.7595)
					(xy 7.2644 -107.7595)
				)
			)
		)
		(zone
			(layer "F.Cu")
			(hatch none 0.5)
			(connect_pads
				(clearance 0)
			)
			(min_thickness 0.25)
			(keepout
				(tracks allowed)
				(vias not_allowed)
				(pads allowed)
				(copperpour not_allowed)
				(footprints allowed)
			)
			(placement
				(enabled no)
				(sheetname "")
			)
			(fill
				(thermal_gap 0.5)
				(thermal_bridge_width 0.5)
				(island_removal_mode 0)
			)
			(polygon
				(pts
					(xy 10.6553 -104.7369) (xy 13.5636 -104.7369) (xy 13.5636 -107.7595) (xy 10.668 -107.7595) (xy 10.3378 -107.7595)
					(xy 10.3378 -104.7369)
				)
			)
		)
	)
	(footprint ""
		(layer "F.Cu")
		(at 30.904434 -238.266224 180)
		(property "Reference" "R41"
			(at 0 0 180)
			(layer "F.SilkS")
			(hide yes)
			(effects
				(font
					(size 1.27 1.27)
				)
			)
		)
		(property "Value" "4K7R2J-2-GP"
			(at 0.064008 -3.993896 180)
			(unlocked yes)
			(layer "F.Fab")
			(hide yes)
			(effects
				(font
					(size 1.016 1.016)
					(thickness 0.1524)
				)
			)
		)
		(property "Device Type" "R402H16"
			(at 0.064008 -5.517896 180)
			(unlocked yes)
			(layer "F.Fab")
			(hide yes)
			(effects
				(font
					(size 1.016 1.016)
					(thickness 0.1524)
				)
			)
		)
		(duplicate_pad_numbers_are_jumpers no)
		(fp_line
			(start 0.508 -0.9398)
			(end -0.508 -0.9398)
			(stroke
				(width 0.1524)
				(type default)
			)
			(layer "F.SilkS")
		)
		(fp_line
			(start -0.508 -0.9398)
			(end -0.508 0.9398)
			(stroke
				(width 0.1524)
				(type default)
			)
			(layer "F.SilkS")
		)
		(fp_rect
			(start -0.508 0.9398)
			(end 0.508 -0.9398)
			(stroke
				(width 0)
				(type default)
			)
			(fill no)
			(layer "F.CrtYd")
		)
		(fp_rect
			(start -0.508 0.9398)
			(end 0.508 -0.9398)
			(stroke
				(width 0)
				(type default)
			)
			(fill no)
			(layer "F.Fab")
		)
		(pad "1" smd custom
			(at 0 -0.4445 180)
			(size 0.1397 0.1397)
			(layers "F.Cu" "F.Mask" "F.Paste")
			(net "P3V3")
			(options
				(clearance outline)
				(anchor circle)
			)
			(primitives
				(gr_poly
					(pts
						(arc
							(start -0.1778 -0.2794)
							(mid -0.249642 -0.249642)
							(end -0.2794 -0.1778)
						)
						(arc
							(start -0.2794 0.1778)
							(mid -0.249642 0.249642)
							(end -0.1778 0.2794)
						)
						(arc
							(start 0.1778 0.2794)
							(mid 0.249642 0.249642)
							(end 0.2794 0.1778)
						)
						(arc
							(start 0.2794 -0.1778)
							(mid 0.249642 -0.249642)
							(end 0.1778 -0.2794)
						)
					)
					(width 0)
					(fill yes)
				)
			)
		)
		(pad "2" smd custom
			(at 0 0.4445 180)
			(size 0.1397 0.1397)
			(layers "F.Cu" "F.Mask" "F.Paste")
			(net "FCB_EEPROM_A2")
			(options
				(clearance outline)
				(anchor circle)
			)
			(primitives
				(gr_poly
					(pts
						(arc
							(start -0.1778 -0.2794)
							(mid -0.249642 -0.249642)
							(end -0.2794 -0.1778)
						)
						(arc
							(start -0.2794 0.1778)
							(mid -0.249642 0.249642)
							(end -0.1778 0.2794)
						)
						(arc
							(start 0.1778 0.2794)
							(mid 0.249642 0.249642)
							(end 0.2794 0.1778)
						)
						(arc
							(start 0.2794 -0.1778)
							(mid 0.249642 -0.249642)
							(end 0.1778 -0.2794)
						)
					)
					(width 0)
					(fill yes)
				)
			)
		)
	)
	(footprint ""
		(layer "F.Cu")
		(at 19.558 -185.1914 180)
		(property "Reference" "R89"
			(at 0 0 180)
			(layer "F.SilkS")
			(hide yes)
			(effects
				(font
					(size 1.27 1.27)
				)
			)
		)
		(property "Value" "10KR2F-2-GP"
			(at 0.064008 -3.993896 180)
			(unlocked yes)
			(layer "F.Fab")
			(hide yes)
			(effects
				(font
					(size 1.016 1.016)
					(thickness 0.1524)
				)
			)
		)
		(property "Device Type" "R402H16"
			(at 0.064008 -5.517896 180)
			(unlocked yes)
			(layer "F.Fab")
			(hide yes)
			(effects
				(font
					(size 1.016 1.016)
					(thickness 0.1524)
				)
			)
		)
		(duplicate_pad_numbers_are_jumpers no)
		(fp_line
			(start 0.508 -0.9398)
			(end -0.508 -0.9398)
			(stroke
				(width 0.1524)
				(type default)
			)
			(layer "F.SilkS")
		)
		(fp_line
			(start -0.508 -0.9398)
			(end -0.508 0.9398)
			(stroke
				(width 0.1524)
				(type default)
			)
			(layer "F.SilkS")
		)
		(fp_rect
			(start -0.508 0.9398)
			(end 0.508 -0.9398)
			(stroke
				(width 0)
				(type default)
			)
			(fill no)
			(layer "F.CrtYd")
		)
		(fp_rect
			(start -0.508 0.9398)
			(end 0.508 -0.9398)
			(stroke
				(width 0)
				(type default)
			)
			(fill no)
			(layer "F.Fab")
		)
		(pad "1" smd custom
			(at 0 -0.4445 180)
			(size 0.1397 0.1397)
			(layers "F.Cu" "F.Mask" "F.Paste")
			(net "FANIN_8")
			(options
				(clearance outline)
				(anchor circle)
			)
			(primitives
				(gr_poly
					(pts
						(arc
							(start -0.1778 -0.2794)
							(mid -0.249642 -0.249642)
							(end -0.2794 -0.1778)
						)
						(arc
							(start -0.2794 0.1778)
							(mid -0.249642 0.249642)
							(end -0.1778 0.2794)
						)
						(arc
							(start 0.1778 0.2794)
							(mid 0.249642 0.249642)
							(end 0.2794 0.1778)
						)
						(arc
							(start 0.2794 -0.1778)
							(mid 0.249642 -0.249642)
							(end 0.1778 -0.2794)
						)
					)
					(width 0)
					(fill yes)
				)
			)
		)
		(pad "2" smd custom
			(at 0 0.4445 180)
			(size 0.1397 0.1397)
			(layers "F.Cu" "F.Mask" "F.Paste")
			(net "GND")
			(options
				(clearance outline)
				(anchor circle)
			)
			(primitives
				(gr_poly
					(pts
						(arc
							(start -0.1778 -0.2794)
							(mid -0.249642 -0.249642)
							(end -0.2794 -0.1778)
						)
						(arc
							(start -0.2794 0.1778)
							(mid -0.249642 0.249642)
							(end -0.1778 0.2794)
						)
						(arc
							(start 0.1778 0.2794)
							(mid 0.249642 0.249642)
							(end 0.2794 0.1778)
						)
						(arc
							(start 0.2794 -0.1778)
							(mid 0.249642 -0.249642)
							(end 0.1778 -0.2794)
						)
					)
					(width 0)
					(fill yes)
				)
			)
		)
	)
	(footprint ""
		(layer "F.Cu")
		(at 41.4274 -135.1534 -90)
		(property "Reference" "PR100"
			(at 0 0 270)
			(layer "F.SilkS")
			(hide yes)
			(effects
				(font
					(size 1.27 1.27)
				)
			)
		)
		(property "Value" "1MR3J-L-GP"
			(at -0.0254 -2.5146 270)
			(unlocked yes)
			(layer "F.Fab")
			(hide yes)
			(effects
				(font
					(size 1.016 1.016)
					(thickness 0.1524)
				)
			)
		)
		(property "Device Type" "R603H22"
			(at -0.0254 -4.0386 270)
			(unlocked yes)
			(layer "F.Fab")
			(hide yes)
			(effects
				(font
					(size 1.016 1.016)
					(thickness 0.1524)
				)
			)
		)
		(duplicate_pad_numbers_are_jumpers no)
		(fp_line
			(start -0.4826 0)
			(end -0.2032 0)
			(stroke
				(width 0.2032)
				(type default)
			)
			(layer "F.SilkS")
		)
		(fp_line
			(start 0.2032 0)
			(end 0.4826 0)
			(stroke
				(width 0.2032)
				(type default)
			)
			(layer "F.SilkS")
		)
		(fp_rect
			(start -0.5842 1.3335)
			(end 0.5842 -1.3335)
			(stroke
				(width 0)
				(type default)
			)
			(fill no)
			(layer "F.CrtYd")
		)
		(fp_rect
			(start -0.5842 1.3335)
			(end 0.5842 -1.3335)
			(stroke
				(width 0)
				(type default)
			)
			(fill no)
			(layer "F.Fab")
		)
		(pad "1" smd custom
			(at 0 -0.762 270)
			(size 0.2159 0.2159)
			(layers "F.Cu" "F.Mask" "F.Paste")
			(net "P12VL_2490_VCC")
			(options
				(clearance outline)
				(anchor circle)
			)
			(primitives
				(gr_poly
					(pts
						(arc
							(start -0.3302 -0.4318)
							(mid -0.402042 -0.402042)
							(end -0.4318 -0.3302)
						)
						(arc
							(start -0.4318 0.3302)
							(mid -0.402042 0.402042)
							(end -0.3302 0.4318)
						)
						(arc
							(start 0.3302 0.4318)
							(mid 0.402042 0.402042)
							(end 0.4318 0.3302)
						)
						(arc
							(start 0.4318 -0.3302)
							(mid 0.402042 -0.402042)
							(end 0.3302 -0.4318)
						)
					)
					(width 0)
					(fill yes)
				)
			)
		)
		(pad "2" smd custom
			(at 0 0.762 270)
			(size 0.2159 0.2159)
			(layers "F.Cu" "F.Mask" "F.Paste")
			(net "P12VL_2490_SENSE")
			(options
				(clearance outline)
				(anchor circle)
			)
			(primitives
				(gr_poly
					(pts
						(arc
							(start -0.3302 -0.4318)
							(mid -0.402042 -0.402042)
							(end -0.4318 -0.3302)
						)
						(arc
							(start -0.4318 0.3302)
							(mid -0.402042 0.402042)
							(end -0.3302 0.4318)
						)
						(arc
							(start 0.3302 0.4318)
							(mid 0.402042 0.402042)
							(end 0.4318 0.3302)
						)
						(arc
							(start 0.4318 -0.3302)
							(mid 0.402042 -0.402042)
							(end 0.3302 -0.4318)
						)
					)
					(width 0)
					(fill yes)
				)
			)
		)
	)
	(footprint ""
		(layer "F.Cu")
		(at 6.999986 -159.999934)
		(property "Reference" "H7"
			(at 0 0 0)
			(layer "F.SilkS")
			(hide yes)
			(effects
				(font
					(size 1.27 1.27)
				)
			)
		)
		(property "Value" "HOLE315R138"
			(at 0 -7.0612 0)
			(unlocked yes)
			(layer "F.Fab")
			(hide yes)
			(effects
				(font
					(size 1.016 1.016)
					(thickness 0.1524)
				)
			)
		)
		(property "Device Type" "HOLE315R138"
			(at 0 -8.5852 0)
			(unlocked yes)
			(layer "F.Fab")
			(hide yes)
			(effects
				(font
					(size 1.016 1.016)
					(thickness 0.1524)
				)
			)
		)
		(duplicate_pad_numbers_are_jumpers no)
		(fp_poly
			(pts
				(xy 0 4.3053) (xy -0.13462 4.30276) (xy -0.27051 4.29641) (xy -0.40513 4.28625) (xy -0.53975 4.27101)
				(xy -0.6731 4.25196) (xy -0.80645 4.2291) (xy -0.9398 4.20116) (xy -1.07061 4.17068) (xy -1.20142 4.13385)
				(xy -1.33096 4.09448) (xy -1.45796 4.0513) (xy -1.58496 4.00304) (xy -1.70942 3.95097) (xy -1.83261 3.89509)
				(xy -1.95453 3.83667) (xy -2.07391 3.77317) (xy -2.19202 3.70586) (xy -2.30632 3.63474) (xy -2.41935 3.56108)
				(xy -2.53111 3.48361) (xy -2.63906 3.40233) (xy -2.74447 3.31724) (xy -2.84734 3.22961) (xy -2.94767 3.13817)
				(xy -3.04419 3.04419) (xy -3.13817 2.94767) (xy -3.22961 2.84734) (xy -3.31724 2.74447) (xy -3.40233 2.63906)
				(xy -3.48361 2.53111) (xy -3.56108 2.41935) (xy -3.63474 2.30632) (xy -3.70586 2.19202) (xy -3.77317 2.07391)
				(xy -3.83667 1.95453) (xy -3.89509 1.83261) (xy -3.95097 1.70942) (xy -4.00304 1.58496) (xy -4.0513 1.45796)
				(xy -4.09448 1.33096) (xy -4.13385 1.20142) (xy -4.17068 1.07061) (xy -4.20116 0.9398) (xy -4.2291 0.80645)
				(xy -4.25196 0.6731) (xy -4.27101 0.53975) (xy -4.28625 0.40513) (xy -4.29641 0.27051) (xy -4.30276 0.13462)
				(xy -4.3053 0) (xy -4.30276 -0.13462) (xy -4.29641 -0.27051) (xy -4.28625 -0.40513) (xy -4.27101 -0.53975)
				(xy -4.25196 -0.6731) (xy -4.2291 -0.80645) (xy -4.20116 -0.9398) (xy -4.17068 -1.07061) (xy -4.13385 -1.20142)
				(xy -4.09448 -1.33096) (xy -4.0513 -1.45796) (xy -4.00304 -1.58496) (xy -3.95097 -1.70942) (xy -3.89509 -1.83261)
				(xy -3.83667 -1.95453) (xy -3.77317 -2.07391) (xy -3.70586 -2.19202) (xy -3.63474 -2.30632) (xy -3.56108 -2.41935)
				(xy -3.48361 -2.53111) (xy -3.40233 -2.63906) (xy -3.31724 -2.74447) (xy -3.22961 -2.84734) (xy -3.13817 -2.94767)
				(xy -3.04419 -3.04419) (xy -2.94767 -3.13817) (xy -2.84734 -3.22961) (xy -2.74447 -3.31724) (xy -2.63906 -3.40233)
				(xy -2.53111 -3.48361) (xy -2.41935 -3.56108) (xy -2.30632 -3.63474) (xy -2.19202 -3.70586) (xy -2.07391 -3.77317)
				(xy -1.95453 -3.83667) (xy -1.83261 -3.89509) (xy -1.70942 -3.95097) (xy -1.58496 -4.00304) (xy -1.45796 -4.0513)
				(xy -1.33096 -4.09448) (xy -1.20142 -4.13385) (xy -1.07061 -4.17068) (xy -0.9398 -4.20116) (xy -0.80645 -4.2291)
				(xy -0.6731 -4.25196) (xy -0.53975 -4.27101) (xy -0.40513 -4.28625) (xy -0.27051 -4.29641) (xy -0.13462 -4.30276)
				(xy 0 -4.3053) (xy 0.13462 -4.30276) (xy 0.27051 -4.29641) (xy 0.40513 -4.28625) (xy 0.53975 -4.27101)
				(xy 0.6731 -4.25196) (xy 0.80645 -4.2291) (xy 0.9398 -4.20116) (xy 1.07061 -4.17068) (xy 1.20142 -4.13385)
				(xy 1.33096 -4.09448) (xy 1.45796 -4.0513) (xy 1.58496 -4.00304) (xy 1.70942 -3.95097) (xy 1.83261 -3.89509)
				(xy 1.95453 -3.83667) (xy 2.07391 -3.77317) (xy 2.19202 -3.70586) (xy 2.30632 -3.63474) (xy 2.41935 -3.56108)
				(xy 2.53111 -3.48361) (xy 2.63906 -3.40233) (xy 2.74447 -3.31724) (xy 2.84734 -3.22961) (xy 2.94767 -3.13817)
				(xy 3.04419 -3.04419) (xy 3.13817 -2.94767) (xy 3.22961 -2.84734) (xy 3.31724 -2.74447) (xy 3.40233 -2.63906)
				(xy 3.48361 -2.53111) (xy 3.56108 -2.41935) (xy 3.63474 -2.30632) (xy 3.70586 -2.19202) (xy 3.77317 -2.07391)
				(xy 3.83667 -1.95453) (xy 3.89509 -1.83261) (xy 3.95097 -1.70942) (xy 4.00304 -1.58496) (xy 4.0513 -1.45796)
				(xy 4.09448 -1.33096) (xy 4.13385 -1.20142) (xy 4.17068 -1.07061) (xy 4.20116 -0.9398) (xy 4.2291 -0.80645)
				(xy 4.25196 -0.6731) (xy 4.27101 -0.53975) (xy 4.28625 -0.40513) (xy 4.29641 -0.27051) (xy 4.30276 -0.13462)
				(xy 4.3053 0) (xy 4.30276 0.13462) (xy 4.29641 0.27051) (xy 4.28625 0.40513) (xy 4.27101 0.53975)
				(xy 4.25196 0.6731) (xy 4.2291 0.80645) (xy 4.20116 0.9398) (xy 4.17068 1.07061) (xy 4.13385 1.20142)
				(xy 4.09448 1.33096) (xy 4.0513 1.45796) (xy 4.00304 1.58496) (xy 3.95097 1.70942) (xy 3.89509 1.83261)
				(xy 3.83667 1.95453) (xy 3.77317 2.07391) (xy 3.70586 2.19202) (xy 3.63474 2.30632) (xy 3.56108 2.41935)
				(xy 3.48361 2.53111) (xy 3.40233 2.63906) (xy 3.31724 2.74447) (xy 3.22961 2.84734) (xy 3.13817 2.94767)
				(xy 3.04419 3.04419) (xy 2.94767 3.13817) (xy 2.84734 3.22961) (xy 2.74447 3.31724) (xy 2.63906 3.40233)
				(xy 2.53111 3.48361) (xy 2.41935 3.56108) (xy 2.30632 3.63474) (xy 2.19202 3.70586) (xy 2.07391 3.77317)
				(xy 1.95453 3.83667) (xy 1.83261 3.89509) (xy 1.70942 3.95097) (xy 1.58496 4.00304) (xy 1.45796 4.0513)
				(xy 1.33096 4.09448) (xy 1.20142 4.13385) (xy 1.07061 4.17068) (xy 0.9398 4.20116) (xy 0.80645 4.2291)
				(xy 0.6731 4.25196) (xy 0.53975 4.27101) (xy 0.40513 4.28625) (xy 0.27051 4.29641) (xy 0.13462 4.30276)
			)
			(stroke
				(width 0)
				(type default)
			)
			(fill no)
			(layer "F.CrtYd")
		)
		(fp_poly
			(pts
				(xy 0 4.3053) (xy -0.13462 4.30276) (xy -0.27051 4.29641) (xy -0.40513 4.28625) (xy -0.53975 4.27101)
				(xy -0.6731 4.25196) (xy -0.80645 4.2291) (xy -0.9398 4.20116) (xy -1.07061 4.17068) (xy -1.20142 4.13385)
				(xy -1.33096 4.09448) (xy -1.45796 4.0513) (xy -1.58496 4.00304) (xy -1.70942 3.95097) (xy -1.83261 3.89509)
				(xy -1.95453 3.83667) (xy -2.07391 3.77317) (xy -2.19202 3.70586) (xy -2.30632 3.63474) (xy -2.41935 3.56108)
				(xy -2.53111 3.48361) (xy -2.63906 3.40233) (xy -2.74447 3.31724) (xy -2.84734 3.22961) (xy -2.94767 3.13817)
				(xy -3.04419 3.04419) (xy -3.13817 2.94767) (xy -3.22961 2.84734) (xy -3.31724 2.74447) (xy -3.40233 2.63906)
				(xy -3.48361 2.53111) (xy -3.56108 2.41935) (xy -3.63474 2.30632) (xy -3.70586 2.19202) (xy -3.77317 2.07391)
				(xy -3.83667 1.95453) (xy -3.89509 1.83261) (xy -3.95097 1.70942) (xy -4.00304 1.58496) (xy -4.0513 1.45796)
				(xy -4.09448 1.33096) (xy -4.13385 1.20142) (xy -4.17068 1.07061) (xy -4.20116 0.9398) (xy -4.2291 0.80645)
				(xy -4.25196 0.6731) (xy -4.27101 0.53975) (xy -4.28625 0.40513) (xy -4.29641 0.27051) (xy -4.30276 0.13462)
				(xy -4.3053 0) (xy -4.30276 -0.13462) (xy -4.29641 -0.27051) (xy -4.28625 -0.40513) (xy -4.27101 -0.53975)
				(xy -4.25196 -0.6731) (xy -4.2291 -0.80645) (xy -4.20116 -0.9398) (xy -4.17068 -1.07061) (xy -4.13385 -1.20142)
				(xy -4.09448 -1.33096) (xy -4.0513 -1.45796) (xy -4.00304 -1.58496) (xy -3.95097 -1.70942) (xy -3.89509 -1.83261)
				(xy -3.83667 -1.95453) (xy -3.77317 -2.07391) (xy -3.70586 -2.19202) (xy -3.63474 -2.30632) (xy -3.56108 -2.41935)
				(xy -3.48361 -2.53111) (xy -3.40233 -2.63906) (xy -3.31724 -2.74447) (xy -3.22961 -2.84734) (xy -3.13817 -2.94767)
				(xy -3.04419 -3.04419) (xy -2.94767 -3.13817) (xy -2.84734 -3.22961) (xy -2.74447 -3.31724) (xy -2.63906 -3.40233)
				(xy -2.53111 -3.48361) (xy -2.41935 -3.56108) (xy -2.30632 -3.63474) (xy -2.19202 -3.70586) (xy -2.07391 -3.77317)
				(xy -1.95453 -3.83667) (xy -1.83261 -3.89509) (xy -1.70942 -3.95097) (xy -1.58496 -4.00304) (xy -1.45796 -4.0513)
				(xy -1.33096 -4.09448) (xy -1.20142 -4.13385) (xy -1.07061 -4.17068) (xy -0.9398 -4.20116) (xy -0.80645 -4.2291)
				(xy -0.6731 -4.25196) (xy -0.53975 -4.27101) (xy -0.40513 -4.28625) (xy -0.27051 -4.29641) (xy -0.13462 -4.30276)
				(xy 0 -4.3053) (xy 0.13462 -4.30276) (xy 0.27051 -4.29641) (xy 0.40513 -4.28625) (xy 0.53975 -4.27101)
				(xy 0.6731 -4.25196) (xy 0.80645 -4.2291) (xy 0.9398 -4.20116) (xy 1.07061 -4.17068) (xy 1.20142 -4.13385)
				(xy 1.33096 -4.09448) (xy 1.45796 -4.0513) (xy 1.58496 -4.00304) (xy 1.70942 -3.95097) (xy 1.83261 -3.89509)
				(xy 1.95453 -3.83667) (xy 2.07391 -3.77317) (xy 2.19202 -3.70586) (xy 2.30632 -3.63474) (xy 2.41935 -3.56108)
				(xy 2.53111 -3.48361) (xy 2.63906 -3.40233) (xy 2.74447 -3.31724) (xy 2.84734 -3.22961) (xy 2.94767 -3.13817)
				(xy 3.04419 -3.04419) (xy 3.13817 -2.94767) (xy 3.22961 -2.84734) (xy 3.31724 -2.74447) (xy 3.40233 -2.63906)
				(xy 3.48361 -2.53111) (xy 3.56108 -2.41935) (xy 3.63474 -2.30632) (xy 3.70586 -2.19202) (xy 3.77317 -2.07391)
				(xy 3.83667 -1.95453) (xy 3.89509 -1.83261) (xy 3.95097 -1.70942) (xy 4.00304 -1.58496) (xy 4.0513 -1.45796)
				(xy 4.09448 -1.33096) (xy 4.13385 -1.20142) (xy 4.17068 -1.07061) (xy 4.20116 -0.9398) (xy 4.2291 -0.80645)
				(xy 4.25196 -0.6731) (xy 4.27101 -0.53975) (xy 4.28625 -0.40513) (xy 4.29641 -0.27051) (xy 4.30276 -0.13462)
				(xy 4.3053 0) (xy 4.30276 0.13462) (xy 4.29641 0.27051) (xy 4.28625 0.40513) (xy 4.27101 0.53975)
				(xy 4.25196 0.6731) (xy 4.2291 0.80645) (xy 4.20116 0.9398) (xy 4.17068 1.07061) (xy 4.13385 1.20142)
				(xy 4.09448 1.33096) (xy 4.0513 1.45796) (xy 4.00304 1.58496) (xy 3.95097 1.70942) (xy 3.89509 1.83261)
				(xy 3.83667 1.95453) (xy 3.77317 2.07391) (xy 3.70586 2.19202) (xy 3.63474 2.30632) (xy 3.56108 2.41935)
				(xy 3.48361 2.53111) (xy 3.40233 2.63906) (xy 3.31724 2.74447) (xy 3.22961 2.84734) (xy 3.13817 2.94767)
				(xy 3.04419 3.04419) (xy 2.94767 3.13817) (xy 2.84734 3.22961) (xy 2.74447 3.31724) (xy 2.63906 3.40233)
				(xy 2.53111 3.48361) (xy 2.41935 3.56108) (xy 2.30632 3.63474) (xy 2.19202 3.70586) (xy 2.07391 3.77317)
				(xy 1.95453 3.83667) (xy 1.83261 3.89509) (xy 1.70942 3.95097) (xy 1.58496 4.00304) (xy 1.45796 4.0513)
				(xy 1.33096 4.09448) (xy 1.20142 4.13385) (xy 1.07061 4.17068) (xy 0.9398 4.20116) (xy 0.80645 4.2291)
				(xy 0.6731 4.25196) (xy 0.53975 4.27101) (xy 0.40513 4.28625) (xy 0.27051 4.29641) (xy 0.13462 4.30276)
			)
			(stroke
				(width 0)
				(type default)
			)
			(fill no)
			(layer "F.Fab")
		)
		(pad "1" thru_hole circle
			(at 0 0)
			(size 8.001 8.001)
			(drill 3.5052)
			(layers "*.Cu" "*.Mask")
			(remove_unused_layers no)
			(net "GND")
			(clearance -1.7399)
			(thermal_gap 0.3048)
			(padstack
				(mode front_inner_back)
				(layer "Inner"
					(shape circle)
					(size 3.9116 3.9116)
					(clearance 0.3048)
				)
				(layer "B.Cu"
					(shape circle)
					(size 8.001 8.001)
					(clearance -1.7399)
				)
			)
		)
	)
	(footprint ""
		(layer "F.Cu")
		(at 28.9814 -96.5454 -90)
		(property "Reference" "C24"
			(at 0 0 270)
			(layer "F.SilkS")
			(hide yes)
			(effects
				(font
					(size 1.27 1.27)
				)
			)
		)
		(property "Value" "SCD1U50V3KX-GP"
			(at 0 -2.8194 270)
			(unlocked yes)
			(layer "F.Fab")
			(hide yes)
			(effects
				(font
					(size 1.016 1.016)
					(thickness 0.1524)
				)
			)
		)
		(property "Device Type" "C603H36"
			(at 0 -4.3434 270)
			(unlocked yes)
			(layer "F.Fab")
			(hide yes)
			(effects
				(font
					(size 1.016 1.016)
					(thickness 0.1524)
				)
			)
		)
		(duplicate_pad_numbers_are_jumpers no)
		(fp_line
			(start 0.508 0)
			(end -0.508 0)
			(stroke
				(width 0.2032)
				(type default)
			)
			(layer "F.SilkS")
		)
		(fp_rect
			(start -0.5842 1.3335)
			(end 0.5842 -1.3335)
			(stroke
				(width 0)
				(type default)
			)
			(fill no)
			(layer "F.CrtYd")
		)
		(fp_rect
			(start -0.5842 1.3335)
			(end 0.5842 -1.3335)
			(stroke
				(width 0)
				(type default)
			)
			(fill no)
			(layer "F.Fab")
		)
		(pad "1" smd custom
			(at 0 -0.762 270)
			(size 0.2159 0.2159)
			(layers "F.Cu" "F.Mask" "F.Paste")
			(net "P12VL")
			(options
				(clearance outline)
				(anchor circle)
			)
			(primitives
				(gr_poly
					(pts
						(arc
							(start -0.3302 -0.4318)
							(mid -0.402042 -0.402042)
							(end -0.4318 -0.3302)
						)
						(arc
							(start -0.4318 0.3302)
							(mid -0.402042 0.402042)
							(end -0.3302 0.4318)
						)
						(arc
							(start 0.3302 0.4318)
							(mid 0.402042 0.402042)
							(end 0.4318 0.3302)
						)
						(arc
							(start 0.4318 -0.3302)
							(mid 0.402042 -0.402042)
							(end 0.3302 -0.4318)
						)
					)
					(width 0)
					(fill yes)
				)
			)
		)
		(pad "2" smd custom
			(at 0 0.762 270)
			(size 0.2159 0.2159)
			(layers "F.Cu" "F.Mask" "F.Paste")
			(net "GND")
			(options
				(clearance outline)
				(anchor circle)
			)
			(primitives
				(gr_poly
					(pts
						(arc
							(start -0.3302 -0.4318)
							(mid -0.402042 -0.402042)
							(end -0.4318 -0.3302)
						)
						(arc
							(start -0.4318 0.3302)
							(mid -0.402042 0.402042)
							(end -0.3302 0.4318)
						)
						(arc
							(start 0.3302 0.4318)
							(mid 0.402042 0.402042)
							(end 0.4318 0.3302)
						)
						(arc
							(start 0.4318 -0.3302)
							(mid 0.402042 -0.402042)
							(end 0.3302 -0.4318)
						)
					)
					(width 0)
					(fill yes)
				)
			)
		)
	)
	(footprint ""
		(layer "F.Cu")
		(at 15.9258 -146.6088 90)
		(property "Reference" "R68"
			(at 0 0 90)
			(layer "F.SilkS")
			(hide yes)
			(effects
				(font
					(size 1.27 1.27)
				)
			)
		)
		(property "Value" "4K7R2F-GP"
			(at 0.064008 -3.993896 90)
			(unlocked yes)
			(layer "F.Fab")
			(hide yes)
			(effects
				(font
					(size 1.016 1.016)
					(thickness 0.1524)
				)
			)
		)
		(property "Device Type" "R402H16"
			(at 0.064008 -5.517896 90)
			(unlocked yes)
			(layer "F.Fab")
			(hide yes)
			(effects
				(font
					(size 1.016 1.016)
					(thickness 0.1524)
				)
			)
		)
		(duplicate_pad_numbers_are_jumpers no)
		(fp_line
			(start -0.508 -0.9398)
			(end -1.524 -0.9398)
			(stroke
				(width 0.1524)
				(type default)
			)
			(layer "F.SilkS")
		)
		(fp_line
			(start -1.524 -0.9398)
			(end -1.524 0.9398)
			(stroke
				(width 0.1524)
				(type default)
			)
			(layer "F.SilkS")
		)
		(fp_rect
			(start -0.508 0.9398)
			(end 0.508 -0.9398)
			(stroke
				(width 0)
				(type default)
			)
			(fill no)
			(layer "F.CrtYd")
		)
		(fp_rect
			(start -0.508 0.9398)
			(end 0.508 -0.9398)
			(stroke
				(width 0)
				(type default)
			)
			(fill no)
			(layer "F.Fab")
		)
		(pad "1" smd custom
			(at 0 -0.4445 90)
			(size 0.1397 0.1397)
			(layers "F.Cu" "F.Mask" "F.Paste")
			(net "P12V")
			(options
				(clearance outline)
				(anchor circle)
			)
			(primitives
				(gr_poly
					(pts
						(arc
							(start -0.1778 -0.2794)
							(mid -0.249642 -0.249642)
							(end -0.2794 -0.1778)
						)
						(arc
							(start -0.2794 0.1778)
							(mid -0.249642 0.249642)
							(end -0.1778 0.2794)
						)
						(arc
							(start 0.1778 0.2794)
							(mid 0.249642 0.249642)
							(end 0.2794 0.1778)
						)
						(arc
							(start 0.2794 -0.1778)
							(mid 0.249642 -0.249642)
							(end 0.1778 -0.2794)
						)
					)
					(width 0)
					(fill yes)
				)
			)
		)
		(pad "2" smd custom
			(at 0 0.4445 90)
			(size 0.1397 0.1397)
			(layers "F.Cu" "F.Mask" "F.Paste")
			(net "FAN_TACH9")
			(options
				(clearance outline)
				(anchor circle)
			)
			(primitives
				(gr_poly
					(pts
						(arc
							(start -0.1778 -0.2794)
							(mid -0.249642 -0.249642)
							(end -0.2794 -0.1778)
						)
						(arc
							(start -0.2794 0.1778)
							(mid -0.249642 0.249642)
							(end -0.1778 0.2794)
						)
						(arc
							(start 0.1778 0.2794)
							(mid 0.249642 0.249642)
							(end 0.2794 0.1778)
						)
						(arc
							(start 0.2794 -0.1778)
							(mid 0.249642 -0.249642)
							(end 0.1778 -0.2794)
						)
					)
					(width 0)
					(fill yes)
				)
			)
		)
	)
	(footprint ""
		(layer "F.Cu")
		(at 35.6616 -144.6784 180)
		(property "Reference" "PC92"
			(at 0 0 180)
			(layer "F.SilkS")
			(hide yes)
			(effects
				(font
					(size 1.27 1.27)
				)
			)
		)
		(property "Value" "SCD01U50V3KX-4GP"
			(at 0 -2.8194 180)
			(unlocked yes)
			(layer "F.Fab")
			(hide yes)
			(effects
				(font
					(size 1.016 1.016)
					(thickness 0.1524)
				)
			)
		)
		(property "Device Type" "C603H36"
			(at 0 -4.3434 180)
			(unlocked yes)
			(layer "F.Fab")
			(hide yes)
			(effects
				(font
					(size 1.016 1.016)
					(thickness 0.1524)
				)
			)
		)
		(duplicate_pad_numbers_are_jumpers no)
		(fp_line
			(start 0.508 0)
			(end -0.508 0)
			(stroke
				(width 0.2032)
				(type default)
			)
			(layer "F.SilkS")
		)
		(fp_rect
			(start -0.5842 1.3335)
			(end 0.5842 -1.3335)
			(stroke
				(width 0)
				(type default)
			)
			(fill no)
			(layer "F.CrtYd")
		)
		(fp_rect
			(start -0.5842 1.3335)
			(end 0.5842 -1.3335)
			(stroke
				(width 0)
				(type default)
			)
			(fill no)
			(layer "F.Fab")
		)
		(pad "1" smd custom
			(at 0 -0.762 180)
			(size 0.2159 0.2159)
			(layers "F.Cu" "F.Mask" "F.Paste")
			(net "P12VL_2490_TIMER")
			(options
				(clearance outline)
				(anchor circle)
			)
			(primitives
				(gr_poly
					(pts
						(arc
							(start -0.3302 -0.4318)
							(mid -0.402042 -0.402042)
							(end -0.4318 -0.3302)
						)
						(arc
							(start -0.4318 0.3302)
							(mid -0.402042 0.402042)
							(end -0.3302 0.4318)
						)
						(arc
							(start 0.3302 0.4318)
							(mid 0.402042 0.402042)
							(end 0.4318 0.3302)
						)
						(arc
							(start 0.4318 -0.3302)
							(mid 0.402042 -0.402042)
							(end 0.3302 -0.4318)
						)
					)
					(width 0)
					(fill yes)
				)
			)
		)
		(pad "2" smd custom
			(at 0 0.762 180)
			(size 0.2159 0.2159)
			(layers "F.Cu" "F.Mask" "F.Paste")
			(net "GND")
			(options
				(clearance outline)
				(anchor circle)
			)
			(primitives
				(gr_poly
					(pts
						(arc
							(start -0.3302 -0.4318)
							(mid -0.402042 -0.402042)
							(end -0.4318 -0.3302)
						)
						(arc
							(start -0.4318 0.3302)
							(mid -0.402042 0.402042)
							(end -0.3302 0.4318)
						)
						(arc
							(start 0.3302 0.4318)
							(mid 0.402042 0.402042)
							(end 0.4318 0.3302)
						)
						(arc
							(start 0.4318 -0.3302)
							(mid 0.402042 -0.402042)
							(end 0.3302 -0.4318)
						)
					)
					(width 0)
					(fill yes)
				)
			)
		)
	)
	(footprint ""
		(layer "F.Cu")
		(at 37.846 -240.665 180)
		(property "Reference" "R157"
			(at 0 0 180)
			(layer "F.SilkS")
			(hide yes)
			(effects
				(font
					(size 1.27 1.27)
				)
			)
		)
		(property "Value" "330R2J-3-GP"
			(at 0.064008 -3.993896 180)
			(unlocked yes)
			(layer "F.Fab")
			(hide yes)
			(effects
				(font
					(size 1.016 1.016)
					(thickness 0.1524)
				)
			)
		)
		(property "Device Type" "R402H16"
			(at 0.064008 -5.517896 180)
			(unlocked yes)
			(layer "F.Fab")
			(hide yes)
			(effects
				(font
					(size 1.016 1.016)
					(thickness 0.1524)
				)
			)
		)
		(duplicate_pad_numbers_are_jumpers no)
		(fp_line
			(start 0.508 -0.9398)
			(end -0.508 -0.9398)
			(stroke
				(width 0.1524)
				(type default)
			)
			(layer "F.SilkS")
		)
		(fp_line
			(start -0.508 -0.9398)
			(end -0.508 0.9398)
			(stroke
				(width 0.1524)
				(type default)
			)
			(layer "F.SilkS")
		)
		(fp_rect
			(start -0.508 0.9398)
			(end 0.508 -0.9398)
			(stroke
				(width 0)
				(type default)
			)
			(fill no)
			(layer "F.CrtYd")
		)
		(fp_rect
			(start -0.508 0.9398)
			(end 0.508 -0.9398)
			(stroke
				(width 0)
				(type default)
			)
			(fill no)
			(layer "F.Fab")
		)
		(pad "1" smd custom
			(at 0 -0.4445 180)
			(size 0.1397 0.1397)
			(layers "F.Cu" "F.Mask" "F.Paste")
			(net "P3V3")
			(options
				(clearance outline)
				(anchor circle)
			)
			(primitives
				(gr_poly
					(pts
						(arc
							(start -0.1778 -0.2794)
							(mid -0.249642 -0.249642)
							(end -0.2794 -0.1778)
						)
						(arc
							(start -0.2794 0.1778)
							(mid -0.249642 0.249642)
							(end -0.1778 0.2794)
						)
						(arc
							(start 0.1778 0.2794)
							(mid 0.249642 0.249642)
							(end 0.2794 0.1778)
						)
						(arc
							(start 0.2794 -0.1778)
							(mid 0.249642 -0.249642)
							(end 0.1778 -0.2794)
						)
					)
					(width 0)
					(fill yes)
				)
			)
		)
		(pad "2" smd custom
			(at 0 0.4445 180)
			(size 0.1397 0.1397)
			(layers "F.Cu" "F.Mask" "F.Paste")
			(net "LED_DR_LED1")
			(options
				(clearance outline)
				(anchor circle)
			)
			(primitives
				(gr_poly
					(pts
						(arc
							(start -0.1778 -0.2794)
							(mid -0.249642 -0.249642)
							(end -0.2794 -0.1778)
						)
						(arc
							(start -0.2794 0.1778)
							(mid -0.249642 0.249642)
							(end -0.1778 0.2794)
						)
						(arc
							(start 0.1778 0.2794)
							(mid 0.249642 0.249642)
							(end 0.2794 0.1778)
						)
						(arc
							(start 0.2794 -0.1778)
							(mid 0.249642 -0.249642)
							(end 0.1778 -0.2794)
						)
					)
					(width 0)
					(fill yes)
				)
			)
		)
	)
	(footprint ""
		(layer "F.Cu")
		(at 29.7434 -363.2454 -90)
		(property "Reference" "TP22"
			(at 0 0 270)
			(layer "F.SilkS")
			(hide yes)
			(effects
				(font
					(size 1.27 1.27)
				)
			)
		)
		(property "Value" "TPAD32-GP"
			(at 0 -3.166364 270)
			(unlocked yes)
			(layer "F.Fab")
			(hide yes)
			(effects
				(font
					(size 1.016 1.016)
					(thickness 0.1524)
				)
			)
		)
		(property "Device Type" "TPAD32"
			(at 0 -4.690618 270)
			(unlocked yes)
			(layer "F.Fab")
			(hide yes)
			(effects
				(font
					(size 1.016 1.016)
					(thickness 0.1524)
				)
			)
		)
		(duplicate_pad_numbers_are_jumpers no)
		(fp_poly
			(pts
				(arc
					(start 0 -0.7112)
					(mid 0 0.7112)
					(end 0 -0.7112)
				)
			)
			(stroke
				(width 0)
				(type default)
			)
			(fill no)
			(layer "F.CrtYd")
		)
		(fp_poly
			(pts
				(arc
					(start 0 -0.7112)
					(mid 0 0.7112)
					(end 0 -0.7112)
				)
			)
			(stroke
				(width 0)
				(type default)
			)
			(fill no)
			(layer "F.Fab")
		)
		(pad "1" smd circle
			(at 0 0 270)
			(size 0.8128 0.8128)
			(layers "F.Cu" "F.Mask" "F.Paste")
			(net "ADM1276_GPIO2")
		)
	)
	(footprint ""
		(layer "F.Cu")
		(at 22.733 -179.8066 -90)
		(property "Reference" "R83"
			(at 0 0 270)
			(layer "F.SilkS")
			(hide yes)
			(effects
				(font
					(size 1.27 1.27)
				)
			)
		)
		(property "Value" "4K7R2F-GP"
			(at 0.064008 -3.993896 270)
			(unlocked yes)
			(layer "F.Fab")
			(hide yes)
			(effects
				(font
					(size 1.016 1.016)
					(thickness 0.1524)
				)
			)
		)
		(property "Device Type" "R402H16"
			(at 0.064008 -5.517896 270)
			(unlocked yes)
			(layer "F.Fab")
			(hide yes)
			(effects
				(font
					(size 1.016 1.016)
					(thickness 0.1524)
				)
			)
		)
		(duplicate_pad_numbers_are_jumpers no)
		(fp_line
			(start -0.508 -0.9398)
			(end -0.508 0.9398)
			(stroke
				(width 0.1524)
				(type default)
			)
			(layer "F.SilkS")
		)
		(fp_line
			(start 0.508 -0.9398)
			(end -0.508 -0.9398)
			(stroke
				(width 0.1524)
				(type default)
			)
			(layer "F.SilkS")
		)
		(fp_rect
			(start -0.508 0.9398)
			(end 0.508 -0.9398)
			(stroke
				(width 0)
				(type default)
			)
			(fill no)
			(layer "F.CrtYd")
		)
		(fp_rect
			(start -0.508 0.9398)
			(end 0.508 -0.9398)
			(stroke
				(width 0)
				(type default)
			)
			(fill no)
			(layer "F.Fab")
		)
		(pad "1" smd custom
			(at 0 -0.4445 270)
			(size 0.1397 0.1397)
			(layers "F.Cu" "F.Mask" "F.Paste")
			(net "P12V")
			(options
				(clearance outline)
				(anchor circle)
			)
			(primitives
				(gr_poly
					(pts
						(arc
							(start -0.1778 -0.2794)
							(mid -0.249642 -0.249642)
							(end -0.2794 -0.1778)
						)
						(arc
							(start -0.2794 0.1778)
							(mid -0.249642 0.249642)
							(end -0.1778 0.2794)
						)
						(arc
							(start 0.1778 0.2794)
							(mid 0.249642 0.249642)
							(end 0.2794 0.1778)
						)
						(arc
							(start 0.2794 -0.1778)
							(mid 0.249642 -0.249642)
							(end 0.1778 -0.2794)
						)
					)
					(width 0)
					(fill yes)
				)
			)
		)
		(pad "2" smd custom
			(at 0 0.4445 270)
			(size 0.1397 0.1397)
			(layers "F.Cu" "F.Mask" "F.Paste")
			(net "FAN_TACH7")
			(options
				(clearance outline)
				(anchor circle)
			)
			(primitives
				(gr_poly
					(pts
						(arc
							(start -0.1778 -0.2794)
							(mid -0.249642 -0.249642)
							(end -0.2794 -0.1778)
						)
						(arc
							(start -0.2794 0.1778)
							(mid -0.249642 0.249642)
							(end -0.1778 0.2794)
						)
						(arc
							(start 0.1778 0.2794)
							(mid 0.249642 0.249642)
							(end 0.2794 0.1778)
						)
						(arc
							(start 0.2794 -0.1778)
							(mid 0.249642 -0.249642)
							(end 0.1778 -0.2794)
						)
					)
					(width 0)
					(fill yes)
				)
			)
		)
	)
	(footprint ""
		(layer "F.Cu")
		(at 26.67 -153.2128 180)
		(property "Reference" "TP1"
			(at 0 0 180)
			(layer "F.SilkS")
			(hide yes)
			(effects
				(font
					(size 1.27 1.27)
				)
			)
		)
		(property "Value" "TPAD32-GP"
			(at 0 -3.166364 180)
			(unlocked yes)
			(layer "F.Fab")
			(hide yes)
			(effects
				(font
					(size 1.016 1.016)
					(thickness 0.1524)
				)
			)
		)
		(property "Device Type" "TPAD32"
			(at 0 -4.690618 180)
			(unlocked yes)
			(layer "F.Fab")
			(hide yes)
			(effects
				(font
					(size 1.016 1.016)
					(thickness 0.1524)
				)
			)
		)
		(duplicate_pad_numbers_are_jumpers no)
		(fp_poly
			(pts
				(arc
					(start -0.7112 0)
					(mid 0.7112 0)
					(end -0.7112 0)
				)
			)
			(stroke
				(width 0)
				(type default)
			)
			(fill no)
			(layer "F.CrtYd")
		)
		(fp_poly
			(pts
				(arc
					(start -0.7112 0)
					(mid 0.7112 0)
					(end -0.7112 0)
				)
			)
			(stroke
				(width 0)
				(type default)
			)
			(fill no)
			(layer "F.Fab")
		)
		(pad "1" smd circle
			(at 0 0 180)
			(size 0.8128 0.8128)
			(layers "F.Cu" "F.Mask" "F.Paste")
			(net "NCT7904_VREF")
		)
	)
	(footprint ""
		(layer "F.Cu")
		(at 26.035 -267.6398 90)
		(property "Reference" "C39"
			(at 0 0 90)
			(layer "F.SilkS")
			(hide yes)
			(effects
				(font
					(size 1.27 1.27)
				)
			)
		)
		(property "Value" "SCD1U50V3KX-GP"
			(at 0 -2.8194 90)
			(unlocked yes)
			(layer "F.Fab")
			(hide yes)
			(effects
				(font
					(size 1.016 1.016)
					(thickness 0.1524)
				)
			)
		)
		(property "Device Type" "C603H36"
			(at 0 -4.3434 90)
			(unlocked yes)
			(layer "F.Fab")
			(hide yes)
			(effects
				(font
					(size 1.016 1.016)
					(thickness 0.1524)
				)
			)
		)
		(duplicate_pad_numbers_are_jumpers no)
		(fp_line
			(start 0.508 0)
			(end -0.508 0)
			(stroke
				(width 0.2032)
				(type default)
			)
			(layer "F.SilkS")
		)
		(fp_rect
			(start -0.5842 1.3335)
			(end 0.5842 -1.3335)
			(stroke
				(width 0)
				(type default)
			)
			(fill no)
			(layer "F.CrtYd")
		)
		(fp_rect
			(start -0.5842 1.3335)
			(end 0.5842 -1.3335)
			(stroke
				(width 0)
				(type default)
			)
			(fill no)
			(layer "F.Fab")
		)
		(pad "1" smd custom
			(at 0 -0.762 90)
			(size 0.2159 0.2159)
			(layers "F.Cu" "F.Mask" "F.Paste")
			(net "P12V")
			(options
				(clearance outline)
				(anchor circle)
			)
			(primitives
				(gr_poly
					(pts
						(arc
							(start -0.3302 -0.4318)
							(mid -0.402042 -0.402042)
							(end -0.4318 -0.3302)
						)
						(arc
							(start -0.4318 0.3302)
							(mid -0.402042 0.402042)
							(end -0.3302 0.4318)
						)
						(arc
							(start 0.3302 0.4318)
							(mid 0.402042 0.402042)
							(end 0.4318 0.3302)
						)
						(arc
							(start 0.4318 -0.3302)
							(mid 0.402042 -0.402042)
							(end 0.3302 -0.4318)
						)
					)
					(width 0)
					(fill yes)
				)
			)
		)
		(pad "2" smd custom
			(at 0 0.762 90)
			(size 0.2159 0.2159)
			(layers "F.Cu" "F.Mask" "F.Paste")
			(net "GND")
			(options
				(clearance outline)
				(anchor circle)
			)
			(primitives
				(gr_poly
					(pts
						(arc
							(start -0.3302 -0.4318)
							(mid -0.402042 -0.402042)
							(end -0.4318 -0.3302)
						)
						(arc
							(start -0.4318 0.3302)
							(mid -0.402042 0.402042)
							(end -0.3302 0.4318)
						)
						(arc
							(start 0.3302 0.4318)
							(mid 0.402042 0.402042)
							(end 0.4318 0.3302)
						)
						(arc
							(start 0.4318 -0.3302)
							(mid 0.402042 -0.402042)
							(end 0.3302 -0.4318)
						)
					)
					(width 0)
					(fill yes)
				)
			)
		)
	)
	(footprint ""
		(layer "F.Cu")
		(at 42.418 -371.221)
		(property "Reference" "PR43"
			(at 0 0 0)
			(layer "F.SilkS")
			(hide yes)
			(effects
				(font
					(size 1.27 1.27)
				)
			)
		)
		(property "Value" "1K5R5J-GP"
			(at 0 -8.9535 0)
			(unlocked yes)
			(layer "F.Fab")
			(hide yes)
			(effects
				(font
					(size 1.27 1.016)
					(thickness 0.1524)
				)
			)
		)
		(property "Device Type" "R805H24"
			(at 0 -10.6299 0)
			(unlocked yes)
			(layer "F.Fab")
			(hide yes)
			(effects
				(font
					(size 1.27 1.016)
					(thickness 0.1524)
				)
			)
		)
		(duplicate_pad_numbers_are_jumpers no)
		(fp_line
			(start -0.889 -1.7018)
			(end -0.889 0.2794)
			(stroke
				(width 0.1524)
				(type default)
			)
			(layer "F.SilkS")
		)
		(fp_line
			(start -0.889 0.0762)
			(end -0.889 1.7018)
			(stroke
				(width 0.1524)
				(type default)
			)
			(layer "F.SilkS")
		)
		(fp_line
			(start -0.889 1.7018)
			(end 0.889 1.7018)
			(stroke
				(width 0.1524)
				(type default)
			)
			(layer "F.SilkS")
		)
		(fp_line
			(start 0.889 -1.7018)
			(end -0.889 -1.7018)
			(stroke
				(width 0.1524)
				(type default)
			)
			(layer "F.SilkS")
		)
		(fp_line
			(start 0.889 -1.7018)
			(end 0.889 -0.381)
			(stroke
				(width 0.1524)
				(type default)
			)
			(layer "F.SilkS")
		)
		(fp_line
			(start 0.889 1.7018)
			(end 0.889 -0.508)
			(stroke
				(width 0.1524)
				(type default)
			)
			(layer "F.SilkS")
		)
		(fp_poly
			(pts
				(xy 0.9652 -1.778) (xy 0.9652 1.778) (xy -0.9652 1.778) (xy -0.9652 -1.778)
			)
			(stroke
				(width 0)
				(type default)
			)
			(fill no)
			(layer "F.CrtYd")
		)
		(fp_rect
			(start -0.9652 1.778)
			(end 0.9652 -1.778)
			(stroke
				(width 0)
				(type default)
			)
			(fill no)
			(layer "F.Fab")
		)
		(pad "1" smd rect
			(at 0 -0.9652)
			(size 1.397 1.143)
			(layers "F.Cu" "F.Mask" "F.Paste")
			(net "P12V_AUX")
		)
		(pad "2" smd rect
			(at 0 0.9652)
			(size 1.397 1.143)
			(layers "F.Cu" "F.Mask" "F.Paste")
			(net "ADM1276_EN_NET")
		)
	)
	(footprint ""
		(layer "F.Cu")
		(at 26.8732 -357.6574 -90)
		(property "Reference" "R367"
			(at 0 0 270)
			(layer "F.SilkS")
			(hide yes)
			(effects
				(font
					(size 1.27 1.27)
				)
			)
		)
		(property "Value" "10KR2F-2-GP"
			(at 0.064008 -3.993896 270)
			(unlocked yes)
			(layer "F.Fab")
			(hide yes)
			(effects
				(font
					(size 1.016 1.016)
					(thickness 0.1524)
				)
			)
		)
		(property "Device Type" "R402H16"
			(at 0.064008 -5.517896 270)
			(unlocked yes)
			(layer "F.Fab")
			(hide yes)
			(effects
				(font
					(size 1.016 1.016)
					(thickness 0.1524)
				)
			)
		)
		(duplicate_pad_numbers_are_jumpers no)
		(fp_line
			(start -0.508 -0.9398)
			(end -0.508 0.9398)
			(stroke
				(width 0.1524)
				(type default)
			)
			(layer "F.SilkS")
		)
		(fp_line
			(start 0.508 -0.9398)
			(end -0.508 -0.9398)
			(stroke
				(width 0.1524)
				(type default)
			)
			(layer "F.SilkS")
		)
		(fp_rect
			(start -0.508 0.9398)
			(end 0.508 -0.9398)
			(stroke
				(width 0)
				(type default)
			)
			(fill no)
			(layer "F.CrtYd")
		)
		(fp_rect
			(start -0.508 0.9398)
			(end 0.508 -0.9398)
			(stroke
				(width 0)
				(type default)
			)
			(fill no)
			(layer "F.Fab")
		)
		(pad "1" smd custom
			(at 0 -0.4445 270)
			(size 0.1397 0.1397)
			(layers "F.Cu" "F.Mask" "F.Paste")
			(net "P3V3")
			(options
				(clearance outline)
				(anchor circle)
			)
			(primitives
				(gr_poly
					(pts
						(arc
							(start -0.1778 -0.2794)
							(mid -0.249642 -0.249642)
							(end -0.2794 -0.1778)
						)
						(arc
							(start -0.2794 0.1778)
							(mid -0.249642 0.249642)
							(end -0.1778 0.2794)
						)
						(arc
							(start 0.1778 0.2794)
							(mid 0.249642 0.249642)
							(end 0.2794 0.1778)
						)
						(arc
							(start 0.2794 -0.1778)
							(mid 0.249642 -0.249642)
							(end 0.1778 -0.2794)
						)
					)
					(width 0)
					(fill yes)
				)
			)
		)
		(pad "2" smd custom
			(at 0 0.4445 270)
			(size 0.1397 0.1397)
			(layers "F.Cu" "F.Mask" "F.Paste")
			(net "TEMP_ALM#_G")
			(options
				(clearance outline)
				(anchor circle)
			)
			(primitives
				(gr_poly
					(pts
						(arc
							(start -0.1778 -0.2794)
							(mid -0.249642 -0.249642)
							(end -0.2794 -0.1778)
						)
						(arc
							(start -0.2794 0.1778)
							(mid -0.249642 0.249642)
							(end -0.1778 0.2794)
						)
						(arc
							(start 0.1778 0.2794)
							(mid 0.249642 0.249642)
							(end 0.2794 0.1778)
						)
						(arc
							(start 0.2794 -0.1778)
							(mid 0.249642 -0.249642)
							(end 0.1778 -0.2794)
						)
					)
					(width 0)
					(fill yes)
				)
			)
		)
	)
	(footprint ""
		(layer "F.Cu")
		(at 35.59429 -150.680166 180)
		(property "Reference" "TP11"
			(at 0 0 180)
			(layer "F.SilkS")
			(hide yes)
			(effects
				(font
					(size 1.27 1.27)
				)
			)
		)
		(property "Value" "TPAD32-GP"
			(at 0 -3.166364 180)
			(unlocked yes)
			(layer "F.Fab")
			(hide yes)
			(effects
				(font
					(size 1.016 1.016)
					(thickness 0.1524)
				)
			)
		)
		(property "Device Type" "TPAD32"
			(at 0 -4.690618 180)
			(unlocked yes)
			(layer "F.Fab")
			(hide yes)
			(effects
				(font
					(size 1.016 1.016)
					(thickness 0.1524)
				)
			)
		)
		(duplicate_pad_numbers_are_jumpers no)
		(fp_poly
			(pts
				(arc
					(start 0.7112 0)
					(mid -0.7112 0)
					(end 0.7112 0)
				)
			)
			(stroke
				(width 0)
				(type default)
			)
			(fill no)
			(layer "F.CrtYd")
		)
		(fp_poly
			(pts
				(arc
					(start 0.7112 0)
					(mid -0.7112 0)
					(end 0.7112 0)
				)
			)
			(stroke
				(width 0)
				(type default)
			)
			(fill no)
			(layer "F.Fab")
		)
		(pad "1" smd circle
			(at 0 0 180)
			(size 0.8128 0.8128)
			(layers "F.Cu" "F.Mask" "F.Paste")
			(net "NCT7904_VSEN12")
		)
	)
	(footprint ""
		(layer "F.Cu")
		(at 14.8844 -43.5102 -90)
		(property "Reference" "R118"
			(at 0 0 270)
			(layer "F.SilkS")
			(hide yes)
			(effects
				(font
					(size 1.27 1.27)
				)
			)
		)
		(property "Value" "470R2F-GP"
			(at 0.064008 -3.993896 270)
			(unlocked yes)
			(layer "F.Fab")
			(hide yes)
			(effects
				(font
					(size 1.016 1.016)
					(thickness 0.1524)
				)
			)
		)
		(property "Device Type" "R402H16"
			(at 0.064008 -5.517896 270)
			(unlocked yes)
			(layer "F.Fab")
			(hide yes)
			(effects
				(font
					(size 1.016 1.016)
					(thickness 0.1524)
				)
			)
		)
		(duplicate_pad_numbers_are_jumpers no)
		(fp_line
			(start -0.508 -0.9398)
			(end -0.508 0.9398)
			(stroke
				(width 0.1524)
				(type default)
			)
			(layer "F.SilkS")
		)
		(fp_line
			(start 0.508 -0.9398)
			(end -0.508 -0.9398)
			(stroke
				(width 0.1524)
				(type default)
			)
			(layer "F.SilkS")
		)
		(fp_rect
			(start -0.508 0.9398)
			(end 0.508 -0.9398)
			(stroke
				(width 0)
				(type default)
			)
			(fill no)
			(layer "F.CrtYd")
		)
		(fp_rect
			(start -0.508 0.9398)
			(end 0.508 -0.9398)
			(stroke
				(width 0)
				(type default)
			)
			(fill no)
			(layer "F.Fab")
		)
		(pad "1" smd custom
			(at 0 -0.4445 270)
			(size 0.1397 0.1397)
			(layers "F.Cu" "F.Mask" "F.Paste")
			(net "SEB_PEER_2A_HB")
			(options
				(clearance outline)
				(anchor circle)
			)
			(primitives
				(gr_poly
					(pts
						(arc
							(start -0.1778 -0.2794)
							(mid -0.249642 -0.249642)
							(end -0.2794 -0.1778)
						)
						(arc
							(start -0.2794 0.1778)
							(mid -0.249642 0.249642)
							(end -0.1778 0.2794)
						)
						(arc
							(start 0.1778 0.2794)
							(mid 0.249642 0.249642)
							(end 0.2794 0.1778)
						)
						(arc
							(start 0.2794 -0.1778)
							(mid 0.249642 -0.249642)
							(end 0.1778 -0.2794)
						)
					)
					(width 0)
					(fill yes)
				)
			)
		)
		(pad "2" smd custom
			(at 0 0.4445 270)
			(size 0.1397 0.1397)
			(layers "F.Cu" "F.Mask" "F.Paste")
			(net "GND")
			(options
				(clearance outline)
				(anchor circle)
			)
			(primitives
				(gr_poly
					(pts
						(arc
							(start -0.1778 -0.2794)
							(mid -0.249642 -0.249642)
							(end -0.2794 -0.1778)
						)
						(arc
							(start -0.2794 0.1778)
							(mid -0.249642 0.249642)
							(end -0.1778 0.2794)
						)
						(arc
							(start 0.1778 0.2794)
							(mid 0.249642 0.249642)
							(end 0.2794 0.1778)
						)
						(arc
							(start 0.2794 -0.1778)
							(mid 0.249642 -0.249642)
							(end 0.1778 -0.2794)
						)
					)
					(width 0)
					(fill yes)
				)
			)
		)
	)
	(footprint ""
		(layer "F.Cu")
		(at 21.6916 -140.4366 180)
		(property "Reference" "PU6"
			(at 0 0 180)
			(layer "F.SilkS")
			(hide yes)
			(effects
				(font
					(size 1.27 1.27)
				)
			)
		)
		(property "Value" "TPS2490DGSR-GP"
			(at 0 -11.1252 180)
			(unlocked yes)
			(layer "F.Fab")
			(hide yes)
			(effects
				(font
					(size 1.016 1.016)
					(thickness 0.1524)
				)
			)
		)
		(property "Device Type" "MSOP10H44"
			(at 0 -12.6492 180)
			(unlocked yes)
			(layer "F.Fab")
			(hide yes)
			(effects
				(font
					(size 1.016 1.016)
					(thickness 0.1524)
				)
			)
		)
		(duplicate_pad_numbers_are_jumpers no)
		(fp_line
			(start 1.143 1.016)
			(end -2.0066 1.016)
			(stroke
				(width 0.1524)
				(type default)
			)
			(layer "F.SilkS")
		)
		(fp_line
			(start 1.143 -1.016)
			(end 1.143 1.016)
			(stroke
				(width 0.1524)
				(type default)
			)
			(layer "F.SilkS")
		)
		(fp_line
			(start -1.5748 0)
			(end -1.9558 0.381)
			(stroke
				(width 0.1524)
				(type default)
			)
			(layer "F.SilkS")
		)
		(fp_line
			(start -1.5748 0)
			(end -1.9558 -0.381)
			(stroke
				(width 0.1524)
				(type default)
			)
			(layer "F.SilkS")
		)
		(fp_line
			(start -1.8288 1.016)
			(end -1.8288 3.048)
			(stroke
				(width 0.508)
				(type default)
			)
			(layer "F.SilkS")
		)
		(fp_line
			(start -2.0066 1.016)
			(end -2.0066 -1.016)
			(stroke
				(width 0.1524)
				(type default)
			)
			(layer "F.SilkS")
		)
		(fp_line
			(start -2.0066 -1.016)
			(end 1.143 -1.016)
			(stroke
				(width 0.1524)
				(type default)
			)
			(layer "F.SilkS")
		)
		(fp_poly
			(pts
				(xy -2.0828 3.3401) (xy 2.0828 3.3401) (xy 2.0828 -3.3401) (xy -2.0828 -3.3401)
			)
			(stroke
				(width 0)
				(type default)
			)
			(fill no)
			(layer "F.CrtYd")
		)
		(fp_poly
			(pts
				(xy -2.0828 3.3401) (xy 2.0828 3.3401) (xy 2.0828 -3.3401) (xy -2.0828 -3.3401)
			)
			(stroke
				(width 0)
				(type default)
			)
			(fill no)
			(layer "F.Fab")
		)
		(pad "1" smd rect
			(at -0.99949 2.0701 180)
			(size 0.3048 1.524)
			(layers "F.Cu" "F.Mask" "F.Paste")
			(net "P12VU_2490_EN_2")
		)
		(pad "2" smd rect
			(at -0.50038 2.0701 180)
			(size 0.3048 1.524)
			(layers "F.Cu" "F.Mask" "F.Paste")
			(net "P12VU_2490_VREF")
		)
		(pad "3" smd rect
			(at 0 2.0701 180)
			(size 0.3048 1.524)
			(layers "F.Cu" "F.Mask" "F.Paste")
			(net "P12VU_2490_PROG")
		)
		(pad "4" smd rect
			(at 0.50038 2.0701 180)
			(size 0.3048 1.524)
			(layers "F.Cu" "F.Mask" "F.Paste")
			(net "P12VU_2490_TIMER")
		)
		(pad "5" smd rect
			(at 0.99949 2.0701 180)
			(size 0.3048 1.524)
			(layers "F.Cu" "F.Mask" "F.Paste")
			(net "GND")
		)
		(pad "6" smd rect
			(at 0.99949 -2.0701 180)
			(size 0.3048 1.524)
			(layers "F.Cu" "F.Mask" "F.Paste")
			(net "P12VU_2490_PG")
		)
		(pad "7" smd rect
			(at 0.50038 -2.0701 180)
			(size 0.3048 1.524)
			(layers "F.Cu" "F.Mask" "F.Paste")
			(net "P12VU")
		)
		(pad "8" smd rect
			(at 0 -2.0701 180)
			(size 0.3048 1.524)
			(layers "F.Cu" "F.Mask" "F.Paste")
			(net "P12VU_2490_GATE")
		)
		(pad "9" smd rect
			(at -0.50038 -2.0701 180)
			(size 0.3048 1.524)
			(layers "F.Cu" "F.Mask" "F.Paste")
			(net "P12VU_2490_SENSE")
		)
		(pad "10" smd rect
			(at -0.99949 -2.0701 180)
			(size 0.3048 1.524)
			(layers "F.Cu" "F.Mask" "F.Paste")
			(net "P12VU_2490_VCC")
		)
	)
	(footprint ""
		(layer "F.Cu")
		(at 8.763 -69.1642 90)
		(property "Reference" "R166"
			(at 0 0 90)
			(layer "F.SilkS")
			(hide yes)
			(effects
				(font
					(size 1.27 1.27)
				)
			)
		)
		(property "Value" "4K7R2F-GP"
			(at 0.064008 -3.993896 90)
			(unlocked yes)
			(layer "F.Fab")
			(hide yes)
			(effects
				(font
					(size 1.016 1.016)
					(thickness 0.1524)
				)
			)
		)
		(property "Device Type" "R402H16"
			(at 0.064008 -5.517896 90)
			(unlocked yes)
			(layer "F.Fab")
			(hide yes)
			(effects
				(font
					(size 1.016 1.016)
					(thickness 0.1524)
				)
			)
		)
		(duplicate_pad_numbers_are_jumpers no)
		(fp_line
			(start 0.508 -0.9398)
			(end -0.508 -0.9398)
			(stroke
				(width 0.1524)
				(type default)
			)
			(layer "F.SilkS")
		)
		(fp_line
			(start -0.508 -0.9398)
			(end -0.508 0.9398)
			(stroke
				(width 0.1524)
				(type default)
			)
			(layer "F.SilkS")
		)
		(fp_rect
			(start -0.508 0.9398)
			(end 0.508 -0.9398)
			(stroke
				(width 0)
				(type default)
			)
			(fill no)
			(layer "F.CrtYd")
		)
		(fp_rect
			(start -0.508 0.9398)
			(end 0.508 -0.9398)
			(stroke
				(width 0)
				(type default)
			)
			(fill no)
			(layer "F.Fab")
		)
		(pad "1" smd custom
			(at 0 -0.4445 90)
			(size 0.1397 0.1397)
			(layers "F.Cu" "F.Mask" "F.Paste")
			(net "P3V3")
			(options
				(clearance outline)
				(anchor circle)
			)
			(primitives
				(gr_poly
					(pts
						(arc
							(start -0.1778 -0.2794)
							(mid -0.249642 -0.249642)
							(end -0.2794 -0.1778)
						)
						(arc
							(start -0.2794 0.1778)
							(mid -0.249642 0.249642)
							(end -0.1778 0.2794)
						)
						(arc
							(start 0.1778 0.2794)
							(mid 0.249642 0.249642)
							(end 0.2794 0.1778)
						)
						(arc
							(start 0.2794 -0.1778)
							(mid 0.249642 -0.249642)
							(end 0.1778 -0.2794)
						)
					)
					(width 0)
					(fill yes)
				)
			)
		)
		(pad "2" smd custom
			(at 0 0.4445 90)
			(size 0.1397 0.1397)
			(layers "F.Cu" "F.Mask" "F.Paste")
			(net "PWM_BUFFER_IN_FAN3_FAN4")
			(options
				(clearance outline)
				(anchor circle)
			)
			(primitives
				(gr_poly
					(pts
						(arc
							(start -0.1778 -0.2794)
							(mid -0.249642 -0.249642)
							(end -0.2794 -0.1778)
						)
						(arc
							(start -0.2794 0.1778)
							(mid -0.249642 0.249642)
							(end -0.1778 0.2794)
						)
						(arc
							(start 0.1778 0.2794)
							(mid 0.249642 0.249642)
							(end 0.2794 0.1778)
						)
						(arc
							(start 0.2794 -0.1778)
							(mid 0.249642 -0.249642)
							(end 0.1778 -0.2794)
						)
					)
					(width 0)
					(fill yes)
				)
			)
		)
	)
	(footprint ""
		(layer "F.Cu")
		(at 6.999986 -459.999842)
		(property "Reference" "H5"
			(at 0 0 0)
			(layer "F.SilkS")
			(hide yes)
			(effects
				(font
					(size 1.27 1.27)
				)
			)
		)
		(property "Value" "HOLE315R138"
			(at 0 -7.0612 0)
			(unlocked yes)
			(layer "F.Fab")
			(hide yes)
			(effects
				(font
					(size 1.016 1.016)
					(thickness 0.1524)
				)
			)
		)
		(property "Device Type" "HOLE315R138"
			(at 0 -8.5852 0)
			(unlocked yes)
			(layer "F.Fab")
			(hide yes)
			(effects
				(font
					(size 1.016 1.016)
					(thickness 0.1524)
				)
			)
		)
		(duplicate_pad_numbers_are_jumpers no)
		(fp_poly
			(pts
				(xy 0 4.3053) (xy -0.13462 4.30276) (xy -0.27051 4.29641) (xy -0.40513 4.28625) (xy -0.53975 4.27101)
				(xy -0.6731 4.25196) (xy -0.80645 4.2291) (xy -0.9398 4.20116) (xy -1.07061 4.17068) (xy -1.20142 4.13385)
				(xy -1.33096 4.09448) (xy -1.45796 4.0513) (xy -1.58496 4.00304) (xy -1.70942 3.95097) (xy -1.83261 3.89509)
				(xy -1.95453 3.83667) (xy -2.07391 3.77317) (xy -2.19202 3.70586) (xy -2.30632 3.63474) (xy -2.41935 3.56108)
				(xy -2.53111 3.48361) (xy -2.63906 3.40233) (xy -2.74447 3.31724) (xy -2.84734 3.22961) (xy -2.94767 3.13817)
				(xy -3.04419 3.04419) (xy -3.13817 2.94767) (xy -3.22961 2.84734) (xy -3.31724 2.74447) (xy -3.40233 2.63906)
				(xy -3.48361 2.53111) (xy -3.56108 2.41935) (xy -3.63474 2.30632) (xy -3.70586 2.19202) (xy -3.77317 2.07391)
				(xy -3.83667 1.95453) (xy -3.89509 1.83261) (xy -3.95097 1.70942) (xy -4.00304 1.58496) (xy -4.0513 1.45796)
				(xy -4.09448 1.33096) (xy -4.13385 1.20142) (xy -4.17068 1.07061) (xy -4.20116 0.9398) (xy -4.2291 0.80645)
				(xy -4.25196 0.6731) (xy -4.27101 0.53975) (xy -4.28625 0.40513) (xy -4.29641 0.27051) (xy -4.30276 0.13462)
				(xy -4.3053 0) (xy -4.30276 -0.13462) (xy -4.29641 -0.27051) (xy -4.28625 -0.40513) (xy -4.27101 -0.53975)
				(xy -4.25196 -0.6731) (xy -4.2291 -0.80645) (xy -4.20116 -0.9398) (xy -4.17068 -1.07061) (xy -4.13385 -1.20142)
				(xy -4.09448 -1.33096) (xy -4.0513 -1.45796) (xy -4.00304 -1.58496) (xy -3.95097 -1.70942) (xy -3.89509 -1.83261)
				(xy -3.83667 -1.95453) (xy -3.77317 -2.07391) (xy -3.70586 -2.19202) (xy -3.63474 -2.30632) (xy -3.56108 -2.41935)
				(xy -3.48361 -2.53111) (xy -3.40233 -2.63906) (xy -3.31724 -2.74447) (xy -3.22961 -2.84734) (xy -3.13817 -2.94767)
				(xy -3.04419 -3.04419) (xy -2.94767 -3.13817) (xy -2.84734 -3.22961) (xy -2.74447 -3.31724) (xy -2.63906 -3.40233)
				(xy -2.53111 -3.48361) (xy -2.41935 -3.56108) (xy -2.30632 -3.63474) (xy -2.19202 -3.70586) (xy -2.07391 -3.77317)
				(xy -1.95453 -3.83667) (xy -1.83261 -3.89509) (xy -1.70942 -3.95097) (xy -1.58496 -4.00304) (xy -1.45796 -4.0513)
				(xy -1.33096 -4.09448) (xy -1.20142 -4.13385) (xy -1.07061 -4.17068) (xy -0.9398 -4.20116) (xy -0.80645 -4.2291)
				(xy -0.6731 -4.25196) (xy -0.53975 -4.27101) (xy -0.40513 -4.28625) (xy -0.27051 -4.29641) (xy -0.13462 -4.30276)
				(xy 0 -4.3053) (xy 0.13462 -4.30276) (xy 0.27051 -4.29641) (xy 0.40513 -4.28625) (xy 0.53975 -4.27101)
				(xy 0.6731 -4.25196) (xy 0.80645 -4.2291) (xy 0.9398 -4.20116) (xy 1.07061 -4.17068) (xy 1.20142 -4.13385)
				(xy 1.33096 -4.09448) (xy 1.45796 -4.0513) (xy 1.58496 -4.00304) (xy 1.70942 -3.95097) (xy 1.83261 -3.89509)
				(xy 1.95453 -3.83667) (xy 2.07391 -3.77317) (xy 2.19202 -3.70586) (xy 2.30632 -3.63474) (xy 2.41935 -3.56108)
				(xy 2.53111 -3.48361) (xy 2.63906 -3.40233) (xy 2.74447 -3.31724) (xy 2.84734 -3.22961) (xy 2.94767 -3.13817)
				(xy 3.04419 -3.04419) (xy 3.13817 -2.94767) (xy 3.22961 -2.84734) (xy 3.31724 -2.74447) (xy 3.40233 -2.63906)
				(xy 3.48361 -2.53111) (xy 3.56108 -2.41935) (xy 3.63474 -2.30632) (xy 3.70586 -2.19202) (xy 3.77317 -2.07391)
				(xy 3.83667 -1.95453) (xy 3.89509 -1.83261) (xy 3.95097 -1.70942) (xy 4.00304 -1.58496) (xy 4.0513 -1.45796)
				(xy 4.09448 -1.33096) (xy 4.13385 -1.20142) (xy 4.17068 -1.07061) (xy 4.20116 -0.9398) (xy 4.2291 -0.80645)
				(xy 4.25196 -0.6731) (xy 4.27101 -0.53975) (xy 4.28625 -0.40513) (xy 4.29641 -0.27051) (xy 4.30276 -0.13462)
				(xy 4.3053 0) (xy 4.30276 0.13462) (xy 4.29641 0.27051) (xy 4.28625 0.40513) (xy 4.27101 0.53975)
				(xy 4.25196 0.6731) (xy 4.2291 0.80645) (xy 4.20116 0.9398) (xy 4.17068 1.07061) (xy 4.13385 1.20142)
				(xy 4.09448 1.33096) (xy 4.0513 1.45796) (xy 4.00304 1.58496) (xy 3.95097 1.70942) (xy 3.89509 1.83261)
				(xy 3.83667 1.95453) (xy 3.77317 2.07391) (xy 3.70586 2.19202) (xy 3.63474 2.30632) (xy 3.56108 2.41935)
				(xy 3.48361 2.53111) (xy 3.40233 2.63906) (xy 3.31724 2.74447) (xy 3.22961 2.84734) (xy 3.13817 2.94767)
				(xy 3.04419 3.04419) (xy 2.94767 3.13817) (xy 2.84734 3.22961) (xy 2.74447 3.31724) (xy 2.63906 3.40233)
				(xy 2.53111 3.48361) (xy 2.41935 3.56108) (xy 2.30632 3.63474) (xy 2.19202 3.70586) (xy 2.07391 3.77317)
				(xy 1.95453 3.83667) (xy 1.83261 3.89509) (xy 1.70942 3.95097) (xy 1.58496 4.00304) (xy 1.45796 4.0513)
				(xy 1.33096 4.09448) (xy 1.20142 4.13385) (xy 1.07061 4.17068) (xy 0.9398 4.20116) (xy 0.80645 4.2291)
				(xy 0.6731 4.25196) (xy 0.53975 4.27101) (xy 0.40513 4.28625) (xy 0.27051 4.29641) (xy 0.13462 4.30276)
			)
			(stroke
				(width 0)
				(type default)
			)
			(fill no)
			(layer "F.CrtYd")
		)
		(fp_poly
			(pts
				(xy 0 4.3053) (xy -0.13462 4.30276) (xy -0.27051 4.29641) (xy -0.40513 4.28625) (xy -0.53975 4.27101)
				(xy -0.6731 4.25196) (xy -0.80645 4.2291) (xy -0.9398 4.20116) (xy -1.07061 4.17068) (xy -1.20142 4.13385)
				(xy -1.33096 4.09448) (xy -1.45796 4.0513) (xy -1.58496 4.00304) (xy -1.70942 3.95097) (xy -1.83261 3.89509)
				(xy -1.95453 3.83667) (xy -2.07391 3.77317) (xy -2.19202 3.70586) (xy -2.30632 3.63474) (xy -2.41935 3.56108)
				(xy -2.53111 3.48361) (xy -2.63906 3.40233) (xy -2.74447 3.31724) (xy -2.84734 3.22961) (xy -2.94767 3.13817)
				(xy -3.04419 3.04419) (xy -3.13817 2.94767) (xy -3.22961 2.84734) (xy -3.31724 2.74447) (xy -3.40233 2.63906)
				(xy -3.48361 2.53111) (xy -3.56108 2.41935) (xy -3.63474 2.30632) (xy -3.70586 2.19202) (xy -3.77317 2.07391)
				(xy -3.83667 1.95453) (xy -3.89509 1.83261) (xy -3.95097 1.70942) (xy -4.00304 1.58496) (xy -4.0513 1.45796)
				(xy -4.09448 1.33096) (xy -4.13385 1.20142) (xy -4.17068 1.07061) (xy -4.20116 0.9398) (xy -4.2291 0.80645)
				(xy -4.25196 0.6731) (xy -4.27101 0.53975) (xy -4.28625 0.40513) (xy -4.29641 0.27051) (xy -4.30276 0.13462)
				(xy -4.3053 0) (xy -4.30276 -0.13462) (xy -4.29641 -0.27051) (xy -4.28625 -0.40513) (xy -4.27101 -0.53975)
				(xy -4.25196 -0.6731) (xy -4.2291 -0.80645) (xy -4.20116 -0.9398) (xy -4.17068 -1.07061) (xy -4.13385 -1.20142)
				(xy -4.09448 -1.33096) (xy -4.0513 -1.45796) (xy -4.00304 -1.58496) (xy -3.95097 -1.70942) (xy -3.89509 -1.83261)
				(xy -3.83667 -1.95453) (xy -3.77317 -2.07391) (xy -3.70586 -2.19202) (xy -3.63474 -2.30632) (xy -3.56108 -2.41935)
				(xy -3.48361 -2.53111) (xy -3.40233 -2.63906) (xy -3.31724 -2.74447) (xy -3.22961 -2.84734) (xy -3.13817 -2.94767)
				(xy -3.04419 -3.04419) (xy -2.94767 -3.13817) (xy -2.84734 -3.22961) (xy -2.74447 -3.31724) (xy -2.63906 -3.40233)
				(xy -2.53111 -3.48361) (xy -2.41935 -3.56108) (xy -2.30632 -3.63474) (xy -2.19202 -3.70586) (xy -2.07391 -3.77317)
				(xy -1.95453 -3.83667) (xy -1.83261 -3.89509) (xy -1.70942 -3.95097) (xy -1.58496 -4.00304) (xy -1.45796 -4.0513)
				(xy -1.33096 -4.09448) (xy -1.20142 -4.13385) (xy -1.07061 -4.17068) (xy -0.9398 -4.20116) (xy -0.80645 -4.2291)
				(xy -0.6731 -4.25196) (xy -0.53975 -4.27101) (xy -0.40513 -4.28625) (xy -0.27051 -4.29641) (xy -0.13462 -4.30276)
				(xy 0 -4.3053) (xy 0.13462 -4.30276) (xy 0.27051 -4.29641) (xy 0.40513 -4.28625) (xy 0.53975 -4.27101)
				(xy 0.6731 -4.25196) (xy 0.80645 -4.2291) (xy 0.9398 -4.20116) (xy 1.07061 -4.17068) (xy 1.20142 -4.13385)
				(xy 1.33096 -4.09448) (xy 1.45796 -4.0513) (xy 1.58496 -4.00304) (xy 1.70942 -3.95097) (xy 1.83261 -3.89509)
				(xy 1.95453 -3.83667) (xy 2.07391 -3.77317) (xy 2.19202 -3.70586) (xy 2.30632 -3.63474) (xy 2.41935 -3.56108)
				(xy 2.53111 -3.48361) (xy 2.63906 -3.40233) (xy 2.74447 -3.31724) (xy 2.84734 -3.22961) (xy 2.94767 -3.13817)
				(xy 3.04419 -3.04419) (xy 3.13817 -2.94767) (xy 3.22961 -2.84734) (xy 3.31724 -2.74447) (xy 3.40233 -2.63906)
				(xy 3.48361 -2.53111) (xy 3.56108 -2.41935) (xy 3.63474 -2.30632) (xy 3.70586 -2.19202) (xy 3.77317 -2.07391)
				(xy 3.83667 -1.95453) (xy 3.89509 -1.83261) (xy 3.95097 -1.70942) (xy 4.00304 -1.58496) (xy 4.0513 -1.45796)
				(xy 4.09448 -1.33096) (xy 4.13385 -1.20142) (xy 4.17068 -1.07061) (xy 4.20116 -0.9398) (xy 4.2291 -0.80645)
				(xy 4.25196 -0.6731) (xy 4.27101 -0.53975) (xy 4.28625 -0.40513) (xy 4.29641 -0.27051) (xy 4.30276 -0.13462)
				(xy 4.3053 0) (xy 4.30276 0.13462) (xy 4.29641 0.27051) (xy 4.28625 0.40513) (xy 4.27101 0.53975)
				(xy 4.25196 0.6731) (xy 4.2291 0.80645) (xy 4.20116 0.9398) (xy 4.17068 1.07061) (xy 4.13385 1.20142)
				(xy 4.09448 1.33096) (xy 4.0513 1.45796) (xy 4.00304 1.58496) (xy 3.95097 1.70942) (xy 3.89509 1.83261)
				(xy 3.83667 1.95453) (xy 3.77317 2.07391) (xy 3.70586 2.19202) (xy 3.63474 2.30632) (xy 3.56108 2.41935)
				(xy 3.48361 2.53111) (xy 3.40233 2.63906) (xy 3.31724 2.74447) (xy 3.22961 2.84734) (xy 3.13817 2.94767)
				(xy 3.04419 3.04419) (xy 2.94767 3.13817) (xy 2.84734 3.22961) (xy 2.74447 3.31724) (xy 2.63906 3.40233)
				(xy 2.53111 3.48361) (xy 2.41935 3.56108) (xy 2.30632 3.63474) (xy 2.19202 3.70586) (xy 2.07391 3.77317)
				(xy 1.95453 3.83667) (xy 1.83261 3.89509) (xy 1.70942 3.95097) (xy 1.58496 4.00304) (xy 1.45796 4.0513)
				(xy 1.33096 4.09448) (xy 1.20142 4.13385) (xy 1.07061 4.17068) (xy 0.9398 4.20116) (xy 0.80645 4.2291)
				(xy 0.6731 4.25196) (xy 0.53975 4.27101) (xy 0.40513 4.28625) (xy 0.27051 4.29641) (xy 0.13462 4.30276)
			)
			(stroke
				(width 0)
				(type default)
			)
			(fill no)
			(layer "F.Fab")
		)
		(pad "1" thru_hole circle
			(at 0 0)
			(size 8.001 8.001)
			(drill 3.5052)
			(layers "*.Cu" "*.Mask")
			(remove_unused_layers no)
			(net "GND")
			(clearance -1.7399)
			(thermal_gap 0.3048)
			(padstack
				(mode front_inner_back)
				(layer "Inner"
					(shape circle)
					(size 3.9116 3.9116)
					(clearance 0.3048)
				)
				(layer "B.Cu"
					(shape circle)
					(size 8.001 8.001)
					(clearance -1.7399)
				)
			)
		)
	)
	(footprint ""
		(layer "F.Cu")
		(at 37.338 -184.531 180)
		(property "Reference" "PC1262"
			(at 0 0 180)
			(layer "F.SilkS")
			(hide yes)
			(effects
				(font
					(size 1.27 1.27)
				)
			)
		)
		(property "Value" "SC10U16V6KX-2GP"
			(at -0.0762 -5.1308 180)
			(unlocked yes)
			(layer "F.Fab")
			(hide yes)
			(effects
				(font
					(size 1.016 1.016)
					(thickness 0.1524)
				)
			)
		)
		(property "Device Type" "C1206H71"
			(at -0.127 -6.6548 180)
			(unlocked yes)
			(layer "F.Fab")
			(hide yes)
			(effects
				(font
					(size 1.016 1.016)
					(thickness 0.1524)
				)
			)
		)
		(duplicate_pad_numbers_are_jumpers no)
		(fp_line
			(start 1.016 2.2352)
			(end -1.016 2.2352)
			(stroke
				(width 0.1524)
				(type default)
			)
			(layer "F.SilkS")
		)
		(fp_line
			(start 1.016 0.8382)
			(end 1.016 2.2352)
			(stroke
				(width 0.1524)
				(type default)
			)
			(layer "F.SilkS")
		)
		(fp_line
			(start 1.016 -2.2352)
			(end 1.016 -0.8382)
			(stroke
				(width 0.1524)
				(type default)
			)
			(layer "F.SilkS")
		)
		(fp_line
			(start -1.016 2.2352)
			(end -1.016 0.8382)
			(stroke
				(width 0.1524)
				(type default)
			)
			(layer "F.SilkS")
		)
		(fp_line
			(start -1.016 -0.8382)
			(end -1.016 -2.2352)
			(stroke
				(width 0.1524)
				(type default)
			)
			(layer "F.SilkS")
		)
		(fp_line
			(start -1.016 -2.2352)
			(end 1.016 -2.2352)
			(stroke
				(width 0.1524)
				(type default)
			)
			(layer "F.SilkS")
		)
		(fp_rect
			(start -1.0922 2.3114)
			(end 1.0922 -2.3114)
			(stroke
				(width 0)
				(type default)
			)
			(fill no)
			(layer "F.CrtYd")
		)
		(fp_poly
			(pts
				(xy 1.0922 -2.3114) (xy 1.0922 2.3114) (xy -1.0922 2.3114) (xy -1.0922 -2.3114)
			)
			(stroke
				(width 0)
				(type default)
			)
			(fill no)
			(layer "F.Fab")
		)
		(pad "1" smd rect
			(at 0 -1.397 180)
			(size 1.651 1.27)
			(layers "F.Cu" "F.Mask" "F.Paste")
			(net "P3V3_AUX")
		)
		(pad "2" smd rect
			(at 0 1.397 180)
			(size 1.651 1.27)
			(layers "F.Cu" "F.Mask" "F.Paste")
			(net "GND")
		)
	)
	(footprint ""
		(layer "F.Cu")
		(at 36.1442 -374.9802 180)
		(property "Reference" "PD1"
			(at 0 0 180)
			(layer "F.SilkS")
			(hide yes)
			(effects
				(font
					(size 1.27 1.27)
				)
			)
		)
		(property "Value" "MM3Z15VT1G-GP"
			(at 0 -6.7818 180)
			(unlocked yes)
			(layer "F.Fab")
			(hide yes)
			(effects
				(font
					(size 1.016 1.016)
					(thickness 0.1524)
				)
			)
		)
		(property "Device Type" "SOD323AKH44"
			(at 0 -8.6868 180)
			(unlocked yes)
			(layer "F.Fab")
			(hide yes)
			(effects
				(font
					(size 1.016 1.016)
					(thickness 0.1524)
				)
			)
		)
		(duplicate_pad_numbers_are_jumpers no)
		(fp_line
			(start 0.889 2.159)
			(end -0.889 2.159)
			(stroke
				(width 0.1524)
				(type default)
			)
			(layer "F.SilkS")
		)
		(fp_line
			(start 0.889 -1.9304)
			(end 0.889 2.159)
			(stroke
				(width 0.1524)
				(type default)
			)
			(layer "F.SilkS")
		)
		(fp_line
			(start 0.762 2.0574)
			(end -0.762 2.0574)
			(stroke
				(width 0.508)
				(type default)
			)
			(layer "F.SilkS")
		)
		(fp_line
			(start -0.889 2.159)
			(end -0.889 -1.9304)
			(stroke
				(width 0.1524)
				(type default)
			)
			(layer "F.SilkS")
		)
		(fp_line
			(start -0.889 -1.9304)
			(end 0.889 -1.9304)
			(stroke
				(width 0.1524)
				(type default)
			)
			(layer "F.SilkS")
		)
		(fp_rect
			(start -1.016 2.3114)
			(end 1.016 -2.0066)
			(stroke
				(width 0)
				(type default)
			)
			(fill no)
			(layer "F.CrtYd")
		)
		(fp_poly
			(pts
				(xy -1.016 -2.0066) (xy 1.016 -2.0066) (xy 1.016 2.3114) (xy -1.016 2.3114)
			)
			(stroke
				(width 0)
				(type default)
			)
			(fill no)
			(layer "F.Fab")
		)
		(pad "A" smd rect
			(at 0 -1.143 180)
			(size 0.5588 1.016)
			(layers "F.Cu" "F.Mask" "F.Paste")
			(net "ADM1276_GATE_RSV")
		)
		(pad "K" smd rect
			(at 0 1.143 180)
			(size 0.5588 1.016)
			(layers "F.Cu" "F.Mask" "F.Paste")
			(net "ADM1276_GATE")
		)
	)
	(footprint ""
		(layer "F.Cu")
		(at 11.811 -426.847 90)
		(property "Reference" "PD2"
			(at 0 0 90)
			(layer "F.SilkS")
			(hide yes)
			(effects
				(font
					(size 1.27 1.27)
				)
			)
		)
		(property "Value" "SMCJ15A-1-GP"
			(at -4.7244 1.5748 90)
			(unlocked yes)
			(layer "F.Fab")
			(hide yes)
			(effects
				(font
					(size 1.016 1.016)
					(thickness 0.1524)
				)
			)
		)
		(property "Device Type" "TVS794591-114297H104"
			(at -4.7244 0.0508 90)
			(unlocked yes)
			(layer "F.Fab")
			(hide yes)
			(effects
				(font
					(size 1.016 1.016)
					(thickness 0.1524)
				)
			)
		)
		(duplicate_pad_numbers_are_jumpers no)
		(fp_line
			(start 3.2004 -4.8641)
			(end -3.2004 -4.8641)
			(stroke
				(width 0.1524)
				(type default)
			)
			(layer "F.SilkS")
		)
		(fp_line
			(start -3.2004 -4.8641)
			(end -3.2004 4.8641)
			(stroke
				(width 0.1524)
				(type default)
			)
			(layer "F.SilkS")
		)
		(fp_line
			(start 3.2004 4.8641)
			(end 3.2004 -4.8641)
			(stroke
				(width 0.1524)
				(type default)
			)
			(layer "F.SilkS")
		)
		(fp_line
			(start -3.2004 4.8641)
			(end 3.2004 4.8641)
			(stroke
				(width 0.1524)
				(type default)
			)
			(layer "F.SilkS")
		)
		(fp_line
			(start 3.2004 5.0419)
			(end -3.2004 5.0419)
			(stroke
				(width 0.508)
				(type default)
			)
			(layer "F.SilkS")
		)
		(fp_rect
			(start -2.9464 3.9751)
			(end 2.9464 -3.9751)
			(stroke
				(width 0)
				(type default)
			)
			(fill no)
			(layer "F.CrtYd")
		)
		(fp_poly
			(pts
				(xy -3.4544 4.9403) (xy -3.4544 -4.9403) (xy 3.4544 -4.9403) (xy 3.4544 3.9624) (xy 2.9464 3.9624)
				(xy 2.9464 -3.9751) (xy -2.9464 -3.9751) (xy -2.9464 3.9751) (xy 3.4544 3.9751) (xy 3.4544 4.9403)
			)
			(stroke
				(width 0)
				(type default)
			)
			(fill no)
			(layer "F.CrtYd")
		)
		(fp_rect
			(start -3.4544 4.9403)
			(end 3.4544 -4.9403)
			(stroke
				(width 0)
				(type default)
			)
			(fill no)
			(layer "F.Fab")
		)
		(pad "A" smd rect
			(at 0 -3.591814 90)
			(size 3.2258 2.032)
			(layers "F.Cu" "F.Mask" "F.Paste")
			(net "GND")
		)
		(pad "K" smd rect
			(at 0 3.591814 90)
			(size 3.2258 2.032)
			(layers "F.Cu" "F.Mask" "F.Paste")
			(net "P12V_AUX")
		)
	)
	(footprint ""
		(layer "F.Cu")
		(at 41.91 -350.647 90)
		(property "Reference" "JP1"
			(at 0 0 90)
			(layer "F.SilkS")
			(hide yes)
			(effects
				(font
					(size 1.27 1.27)
				)
			)
		)
		(property "Value" "PIN-CON3-S3-GP"
			(at -5.8039 -0.0889 90)
			(unlocked yes)
			(layer "F.Fab")
			(hide yes)
			(effects
				(font
					(size 1.016 1.016)
					(thickness 0.1524)
				)
			)
		)
		(property "Device Type" "21S-H91-03GB31"
			(at -5.8039 -1.6129 90)
			(unlocked yes)
			(layer "F.Fab")
			(hide yes)
			(effects
				(font
					(size 1.016 1.016)
					(thickness 0.1524)
				)
			)
		)
		(duplicate_pad_numbers_are_jumpers no)
		(fp_line
			(start -4.064 -1.6256)
			(end -2.794 -1.6256)
			(stroke
				(width 0.4064)
				(type default)
			)
			(layer "F.SilkS")
		)
		(fp_line
			(start 3.937 -1.4986)
			(end -3.937 -1.4986)
			(stroke
				(width 0.1524)
				(type default)
			)
			(layer "F.SilkS")
		)
		(fp_line
			(start -3.937 -1.4986)
			(end -3.937 1.4986)
			(stroke
				(width 0.1524)
				(type default)
			)
			(layer "F.SilkS")
		)
		(fp_line
			(start -4.064 -0.3556)
			(end -4.064 -1.6256)
			(stroke
				(width 0.4064)
				(type default)
			)
			(layer "F.SilkS")
		)
		(fp_line
			(start 3.937 1.4986)
			(end 3.937 -1.4986)
			(stroke
				(width 0.1524)
				(type default)
			)
			(layer "F.SilkS")
		)
		(fp_line
			(start -3.937 1.4986)
			(end 3.937 1.4986)
			(stroke
				(width 0.1524)
				(type default)
			)
			(layer "F.SilkS")
		)
		(fp_circle
			(center 2.54 0)
			(end 2.54 1.0668)
			(stroke
				(width 0.3048)
				(type default)
			)
			(fill no)
			(layer "F.SilkS")
		)
		(fp_circle
			(center 0 0)
			(end 0 1.0668)
			(stroke
				(width 0.3048)
				(type default)
			)
			(fill no)
			(layer "F.SilkS")
		)
		(fp_circle
			(center -2.54 0)
			(end -2.54 1.0668)
			(stroke
				(width 0.3048)
				(type default)
			)
			(fill no)
			(layer "F.SilkS")
		)
		(fp_rect
			(start -3.683 1.2446)
			(end 3.683 -1.2446)
			(stroke
				(width 0)
				(type default)
			)
			(fill no)
			(layer "F.CrtYd")
		)
		(fp_poly
			(pts
				(xy 4.191 -1.2446) (xy -3.683 -1.2446) (xy -3.683 1.2446) (xy 3.683 1.2446) (xy 3.683 -1.2319) (xy 4.191 -1.2319)
				(xy 4.191 1.7526) (xy -4.191 1.7526) (xy -4.191 -1.7526) (xy 4.191 -1.7526)
			)
			(stroke
				(width 0)
				(type default)
			)
			(fill no)
			(layer "F.CrtYd")
		)
		(fp_rect
			(start -4.191 1.7526)
			(end 4.191 -1.7526)
			(stroke
				(width 0)
				(type default)
			)
			(fill no)
			(layer "F.Fab")
		)
		(pad "1" thru_hole circle
			(at -2.54 0 90)
			(size 1.4224 1.4224)
			(drill 1.016)
			(layers "*.Cu" "*.Mask")
			(remove_unused_layers no)
			(net "TEMP_ALM#_JP_1")
			(clearance 0.1524)
			(thermal_gap 0.1524)
		)
		(pad "2" thru_hole circle
			(at 0 0 90)
			(size 1.4224 1.4224)
			(drill 1.016)
			(layers "*.Cu" "*.Mask")
			(remove_unused_layers no)
			(net "TEMP_ALM#_JP_2")
			(clearance 0.1524)
			(thermal_gap 0.1524)
		)
		(pad "3" thru_hole circle
			(at 2.54 0 90)
			(size 1.4224 1.4224)
			(drill 1.016)
			(layers "*.Cu" "*.Mask")
			(remove_unused_layers no)
			(net "OTP_RETRY_B")
			(clearance 0.1524)
			(thermal_gap 0.1524)
		)
	)
	(footprint ""
		(layer "F.Cu")
		(at 14.7574 -262.2804 180)
		(property "Reference" "C35"
			(at 0 0 180)
			(layer "F.SilkS")
			(hide yes)
			(effects
				(font
					(size 1.27 1.27)
				)
			)
		)
		(property "Value" "SCD1U16V2KX-3GP"
			(at 1.1811 -2.7051 180)
			(unlocked yes)
			(layer "F.Fab")
			(hide yes)
			(effects
				(font
					(size 1.016 1.016)
					(thickness 0.1524)
				)
			)
		)
		(property "Device Type" "C402H22"
			(at 1.1811 -4.2291 180)
			(unlocked yes)
			(layer "F.Fab")
			(hide yes)
			(effects
				(font
					(size 1.016 1.016)
					(thickness 0.1524)
				)
			)
		)
		(duplicate_pad_numbers_are_jumpers no)
		(fp_rect
			(start -0.4318 0.9525)
			(end 0.4318 -0.9525)
			(stroke
				(width 0)
				(type default)
			)
			(fill no)
			(layer "F.CrtYd")
		)
		(fp_rect
			(start -0.4318 0.9525)
			(end 0.4318 -0.9525)
			(stroke
				(width 0)
				(type default)
			)
			(fill no)
			(layer "F.Fab")
		)
		(pad "1" smd custom
			(at 0 -0.4445 180)
			(size 0.1524 0.1524)
			(layers "F.Cu" "F.Mask" "F.Paste")
			(net "FAN_TACH6")
			(options
				(clearance outline)
				(anchor circle)
			)
			(primitives
				(gr_poly
					(pts
						(arc
							(start 0.3048 -0.2032)
							(mid 0.275042 -0.275042)
							(end 0.2032 -0.3048)
						)
						(arc
							(start -0.2032 -0.3048)
							(mid -0.275042 -0.275042)
							(end -0.3048 -0.2032)
						)
						(arc
							(start -0.3048 0.2032)
							(mid -0.275042 0.275042)
							(end -0.2032 0.3048)
						)
						(arc
							(start 0.2032 0.3048)
							(mid 0.275042 0.275042)
							(end 0.3048 0.2032)
						)
					)
					(width 0)
					(fill yes)
				)
			)
		)
		(pad "2" smd custom
			(at 0 0.4445 180)
			(size 0.1524 0.1524)
			(layers "F.Cu" "F.Mask" "F.Paste")
			(net "GND")
			(options
				(clearance outline)
				(anchor circle)
			)
			(primitives
				(gr_poly
					(pts
						(arc
							(start 0.3048 -0.2032)
							(mid 0.275042 -0.275042)
							(end 0.2032 -0.3048)
						)
						(arc
							(start -0.2032 -0.3048)
							(mid -0.275042 -0.275042)
							(end -0.3048 -0.2032)
						)
						(arc
							(start -0.3048 0.2032)
							(mid -0.275042 0.275042)
							(end -0.2032 0.3048)
						)
						(arc
							(start 0.2032 0.3048)
							(mid 0.275042 0.275042)
							(end 0.3048 0.2032)
						)
					)
					(width 0)
					(fill yes)
				)
			)
		)
	)
	(footprint ""
		(layer "F.Cu")
		(at 20.7264 -26.162 90)
		(property "Reference" "R182"
			(at 0 0 90)
			(layer "F.SilkS")
			(hide yes)
			(effects
				(font
					(size 1.27 1.27)
				)
			)
		)
		(property "Value" "0R1206-PAD-1-GP"
			(at 0 -5.0292 90)
			(unlocked yes)
			(layer "F.Fab")
			(hide yes)
			(effects
				(font
					(size 1.016 1.016)
					(thickness 0.1524)
				)
			)
		)
		(property "Device Type" "0R1206-PAD-1"
			(at 0 -6.5532 90)
			(unlocked yes)
			(layer "F.Fab")
			(hide yes)
			(effects
				(font
					(size 1.016 1.016)
					(thickness 0.1524)
				)
			)
		)
		(duplicate_pad_numbers_are_jumpers no)
		(fp_line
			(start 1.016 -2.2352)
			(end -1.016 -2.2352)
			(stroke
				(width 0.1524)
				(type default)
			)
			(layer "F.SilkS")
		)
		(fp_line
			(start -1.016 -2.2352)
			(end -1.016 2.2352)
			(stroke
				(width 0.1524)
				(type default)
			)
			(layer "F.SilkS")
		)
		(fp_line
			(start 1.016 2.2352)
			(end 1.016 -2.2352)
			(stroke
				(width 0.1524)
				(type default)
			)
			(layer "F.SilkS")
		)
		(fp_line
			(start -1.016 2.2352)
			(end 1.016 2.2352)
			(stroke
				(width 0.1524)
				(type default)
			)
			(layer "F.SilkS")
		)
		(fp_rect
			(start -1.0922 2.3114)
			(end 1.0922 -2.3114)
			(stroke
				(width 0)
				(type default)
			)
			(fill no)
			(layer "F.CrtYd")
		)
		(fp_poly
			(pts
				(xy -1.0922 -2.3114) (xy 1.0922 -2.3114) (xy 1.0922 2.3114) (xy -1.0922 2.3114)
			)
			(stroke
				(width 0)
				(type default)
			)
			(fill no)
			(layer "F.Fab")
		)
		(pad "1" smd rect
			(at 0 -1.397 90)
			(size 1.651 2.0574)
			(drill
				(offset 0 0.3937)
			)
			(layers "F.Cu" "F.Mask" "F.Paste")
			(net "P12V_FAN6")
		)
		(pad "2" smd rect
			(at 0 1.397 90)
			(size 1.651 2.0574)
			(drill
				(offset 0 -0.3937)
			)
			(layers "F.Cu" "F.Mask" "F.Paste")
			(net "P12V")
		)
	)
	(footprint ""
		(layer "F.Cu")
		(at 37.719 -111.633)
		(property "Reference" "PQ8"
			(at 0 0 0)
			(layer "F.SilkS")
			(hide yes)
			(effects
				(font
					(size 1.27 1.27)
				)
			)
		)
		(property "Value" "PH0925CL-GP"
			(at -4.2799 -0.4572 0)
			(unlocked yes)
			(layer "F.Fab")
			(hide yes)
			(effects
				(font
					(size 1.016 1.016)
					(thickness 0.1524)
				)
			)
		)
		(property "Device Type" "LFPAK-5PH48-U"
			(at -4.2799 -1.9812 0)
			(unlocked yes)
			(layer "F.Fab")
			(hide yes)
			(effects
				(font
					(size 1.016 1.016)
					(thickness 0.1524)
				)
			)
		)
		(duplicate_pad_numbers_are_jumpers no)
		(fp_line
			(start -2.7559 -6.5532)
			(end -2.7559 1.0668)
			(stroke
				(width 0.1524)
				(type default)
			)
			(layer "F.SilkS")
		)
		(fp_line
			(start -2.7559 1.0668)
			(end 2.7559 1.0668)
			(stroke
				(width 0.1524)
				(type default)
			)
			(layer "F.SilkS")
		)
		(fp_line
			(start -1.7272 1.1684)
			(end -2.1082 1.1684)
			(stroke
				(width 0.3302)
				(type default)
			)
			(layer "F.SilkS")
		)
		(fp_line
			(start 2.7559 -6.5532)
			(end -2.7559 -6.5532)
			(stroke
				(width 0.1524)
				(type default)
			)
			(layer "F.SilkS")
		)
		(fp_line
			(start 2.7559 1.0668)
			(end 2.7559 -6.5532)
			(stroke
				(width 0.1524)
				(type default)
			)
			(layer "F.SilkS")
		)
		(fp_poly
			(pts
				(xy -2.3368 1.5748) (xy -1.905 1.143) (xy -1.4732 1.5748)
			)
			(stroke
				(width 0)
				(type default)
			)
			(fill yes)
			(layer "F.SilkS")
		)
		(fp_poly
			(pts
				(xy -2.5019 -4.02971) (xy -0.3302 -4.02971) (xy -0.3302 -6.30301) (xy -2.5019 -6.30301)
			)
			(stroke
				(width 0)
				(type default)
			)
			(fill yes)
			(layer "F.Paste")
		)
		(fp_poly
			(pts
				(xy -2.5019 -1.09601) (xy -0.3302 -1.09601) (xy -0.3302 -3.36931) (xy -2.5019 -3.36931)
			)
			(stroke
				(width 0)
				(type default)
			)
			(fill yes)
			(layer "F.Paste")
		)
		(fp_poly
			(pts
				(xy 0.3302 -4.02971) (xy 2.5019 -4.02971) (xy 2.5019 -6.30301) (xy 0.3302 -6.30301)
			)
			(stroke
				(width 0)
				(type default)
			)
			(fill yes)
			(layer "F.Paste")
		)
		(fp_poly
			(pts
				(xy 0.3302 -1.09601) (xy 2.5019 -1.09601) (xy 2.5019 -3.36931) (xy 0.3302 -3.36931)
			)
			(stroke
				(width 0)
				(type default)
			)
			(fill yes)
			(layer "F.Paste")
		)
		(fp_rect
			(start -2.4511 0.3048)
			(end 2.4511 -5.6896)
			(stroke
				(width 0)
				(type default)
			)
			(fill no)
			(layer "F.CrtYd")
		)
		(fp_poly
			(pts
				(xy -3.0099 1.3208) (xy -3.0099 -6.8072) (xy 3.0099 -6.8072) (xy 3.0099 -1.016) (xy 2.4511 -1.016)
				(xy 2.4511 -5.6896) (xy -2.4511 -5.6896) (xy -2.4511 0.3048) (xy 2.4511 0.3048) (xy 2.4511 -1.0033)
				(xy 3.0099 -1.0033) (xy 3.0099 1.3208)
			)
			(stroke
				(width 0)
				(type default)
			)
			(fill no)
			(layer "F.CrtYd")
		)
		(fp_rect
			(start -3.0099 1.3208)
			(end 3.0099 -6.8072)
			(stroke
				(width 0)
				(type default)
			)
			(fill no)
			(layer "F.Fab")
		)
		(pad "1" smd rect
			(at -1.905 0)
			(size 0.762 1.6256)
			(layers "F.Cu" "F.Mask" "F.Paste")
			(net "P12VL")
		)
		(pad "2" smd rect
			(at -0.635 0)
			(size 0.762 1.6256)
			(layers "F.Cu" "F.Mask" "F.Paste")
			(net "P12VL")
		)
		(pad "3" smd rect
			(at 0.635 0)
			(size 0.762 1.6256)
			(layers "F.Cu" "F.Mask" "F.Paste")
			(net "P12VL")
		)
		(pad "4" smd rect
			(at 1.905 0)
			(size 0.762 1.6256)
			(layers "F.Cu" "F.Mask" "F.Paste")
			(net "P12VL_2490_GATE_DRV")
		)
		(pad "5" smd rect
			(at 0 -3.69951)
			(size 5.0038 5.207)
			(layers "F.Cu" "F.Mask" "F.Paste")
			(net "P12VL_NET")
		)
	)
	(footprint ""
		(layer "F.Cu")
		(at 43.942 -95.7326 90)
		(property "Reference" "TC5"
			(at 0 0 90)
			(layer "F.SilkS")
			(hide yes)
			(effects
				(font
					(size 1.27 1.27)
				)
			)
		)
		(property "Value" "ST68U16VDM-1-GP"
			(at 0 -9.6012 90)
			(unlocked yes)
			(layer "F.Fab")
			(hide yes)
			(effects
				(font
					(size 1.016 1.016)
					(thickness 0.1524)
				)
			)
		)
		(property "Device Type" "CT7343H79"
			(at 0 -11.1252 90)
			(unlocked yes)
			(layer "F.Fab")
			(hide yes)
			(effects
				(font
					(size 1.016 1.016)
					(thickness 0.1524)
				)
			)
		)
		(duplicate_pad_numbers_are_jumpers no)
		(fp_line
			(start 2.286 -4.8768)
			(end -2.286 -4.8768)
			(stroke
				(width 0.1524)
				(type default)
			)
			(layer "F.SilkS")
		)
		(fp_line
			(start -2.286 -4.8768)
			(end -2.286 -2.032)
			(stroke
				(width 0.1524)
				(type default)
			)
			(layer "F.SilkS")
		)
		(fp_line
			(start 2.1082 -4.699)
			(end -2.1082 -4.699)
			(stroke
				(width 0.508)
				(type default)
			)
			(layer "F.SilkS")
		)
		(fp_line
			(start 2.286 -2.032)
			(end 2.286 -4.8768)
			(stroke
				(width 0.1524)
				(type default)
			)
			(layer "F.SilkS")
		)
		(fp_line
			(start 2.286 2.032)
			(end 2.286 4.8768)
			(stroke
				(width 0.1524)
				(type default)
			)
			(layer "F.SilkS")
		)
		(fp_line
			(start 2.286 4.8768)
			(end -2.286 4.8768)
			(stroke
				(width 0.1524)
				(type default)
			)
			(layer "F.SilkS")
		)
		(fp_line
			(start -2.286 4.8768)
			(end -2.286 2.032)
			(stroke
				(width 0.1524)
				(type default)
			)
			(layer "F.SilkS")
		)
		(fp_rect
			(start -2.1463 3.6449)
			(end 2.1463 -3.6449)
			(stroke
				(width 0)
				(type default)
			)
			(fill no)
			(layer "F.CrtYd")
		)
		(fp_poly
			(pts
				(xy -2.54 4.953) (xy -2.54 4.2926) (xy -3.81 4.2926) (xy -3.81 -4.2926) (xy -2.54 -4.2926) (xy -2.54 -4.953)
				(xy 2.54 -4.953) (xy 2.54 -4.2926) (xy 3.81 -4.2926) (xy 3.81 -1.6256) (xy 2.1463 -1.6256) (xy 2.1463 -3.6449)
				(xy -2.1463 -3.6449) (xy -2.1463 3.6449) (xy 2.1463 3.6449) (xy 2.1463 -1.6129) (xy 3.81 -1.6129)
				(xy 3.81 4.2926) (xy 2.54 4.2926) (xy 2.54 4.953)
			)
			(stroke
				(width 0)
				(type default)
			)
			(fill no)
			(layer "F.CrtYd")
		)
		(fp_rect
			(start 2.54 4.2926)
			(end 3.81 -4.2926)
			(stroke
				(width 0)
				(type default)
			)
			(fill no)
			(layer "F.Fab")
		)
		(fp_rect
			(start -3.81 4.2926)
			(end -2.54 -4.2926)
			(stroke
				(width 0)
				(type default)
			)
			(fill no)
			(layer "F.Fab")
		)
		(fp_rect
			(start -2.54 4.953)
			(end 2.54 -4.953)
			(stroke
				(width 0)
				(type default)
			)
			(fill no)
			(layer "F.Fab")
		)
		(pad "1" smd rect
			(at 0 -3.1496 90)
			(size 2.413 2.286)
			(layers "F.Cu" "F.Mask" "F.Paste")
			(net "P12VL")
		)
		(pad "2" smd rect
			(at 0 3.1496 90)
			(size 2.413 2.286)
			(layers "F.Cu" "F.Mask" "F.Paste")
			(net "GND")
		)
		(zone
			(layer "F.Cu")
			(hatch none 0.5)
			(connect_pads
				(clearance 0)
			)
			(min_thickness 0.25)
			(keepout
				(tracks allowed)
				(vias not_allowed)
				(pads allowed)
				(copperpour not_allowed)
				(footprints allowed)
			)
			(placement
				(enabled no)
				(sheetname "")
			)
			(fill
				(thermal_gap 0.5)
				(thermal_bridge_width 0.5)
				(island_removal_mode 0)
			)
			(polygon
				(pts
					(xy 42.2529 -97.2439) (xy 39.3446 -97.2439) (xy 39.3446 -94.2213) (xy 42.2402 -94.2213) (xy 42.5704 -94.2213)
					(xy 42.5704 -97.2439)
				)
			)
		)
		(zone
			(layer "F.Cu")
			(hatch none 0.5)
			(connect_pads
				(clearance 0)
			)
			(min_thickness 0.25)
			(keepout
				(tracks allowed)
				(vias not_allowed)
				(pads allowed)
				(copperpour not_allowed)
				(footprints allowed)
			)
			(placement
				(enabled no)
				(sheetname "")
			)
			(fill
				(thermal_gap 0.5)
				(thermal_bridge_width 0.5)
				(island_removal_mode 0)
			)
			(polygon
				(pts
					(xy 48.5394 -94.2213) (xy 48.5394 -97.2439) (xy 45.6438 -97.2439) (xy 45.3136 -97.2439) (xy 45.3136 -94.2213)
					(xy 45.6438 -94.2213)
				)
			)
		)
	)
	(footprint ""
		(layer "F.Cu")
		(at 47.625 -408.051 90)
		(property "Reference" "PC7"
			(at 0 0 90)
			(layer "F.SilkS")
			(hide yes)
			(effects
				(font
					(size 1.27 1.27)
				)
			)
		)
		(property "Value" "SC1U25V5KX-1GP"
			(at -0.0762 -6.1214 90)
			(unlocked yes)
			(layer "F.Fab")
			(hide yes)
			(effects
				(font
					(size 1.016 1.016)
					(thickness 0.1524)
				)
			)
		)
		(property "Device Type" "C805H58"
			(at -0.0762 -8.1534 90)
			(unlocked yes)
			(layer "F.Fab")
			(hide yes)
			(effects
				(font
					(size 1.016 1.016)
					(thickness 0.1524)
				)
			)
		)
		(duplicate_pad_numbers_are_jumpers no)
		(fp_line
			(start 0.635 0)
			(end -0.635 0)
			(stroke
				(width 0.508)
				(type default)
			)
			(layer "F.SilkS")
		)
		(fp_rect
			(start -0.9652 1.778)
			(end 0.9652 -1.778)
			(stroke
				(width 0)
				(type default)
			)
			(fill no)
			(layer "F.CrtYd")
		)
		(fp_poly
			(pts
				(xy -0.9652 -1.778) (xy 0.9652 -1.778) (xy 0.9652 1.778) (xy -0.9652 1.778)
			)
			(stroke
				(width 0)
				(type default)
			)
			(fill no)
			(layer "F.Fab")
		)
		(pad "1" smd rect
			(at 0 -0.9652 90)
			(size 1.397 1.143)
			(layers "F.Cu" "F.Mask" "F.Paste")
			(net "P12V_SENSE_TRACE")
		)
		(pad "2" smd rect
			(at 0 0.9652 90)
			(size 1.397 1.143)
			(layers "F.Cu" "F.Mask" "F.Paste")
			(net "GND")
		)
	)
	(footprint ""
		(layer "F.Cu")
		(at 36.9062 -147.447 180)
		(property "Reference" "PR115"
			(at 0 0 180)
			(layer "F.SilkS")
			(hide yes)
			(effects
				(font
					(size 1.27 1.27)
				)
			)
		)
		(property "Value" "20KR2F-L-GP"
			(at 0.064008 -3.993896 180)
			(unlocked yes)
			(layer "F.Fab")
			(hide yes)
			(effects
				(font
					(size 1.016 1.016)
					(thickness 0.1524)
				)
			)
		)
		(property "Device Type" "R402H16"
			(at 0.064008 -5.517896 180)
			(unlocked yes)
			(layer "F.Fab")
			(hide yes)
			(effects
				(font
					(size 1.016 1.016)
					(thickness 0.1524)
				)
			)
		)
		(duplicate_pad_numbers_are_jumpers no)
		(fp_line
			(start 0.508 -0.9398)
			(end -0.508 -0.9398)
			(stroke
				(width 0.1524)
				(type default)
			)
			(layer "F.SilkS")
		)
		(fp_line
			(start -0.508 -0.9398)
			(end -0.508 0.9398)
			(stroke
				(width 0.1524)
				(type default)
			)
			(layer "F.SilkS")
		)
		(fp_rect
			(start -0.508 0.9398)
			(end 0.508 -0.9398)
			(stroke
				(width 0)
				(type default)
			)
			(fill no)
			(layer "F.CrtYd")
		)
		(fp_rect
			(start -0.508 0.9398)
			(end 0.508 -0.9398)
			(stroke
				(width 0)
				(type default)
			)
			(fill no)
			(layer "F.Fab")
		)
		(pad "1" smd custom
			(at 0 -0.4445 180)
			(size 0.1397 0.1397)
			(layers "F.Cu" "F.Mask" "F.Paste")
			(net "P12VL_2490_PROG")
			(options
				(clearance outline)
				(anchor circle)
			)
			(primitives
				(gr_poly
					(pts
						(arc
							(start -0.1778 -0.2794)
							(mid -0.249642 -0.249642)
							(end -0.2794 -0.1778)
						)
						(arc
							(start -0.2794 0.1778)
							(mid -0.249642 0.249642)
							(end -0.1778 0.2794)
						)
						(arc
							(start 0.1778 0.2794)
							(mid 0.249642 0.249642)
							(end 0.2794 0.1778)
						)
						(arc
							(start 0.2794 -0.1778)
							(mid 0.249642 -0.249642)
							(end 0.1778 -0.2794)
						)
					)
					(width 0)
					(fill yes)
				)
			)
		)
		(pad "2" smd custom
			(at 0 0.4445 180)
			(size 0.1397 0.1397)
			(layers "F.Cu" "F.Mask" "F.Paste")
			(net "GND")
			(options
				(clearance outline)
				(anchor circle)
			)
			(primitives
				(gr_poly
					(pts
						(arc
							(start -0.1778 -0.2794)
							(mid -0.249642 -0.249642)
							(end -0.2794 -0.1778)
						)
						(arc
							(start -0.2794 0.1778)
							(mid -0.249642 0.249642)
							(end -0.1778 0.2794)
						)
						(arc
							(start 0.1778 0.2794)
							(mid 0.249642 0.249642)
							(end 0.2794 0.1778)
						)
						(arc
							(start 0.2794 -0.1778)
							(mid 0.249642 -0.249642)
							(end 0.1778 -0.2794)
						)
					)
					(width 0)
					(fill yes)
				)
			)
		)
	)
	(footprint ""
		(layer "F.Cu")
		(at 15.494 -60.5282 180)
		(property "Reference" "R359"
			(at 0 0 180)
			(layer "F.SilkS")
			(hide yes)
			(effects
				(font
					(size 1.27 1.27)
				)
			)
		)
		(property "Value" "10KR2F-2-GP"
			(at 0.064008 -3.993896 180)
			(unlocked yes)
			(layer "F.Fab")
			(hide yes)
			(effects
				(font
					(size 1.016 1.016)
					(thickness 0.1524)
				)
			)
		)
		(property "Device Type" "R402H16"
			(at 0.064008 -5.517896 180)
			(unlocked yes)
			(layer "F.Fab")
			(hide yes)
			(effects
				(font
					(size 1.016 1.016)
					(thickness 0.1524)
				)
			)
		)
		(duplicate_pad_numbers_are_jumpers no)
		(fp_line
			(start 0.508 -0.9398)
			(end -0.508 -0.9398)
			(stroke
				(width 0.1524)
				(type default)
			)
			(layer "F.SilkS")
		)
		(fp_line
			(start -0.508 -0.9398)
			(end -0.508 0.9398)
			(stroke
				(width 0.1524)
				(type default)
			)
			(layer "F.SilkS")
		)
		(fp_rect
			(start -0.508 0.9398)
			(end 0.508 -0.9398)
			(stroke
				(width 0)
				(type default)
			)
			(fill no)
			(layer "F.CrtYd")
		)
		(fp_rect
			(start -0.508 0.9398)
			(end 0.508 -0.9398)
			(stroke
				(width 0)
				(type default)
			)
			(fill no)
			(layer "F.Fab")
		)
		(pad "1" smd custom
			(at 0 -0.4445 180)
			(size 0.1397 0.1397)
			(layers "F.Cu" "F.Mask" "F.Paste")
			(net "P3V3")
			(options
				(clearance outline)
				(anchor circle)
			)
			(primitives
				(gr_poly
					(pts
						(arc
							(start -0.1778 -0.2794)
							(mid -0.249642 -0.249642)
							(end -0.2794 -0.1778)
						)
						(arc
							(start -0.2794 0.1778)
							(mid -0.249642 0.249642)
							(end -0.1778 0.2794)
						)
						(arc
							(start 0.1778 0.2794)
							(mid 0.249642 0.249642)
							(end 0.2794 0.1778)
						)
						(arc
							(start 0.2794 -0.1778)
							(mid 0.249642 -0.249642)
							(end 0.1778 -0.2794)
						)
					)
					(width 0)
					(fill yes)
				)
			)
		)
		(pad "2" smd custom
			(at 0 0.4445 180)
			(size 0.1397 0.1397)
			(layers "F.Cu" "F.Mask" "F.Paste")
			(net "UPPER_TRAY_ID")
			(options
				(clearance outline)
				(anchor circle)
			)
			(primitives
				(gr_poly
					(pts
						(arc
							(start -0.1778 -0.2794)
							(mid -0.249642 -0.249642)
							(end -0.2794 -0.1778)
						)
						(arc
							(start -0.2794 0.1778)
							(mid -0.249642 0.249642)
							(end -0.1778 0.2794)
						)
						(arc
							(start 0.1778 0.2794)
							(mid 0.249642 0.249642)
							(end 0.2794 0.1778)
						)
						(arc
							(start 0.2794 -0.1778)
							(mid 0.249642 -0.249642)
							(end 0.1778 -0.2794)
						)
					)
					(width 0)
					(fill yes)
				)
			)
		)
	)
	(footprint ""
		(layer "F.Cu")
		(at 31.96209 -150.781766 180)
		(property "Reference" "TP6"
			(at 0 0 180)
			(layer "F.SilkS")
			(hide yes)
			(effects
				(font
					(size 1.27 1.27)
				)
			)
		)
		(property "Value" "TPAD32-GP"
			(at 0 -3.166364 180)
			(unlocked yes)
			(layer "F.Fab")
			(hide yes)
			(effects
				(font
					(size 1.016 1.016)
					(thickness 0.1524)
				)
			)
		)
		(property "Device Type" "TPAD32"
			(at 0 -4.690618 180)
			(unlocked yes)
			(layer "F.Fab")
			(hide yes)
			(effects
				(font
					(size 1.016 1.016)
					(thickness 0.1524)
				)
			)
		)
		(duplicate_pad_numbers_are_jumpers no)
		(fp_poly
			(pts
				(arc
					(start 0.7112 0)
					(mid -0.7112 0)
					(end 0.7112 0)
				)
			)
			(stroke
				(width 0)
				(type default)
			)
			(fill no)
			(layer "F.CrtYd")
		)
		(fp_poly
			(pts
				(arc
					(start 0.7112 0)
					(mid -0.7112 0)
					(end 0.7112 0)
				)
			)
			(stroke
				(width 0)
				(type default)
			)
			(fill no)
			(layer "F.Fab")
		)
		(pad "1" smd circle
			(at 0 0 180)
			(size 0.8128 0.8128)
			(layers "F.Cu" "F.Mask" "F.Paste")
			(net "NCT7904_VSEN8")
		)
	)
	(footprint ""
		(layer "F.Cu")
		(at 14.8844 -40.4622 90)
		(property "Reference" "R172"
			(at 0 0 90)
			(layer "F.SilkS")
			(hide yes)
			(effects
				(font
					(size 1.27 1.27)
				)
			)
		)
		(property "Value" "0R2J-2-GP"
			(at 0.064008 -3.993896 90)
			(unlocked yes)
			(layer "F.Fab")
			(hide yes)
			(effects
				(font
					(size 1.016 1.016)
					(thickness 0.1524)
				)
			)
		)
		(property "Device Type" "R402H16"
			(at 0.064008 -5.517896 90)
			(unlocked yes)
			(layer "F.Fab")
			(hide yes)
			(effects
				(font
					(size 1.016 1.016)
					(thickness 0.1524)
				)
			)
		)
		(duplicate_pad_numbers_are_jumpers no)
		(fp_line
			(start 0.508 -0.9398)
			(end -0.508 -0.9398)
			(stroke
				(width 0.1524)
				(type default)
			)
			(layer "F.SilkS")
		)
		(fp_line
			(start -0.508 -0.9398)
			(end -0.508 0.9398)
			(stroke
				(width 0.1524)
				(type default)
			)
			(layer "F.SilkS")
		)
		(fp_rect
			(start -0.508 0.9398)
			(end 0.508 -0.9398)
			(stroke
				(width 0)
				(type default)
			)
			(fill no)
			(layer "F.CrtYd")
		)
		(fp_rect
			(start -0.508 0.9398)
			(end 0.508 -0.9398)
			(stroke
				(width 0)
				(type default)
			)
			(fill no)
			(layer "F.Fab")
		)
		(pad "1" smd custom
			(at 0 -0.4445 90)
			(size 0.1397 0.1397)
			(layers "F.Cu" "F.Mask" "F.Paste")
			(net "SELF_1B_HB")
			(options
				(clearance outline)
				(anchor circle)
			)
			(primitives
				(gr_poly
					(pts
						(arc
							(start -0.1778 -0.2794)
							(mid -0.249642 -0.249642)
							(end -0.2794 -0.1778)
						)
						(arc
							(start -0.2794 0.1778)
							(mid -0.249642 0.249642)
							(end -0.1778 0.2794)
						)
						(arc
							(start 0.1778 0.2794)
							(mid 0.249642 0.249642)
							(end 0.2794 0.1778)
						)
						(arc
							(start 0.2794 -0.1778)
							(mid 0.249642 -0.249642)
							(end 0.1778 -0.2794)
						)
					)
					(width 0)
					(fill yes)
				)
			)
		)
		(pad "2" smd custom
			(at 0 0.4445 90)
			(size 0.1397 0.1397)
			(layers "F.Cu" "F.Mask" "F.Paste")
			(net "SEB_PEER_2B_HB")
			(options
				(clearance outline)
				(anchor circle)
			)
			(primitives
				(gr_poly
					(pts
						(arc
							(start -0.1778 -0.2794)
							(mid -0.249642 -0.249642)
							(end -0.2794 -0.1778)
						)
						(arc
							(start -0.2794 0.1778)
							(mid -0.249642 0.249642)
							(end -0.1778 0.2794)
						)
						(arc
							(start 0.1778 0.2794)
							(mid 0.249642 0.249642)
							(end 0.2794 0.1778)
						)
						(arc
							(start 0.2794 -0.1778)
							(mid 0.249642 -0.249642)
							(end 0.1778 -0.2794)
						)
					)
					(width 0)
					(fill yes)
				)
			)
		)
	)
	(footprint ""
		(layer "F.Cu")
		(at 15.494 -168.2242 90)
		(property "Reference" "C34"
			(at 0 0 90)
			(layer "F.SilkS")
			(hide yes)
			(effects
				(font
					(size 1.27 1.27)
				)
			)
		)
		(property "Value" "SC1U25V3KX-1-GP"
			(at 0 -2.8194 90)
			(unlocked yes)
			(layer "F.Fab")
			(hide yes)
			(effects
				(font
					(size 1.016 1.016)
					(thickness 0.1524)
				)
			)
		)
		(property "Device Type" "C603H36"
			(at 0 -4.3434 90)
			(unlocked yes)
			(layer "F.Fab")
			(hide yes)
			(effects
				(font
					(size 1.016 1.016)
					(thickness 0.1524)
				)
			)
		)
		(duplicate_pad_numbers_are_jumpers no)
		(fp_line
			(start 0.508 0)
			(end -0.508 0)
			(stroke
				(width 0.2032)
				(type default)
			)
			(layer "F.SilkS")
		)
		(fp_rect
			(start -0.5842 1.3335)
			(end 0.5842 -1.3335)
			(stroke
				(width 0)
				(type default)
			)
			(fill no)
			(layer "F.CrtYd")
		)
		(fp_rect
			(start -0.5842 1.3335)
			(end 0.5842 -1.3335)
			(stroke
				(width 0)
				(type default)
			)
			(fill no)
			(layer "F.Fab")
		)
		(pad "1" smd custom
			(at 0 -0.762 90)
			(size 0.2159 0.2159)
			(layers "F.Cu" "F.Mask" "F.Paste")
			(net "P12V")
			(options
				(clearance outline)
				(anchor circle)
			)
			(primitives
				(gr_poly
					(pts
						(arc
							(start -0.3302 -0.4318)
							(mid -0.402042 -0.402042)
							(end -0.4318 -0.3302)
						)
						(arc
							(start -0.4318 0.3302)
							(mid -0.402042 0.402042)
							(end -0.3302 0.4318)
						)
						(arc
							(start 0.3302 0.4318)
							(mid 0.402042 0.402042)
							(end 0.4318 0.3302)
						)
						(arc
							(start 0.4318 -0.3302)
							(mid 0.402042 -0.402042)
							(end 0.3302 -0.4318)
						)
					)
					(width 0)
					(fill yes)
				)
			)
		)
		(pad "2" smd custom
			(at 0 0.762 90)
			(size 0.2159 0.2159)
			(layers "F.Cu" "F.Mask" "F.Paste")
			(net "GND")
			(options
				(clearance outline)
				(anchor circle)
			)
			(primitives
				(gr_poly
					(pts
						(arc
							(start -0.3302 -0.4318)
							(mid -0.402042 -0.402042)
							(end -0.4318 -0.3302)
						)
						(arc
							(start -0.4318 0.3302)
							(mid -0.402042 0.402042)
							(end -0.3302 0.4318)
						)
						(arc
							(start 0.3302 0.4318)
							(mid 0.402042 0.402042)
							(end 0.4318 0.3302)
						)
						(arc
							(start 0.4318 -0.3302)
							(mid 0.402042 -0.402042)
							(end 0.3302 -0.4318)
						)
					)
					(width 0)
					(fill yes)
				)
			)
		)
	)
	(footprint ""
		(layer "F.Cu")
		(at 19.3294 -277.0124 -90)
		(property "Reference" "TC16"
			(at 0 0 270)
			(layer "F.SilkS")
			(hide yes)
			(effects
				(font
					(size 1.27 1.27)
				)
			)
		)
		(property "Value" "ST15U25VDM-1-GP"
			(at 0 -9.6012 270)
			(unlocked yes)
			(layer "F.Fab")
			(hide yes)
			(effects
				(font
					(size 1.016 1.016)
					(thickness 0.1524)
				)
			)
		)
		(property "Device Type" "CT7343H79"
			(at 0 -11.1252 270)
			(unlocked yes)
			(layer "F.Fab")
			(hide yes)
			(effects
				(font
					(size 1.016 1.016)
					(thickness 0.1524)
				)
			)
		)
		(duplicate_pad_numbers_are_jumpers no)
		(fp_line
			(start -2.286 4.8768)
			(end -2.286 2.032)
			(stroke
				(width 0.1524)
				(type default)
			)
			(layer "F.SilkS")
		)
		(fp_line
			(start 2.286 4.8768)
			(end -2.286 4.8768)
			(stroke
				(width 0.1524)
				(type default)
			)
			(layer "F.SilkS")
		)
		(fp_line
			(start 2.286 2.032)
			(end 2.286 4.8768)
			(stroke
				(width 0.1524)
				(type default)
			)
			(layer "F.SilkS")
		)
		(fp_line
			(start 2.286 -2.032)
			(end 2.286 -4.8768)
			(stroke
				(width 0.1524)
				(type default)
			)
			(layer "F.SilkS")
		)
		(fp_line
			(start 2.1082 -4.699)
			(end -2.1082 -4.699)
			(stroke
				(width 0.508)
				(type default)
			)
			(layer "F.SilkS")
		)
		(fp_line
			(start -2.286 -4.8768)
			(end -2.286 -2.032)
			(stroke
				(width 0.1524)
				(type default)
			)
			(layer "F.SilkS")
		)
		(fp_line
			(start 2.286 -4.8768)
			(end -2.286 -4.8768)
			(stroke
				(width 0.1524)
				(type default)
			)
			(layer "F.SilkS")
		)
		(fp_rect
			(start -2.1463 3.6449)
			(end 2.1463 -3.6449)
			(stroke
				(width 0)
				(type default)
			)
			(fill no)
			(layer "F.CrtYd")
		)
		(fp_poly
			(pts
				(xy -2.54 4.953) (xy -2.54 4.2926) (xy -3.81 4.2926) (xy -3.81 -4.2926) (xy -2.54 -4.2926) (xy -2.54 -4.953)
				(xy 2.54 -4.953) (xy 2.54 -4.2926) (xy 3.81 -4.2926) (xy 3.81 -1.6256) (xy 2.1463 -1.6256) (xy 2.1463 -3.6449)
				(xy -2.1463 -3.6449) (xy -2.1463 3.6449) (xy 2.1463 3.6449) (xy 2.1463 -1.6129) (xy 3.81 -1.6129)
				(xy 3.81 4.2926) (xy 2.54 4.2926) (xy 2.54 4.953)
			)
			(stroke
				(width 0)
				(type default)
			)
			(fill no)
			(layer "F.CrtYd")
		)
		(fp_rect
			(start -2.54 4.953)
			(end 2.54 -4.953)
			(stroke
				(width 0)
				(type default)
			)
			(fill no)
			(layer "F.Fab")
		)
		(fp_rect
			(start -3.81 4.2926)
			(end -2.54 -4.2926)
			(stroke
				(width 0)
				(type default)
			)
			(fill no)
			(layer "F.Fab")
		)
		(fp_rect
			(start 2.54 4.2926)
			(end 3.81 -4.2926)
			(stroke
				(width 0)
				(type default)
			)
			(fill no)
			(layer "F.Fab")
		)
		(pad "1" smd rect
			(at 0 -3.1496 270)
			(size 2.413 2.286)
			(layers "F.Cu" "F.Mask" "F.Paste")
			(net "P12V")
		)
		(pad "2" smd rect
			(at 0 3.1496 270)
			(size 2.413 2.286)
			(layers "F.Cu" "F.Mask" "F.Paste")
			(net "GND")
		)
		(zone
			(layer "F.Cu")
			(hatch none 0.5)
			(connect_pads
				(clearance 0)
			)
			(min_thickness 0.25)
			(keepout
				(tracks allowed)
				(vias not_allowed)
				(pads allowed)
				(copperpour not_allowed)
				(footprints allowed)
			)
			(placement
				(enabled no)
				(sheetname "")
			)
			(fill
				(thermal_gap 0.5)
				(thermal_bridge_width 0.5)
				(island_removal_mode 0)
			)
			(polygon
				(pts
					(xy 14.732 -278.5237) (xy 14.732 -275.5011) (xy 17.6276 -275.5011) (xy 17.9578 -275.5011) (xy 17.9578 -278.5237)
					(xy 17.6276 -278.5237)
				)
			)
		)
		(zone
			(layer "F.Cu")
			(hatch none 0.5)
			(connect_pads
				(clearance 0)
			)
			(min_thickness 0.25)
			(keepout
				(tracks allowed)
				(vias not_allowed)
				(pads allowed)
				(copperpour not_allowed)
				(footprints allowed)
			)
			(placement
				(enabled no)
				(sheetname "")
			)
			(fill
				(thermal_gap 0.5)
				(thermal_bridge_width 0.5)
				(island_removal_mode 0)
			)
			(polygon
				(pts
					(xy 21.0185 -275.5011) (xy 23.9268 -275.5011) (xy 23.9268 -278.5237) (xy 21.0312 -278.5237) (xy 20.701 -278.5237)
					(xy 20.701 -275.5011)
				)
			)
		)
	)
	(footprint ""
		(layer "F.Cu")
		(at 5.947918 -434.623972 180)
		(property "Reference" "Q8"
			(at 0 0 180)
			(layer "F.SilkS")
			(hide yes)
			(effects
				(font
					(size 1.27 1.27)
				)
			)
		)
		(property "Value" "PMBS3904-1-GP"
			(at 0 -9.0932 180)
			(unlocked yes)
			(layer "F.Fab")
			(hide yes)
			(effects
				(font
					(size 1.016 1.016)
					(thickness 0.1524)
				)
			)
		)
		(property "Device Type" "SOT-23-10H44"
			(at 0 -10.6172 180)
			(unlocked yes)
			(layer "F.Fab")
			(hide yes)
			(effects
				(font
					(size 1.016 1.016)
					(thickness 0.1524)
				)
			)
		)
		(duplicate_pad_numbers_are_jumpers no)
		(fp_line
			(start 1.651 1.778)
			(end 1.651 -1.778)
			(stroke
				(width 0.1524)
				(type default)
			)
			(layer "F.SilkS")
		)
		(fp_line
			(start 1.651 -1.778)
			(end -1.651 -1.778)
			(stroke
				(width 0.1524)
				(type default)
			)
			(layer "F.SilkS")
		)
		(fp_line
			(start -0.635 1.8796)
			(end -1.7526 1.8796)
			(stroke
				(width 0.3302)
				(type default)
			)
			(layer "F.SilkS")
		)
		(fp_line
			(start -0.71628 2.15265)
			(end -1.26492 2.15265)
			(stroke
				(width 0.0127)
				(type default)
			)
			(layer "F.SilkS")
		)
		(fp_line
			(start -0.719074 2.145538)
			(end -1.265936 2.14122)
			(stroke
				(width 0.0127)
				(type default)
			)
			(layer "F.SilkS")
		)
		(fp_line
			(start -0.9906 1.86309)
			(end -0.701294 2.15265)
			(stroke
				(width 0.0127)
				(type default)
			)
			(layer "F.SilkS")
		)
		(fp_line
			(start -0.994156 1.8669)
			(end -0.987044 1.8669)
			(stroke
				(width 0.0127)
				(type default)
			)
			(layer "F.SilkS")
		)
		(fp_line
			(start -1.003808 1.876552)
			(end -0.977646 1.876552)
			(stroke
				(width 0.0127)
				(type default)
			)
			(layer "F.SilkS")
		)
		(fp_line
			(start -1.013206 1.88595)
			(end -0.967994 1.88595)
			(stroke
				(width 0.0127)
				(type default)
			)
			(layer "F.SilkS")
		)
		(fp_line
			(start -1.022858 1.895602)
			(end -0.958596 1.895602)
			(stroke
				(width 0.0127)
				(type default)
			)
			(layer "F.SilkS")
		)
		(fp_line
			(start -1.032256 1.905)
			(end -0.948944 1.905)
			(stroke
				(width 0.0127)
				(type default)
			)
			(layer "F.SilkS")
		)
		(fp_line
			(start -1.041908 1.914652)
			(end -0.939546 1.914652)
			(stroke
				(width 0.0127)
				(type default)
			)
			(layer "F.SilkS")
		)
		(fp_line
			(start -1.051306 1.92405)
			(end -0.929894 1.92405)
			(stroke
				(width 0.0127)
				(type default)
			)
			(layer "F.SilkS")
		)
		(fp_line
			(start -1.060958 1.933702)
			(end -0.920496 1.933702)
			(stroke
				(width 0.0127)
				(type default)
			)
			(layer "F.SilkS")
		)
		(fp_line
			(start -1.070356 1.9431)
			(end -0.910844 1.9431)
			(stroke
				(width 0.0127)
				(type default)
			)
			(layer "F.SilkS")
		)
		(fp_line
			(start -1.080008 1.952752)
			(end -0.901446 1.952752)
			(stroke
				(width 0.0127)
				(type default)
			)
			(layer "F.SilkS")
		)
		(fp_line
			(start -1.089406 1.96215)
			(end -0.891794 1.96215)
			(stroke
				(width 0.0127)
				(type default)
			)
			(layer "F.SilkS")
		)
		(fp_line
			(start -1.099058 1.971802)
			(end -0.882396 1.971802)
			(stroke
				(width 0.0127)
				(type default)
			)
			(layer "F.SilkS")
		)
		(fp_line
			(start -1.108456 1.9812)
			(end -0.872744 1.9812)
			(stroke
				(width 0.0127)
				(type default)
			)
			(layer "F.SilkS")
		)
		(fp_line
			(start -1.118108 1.990852)
			(end -0.863346 1.990852)
			(stroke
				(width 0.0127)
				(type default)
			)
			(layer "F.SilkS")
		)
		(fp_line
			(start -1.127506 2.00025)
			(end -0.853694 2.00025)
			(stroke
				(width 0.0127)
				(type default)
			)
			(layer "F.SilkS")
		)
		(fp_line
			(start -1.137158 2.009902)
			(end -0.844296 2.009902)
			(stroke
				(width 0.0127)
				(type default)
			)
			(layer "F.SilkS")
		)
		(fp_line
			(start -1.146556 2.0193)
			(end -0.834644 2.0193)
			(stroke
				(width 0.0127)
				(type default)
			)
			(layer "F.SilkS")
		)
		(fp_line
			(start -1.156208 2.028952)
			(end -0.825246 2.028952)
			(stroke
				(width 0.0127)
				(type default)
			)
			(layer "F.SilkS")
		)
		(fp_line
			(start -1.165606 2.03835)
			(end -0.815594 2.03835)
			(stroke
				(width 0.0127)
				(type default)
			)
			(layer "F.SilkS")
		)
		(fp_line
			(start -1.175258 2.048002)
			(end -0.806196 2.048002)
			(stroke
				(width 0.0127)
				(type default)
			)
			(layer "F.SilkS")
		)
		(fp_line
			(start -1.184656 2.0574)
			(end -0.796544 2.0574)
			(stroke
				(width 0.0127)
				(type default)
			)
			(layer "F.SilkS")
		)
		(fp_line
			(start -1.194308 2.067052)
			(end -0.787146 2.067052)
			(stroke
				(width 0.0127)
				(type default)
			)
			(layer "F.SilkS")
		)
		(fp_line
			(start -1.203706 2.07645)
			(end -0.777494 2.07645)
			(stroke
				(width 0.0127)
				(type default)
			)
			(layer "F.SilkS")
		)
		(fp_line
			(start -1.213358 2.086102)
			(end -0.768096 2.086102)
			(stroke
				(width 0.0127)
				(type default)
			)
			(layer "F.SilkS")
		)
		(fp_line
			(start -1.222756 2.0955)
			(end -0.758444 2.0955)
			(stroke
				(width 0.0127)
				(type default)
			)
			(layer "F.SilkS")
		)
		(fp_line
			(start -1.232408 2.105152)
			(end -0.749046 2.105152)
			(stroke
				(width 0.0127)
				(type default)
			)
			(layer "F.SilkS")
		)
		(fp_line
			(start -1.241806 2.11455)
			(end -0.739394 2.11455)
			(stroke
				(width 0.0127)
				(type default)
			)
			(layer "F.SilkS")
		)
		(fp_line
			(start -1.251458 2.124202)
			(end -0.729996 2.124202)
			(stroke
				(width 0.0127)
				(type default)
			)
			(layer "F.SilkS")
		)
		(fp_line
			(start -1.260856 2.1336)
			(end -0.720344 2.1336)
			(stroke
				(width 0.0127)
				(type default)
			)
			(layer "F.SilkS")
		)
		(fp_line
			(start -1.279144 2.15265)
			(end -0.701294 2.15265)
			(stroke
				(width 0.0127)
				(type default)
			)
			(layer "F.SilkS")
		)
		(fp_line
			(start -1.279398 2.152142)
			(end -0.9906 1.86309)
			(stroke
				(width 0.0127)
				(type default)
			)
			(layer "F.SilkS")
		)
		(fp_line
			(start -1.651 1.778)
			(end 1.651 1.778)
			(stroke
				(width 0.1524)
				(type default)
			)
			(layer "F.SilkS")
		)
		(fp_line
			(start -1.651 -1.778)
			(end -1.651 1.778)
			(stroke
				(width 0.1524)
				(type default)
			)
			(layer "F.SilkS")
		)
		(fp_line
			(start -1.7526 1.8796)
			(end -1.7526 0.9906)
			(stroke
				(width 0.3302)
				(type default)
			)
			(layer "F.SilkS")
		)
		(fp_poly
			(pts
				(xy -1.285748 2.159) (xy -1.285748 1.8796) (xy -1.778 1.8796) (xy -1.778 -1.8796) (xy 1.778 -1.8796)
				(xy 1.778 1.8796) (xy -0.694944 1.8796) (xy -0.694944 2.159)
			)
			(stroke
				(width 0)
				(type default)
			)
			(fill no)
			(layer "F.CrtYd")
		)
		(fp_poly
			(pts
				(xy -1.285748 2.159) (xy -1.285748 1.8796) (xy -1.778 1.8796) (xy -1.778 -1.8796) (xy 1.778 -1.8796)
				(xy 1.778 1.8796) (xy -0.694944 1.8796) (xy -0.694944 2.159)
			)
			(stroke
				(width 0)
				(type default)
			)
			(fill no)
			(layer "F.Fab")
		)
		(pad "1" smd rect
			(at -0.98425 0.9525 180)
			(size 0.762 1.143)
			(layers "F.Cu" "F.Mask" "F.Paste")
			(net "LED_DR_LED0_B")
		)
		(pad "2" smd rect
			(at 0.98425 0.9525 180)
			(size 0.762 1.143)
			(layers "F.Cu" "F.Mask" "F.Paste")
			(net "GND")
		)
		(pad "3" smd rect
			(at 0 -0.9525 180)
			(size 0.762 1.143)
			(layers "F.Cu" "F.Mask" "F.Paste")
			(net "LED_DR_LED0_BLUE")
		)
	)
	(footprint ""
		(layer "F.Cu")
		(at 35.541966 -153.45791 90)
		(property "Reference" "TP13"
			(at 0 0 90)
			(layer "F.SilkS")
			(hide yes)
			(effects
				(font
					(size 1.27 1.27)
				)
			)
		)
		(property "Value" "TPAD32-GP"
			(at 0 -3.166364 90)
			(unlocked yes)
			(layer "F.Fab")
			(hide yes)
			(effects
				(font
					(size 1.016 1.016)
					(thickness 0.1524)
				)
			)
		)
		(property "Device Type" "TPAD32"
			(at 0 -4.690618 90)
			(unlocked yes)
			(layer "F.Fab")
			(hide yes)
			(effects
				(font
					(size 1.016 1.016)
					(thickness 0.1524)
				)
			)
		)
		(duplicate_pad_numbers_are_jumpers no)
		(fp_poly
			(pts
				(arc
					(start 0.7112 0)
					(mid -0.7112 0)
					(end 0.7112 0)
				)
			)
			(stroke
				(width 0)
				(type default)
			)
			(fill no)
			(layer "F.CrtYd")
		)
		(fp_poly
			(pts
				(arc
					(start 0.7112 0)
					(mid -0.7112 0)
					(end 0.7112 0)
				)
			)
			(stroke
				(width 0)
				(type default)
			)
			(fill no)
			(layer "F.Fab")
		)
		(pad "1" smd circle
			(at 0 0 90)
			(size 0.8128 0.8128)
			(layers "F.Cu" "F.Mask" "F.Paste")
			(net "NCT7904_VSEN13")
		)
	)
	(footprint ""
		(layer "F.Cu")
		(at 23.622 -367.411 -90)
		(property "Reference" "PR3"
			(at 0 0 270)
			(layer "F.SilkS")
			(hide yes)
			(effects
				(font
					(size 1.27 1.27)
				)
			)
		)
		(property "Value" "51K1R2F-GP"
			(at 0.064008 -3.993896 270)
			(unlocked yes)
			(layer "F.Fab")
			(hide yes)
			(effects
				(font
					(size 1.016 1.016)
					(thickness 0.1524)
				)
			)
		)
		(property "Device Type" "R402H16"
			(at 0.064008 -5.517896 270)
			(unlocked yes)
			(layer "F.Fab")
			(hide yes)
			(effects
				(font
					(size 1.016 1.016)
					(thickness 0.1524)
				)
			)
		)
		(duplicate_pad_numbers_are_jumpers no)
		(fp_line
			(start -0.508 -0.9398)
			(end -0.508 0.9398)
			(stroke
				(width 0.1524)
				(type default)
			)
			(layer "F.SilkS")
		)
		(fp_line
			(start 0.508 -0.9398)
			(end -0.508 -0.9398)
			(stroke
				(width 0.1524)
				(type default)
			)
			(layer "F.SilkS")
		)
		(fp_rect
			(start -0.508 0.9398)
			(end 0.508 -0.9398)
			(stroke
				(width 0)
				(type default)
			)
			(fill no)
			(layer "F.CrtYd")
		)
		(fp_rect
			(start -0.508 0.9398)
			(end 0.508 -0.9398)
			(stroke
				(width 0)
				(type default)
			)
			(fill no)
			(layer "F.Fab")
		)
		(pad "1" smd custom
			(at 0 -0.4445 270)
			(size 0.1397 0.1397)
			(layers "F.Cu" "F.Mask" "F.Paste")
			(net "ADM1276_ISET")
			(options
				(clearance outline)
				(anchor circle)
			)
			(primitives
				(gr_poly
					(pts
						(arc
							(start -0.1778 -0.2794)
							(mid -0.249642 -0.249642)
							(end -0.2794 -0.1778)
						)
						(arc
							(start -0.2794 0.1778)
							(mid -0.249642 0.249642)
							(end -0.1778 0.2794)
						)
						(arc
							(start 0.1778 0.2794)
							(mid 0.249642 0.249642)
							(end 0.2794 0.1778)
						)
						(arc
							(start 0.2794 -0.1778)
							(mid 0.249642 -0.249642)
							(end 0.1778 -0.2794)
						)
					)
					(width 0)
					(fill yes)
				)
			)
		)
		(pad "2" smd custom
			(at 0 0.4445 270)
			(size 0.1397 0.1397)
			(layers "F.Cu" "F.Mask" "F.Paste")
			(net "GND")
			(options
				(clearance outline)
				(anchor circle)
			)
			(primitives
				(gr_poly
					(pts
						(arc
							(start -0.1778 -0.2794)
							(mid -0.249642 -0.249642)
							(end -0.2794 -0.1778)
						)
						(arc
							(start -0.2794 0.1778)
							(mid -0.249642 0.249642)
							(end -0.1778 0.2794)
						)
						(arc
							(start 0.1778 0.2794)
							(mid 0.249642 0.249642)
							(end 0.2794 0.1778)
						)
						(arc
							(start 0.2794 -0.1778)
							(mid 0.249642 -0.249642)
							(end 0.1778 -0.2794)
						)
					)
					(width 0)
					(fill yes)
				)
			)
		)
	)
	(footprint ""
		(layer "F.Cu")
		(at 9.9568 -87.757)
		(property "Reference" "R30"
			(at 0 0 0)
			(layer "F.SilkS")
			(hide yes)
			(effects
				(font
					(size 1.27 1.27)
				)
			)
		)
		(property "Value" "0R2J-2-GP"
			(at 0.064008 -3.993896 0)
			(unlocked yes)
			(layer "F.Fab")
			(hide yes)
			(effects
				(font
					(size 1.016 1.016)
					(thickness 0.1524)
				)
			)
		)
		(property "Device Type" "R402H16"
			(at 0.064008 -5.517896 0)
			(unlocked yes)
			(layer "F.Fab")
			(hide yes)
			(effects
				(font
					(size 1.016 1.016)
					(thickness 0.1524)
				)
			)
		)
		(duplicate_pad_numbers_are_jumpers no)
		(fp_line
			(start -0.508 -0.9398)
			(end -0.508 0.9398)
			(stroke
				(width 0.1524)
				(type default)
			)
			(layer "F.SilkS")
		)
		(fp_line
			(start 0.508 -0.9398)
			(end -0.508 -0.9398)
			(stroke
				(width 0.1524)
				(type default)
			)
			(layer "F.SilkS")
		)
		(fp_rect
			(start -0.508 0.9398)
			(end 0.508 -0.9398)
			(stroke
				(width 0)
				(type default)
			)
			(fill no)
			(layer "F.CrtYd")
		)
		(fp_rect
			(start -0.508 0.9398)
			(end 0.508 -0.9398)
			(stroke
				(width 0)
				(type default)
			)
			(fill no)
			(layer "F.Fab")
		)
		(pad "1" smd custom
			(at 0 -0.4445)
			(size 0.1397 0.1397)
			(layers "F.Cu" "F.Mask" "F.Paste")
			(net "LED_DR_LED4_K")
			(options
				(clearance outline)
				(anchor circle)
			)
			(primitives
				(gr_poly
					(pts
						(arc
							(start -0.1778 -0.2794)
							(mid -0.249642 -0.249642)
							(end -0.2794 -0.1778)
						)
						(arc
							(start -0.2794 0.1778)
							(mid -0.249642 0.249642)
							(end -0.1778 0.2794)
						)
						(arc
							(start 0.1778 0.2794)
							(mid 0.249642 0.249642)
							(end 0.2794 0.1778)
						)
						(arc
							(start 0.2794 -0.1778)
							(mid 0.249642 -0.249642)
							(end 0.1778 -0.2794)
						)
					)
					(width 0)
					(fill yes)
				)
			)
		)
		(pad "2" smd custom
			(at 0 0.4445)
			(size 0.1397 0.1397)
			(layers "F.Cu" "F.Mask" "F.Paste")
			(net "GND")
			(options
				(clearance outline)
				(anchor circle)
			)
			(primitives
				(gr_poly
					(pts
						(arc
							(start -0.1778 -0.2794)
							(mid -0.249642 -0.249642)
							(end -0.2794 -0.1778)
						)
						(arc
							(start -0.2794 0.1778)
							(mid -0.249642 0.249642)
							(end -0.1778 0.2794)
						)
						(arc
							(start 0.1778 0.2794)
							(mid 0.249642 0.249642)
							(end 0.2794 0.1778)
						)
						(arc
							(start 0.2794 -0.1778)
							(mid 0.249642 -0.249642)
							(end 0.1778 -0.2794)
						)
					)
					(width 0)
					(fill yes)
				)
			)
		)
	)
	(footprint ""
		(layer "F.Cu")
		(at 6.999986 -39.99992)
		(property "Reference" "H2"
			(at 0 0 0)
			(layer "F.SilkS")
			(hide yes)
			(effects
				(font
					(size 1.27 1.27)
				)
			)
		)
		(property "Value" "HOLE315R158"
			(at -5.08 -0.4572 0)
			(unlocked yes)
			(layer "F.Fab")
			(hide yes)
			(effects
				(font
					(size 1.016 1.016)
					(thickness 0.1524)
				)
			)
		)
		(property "Device Type" "HOLE315R158"
			(at -5.08 -1.9812 0)
			(unlocked yes)
			(layer "F.Fab")
			(hide yes)
			(effects
				(font
					(size 1.016 1.016)
					(thickness 0.1524)
				)
			)
		)
		(duplicate_pad_numbers_are_jumpers no)
		(fp_poly
			(pts
				(arc
					(start -4.3053 0)
					(mid 4.3053 0)
					(end -4.3053 0)
				)
			)
			(stroke
				(width 0)
				(type default)
			)
			(fill no)
			(layer "B.CrtYd")
		)
		(fp_poly
			(pts
				(arc
					(start -4.3053 0)
					(mid 4.3053 0)
					(end -4.3053 0)
				)
			)
			(stroke
				(width 0)
				(type default)
			)
			(fill no)
			(layer "F.CrtYd")
		)
		(fp_poly
			(pts
				(arc
					(start -4.3053 0)
					(mid 4.3053 0)
					(end -4.3053 0)
				)
			)
			(stroke
				(width 0)
				(type default)
			)
			(fill no)
			(layer "B.Fab")
		)
		(fp_poly
			(pts
				(arc
					(start -4.3053 0)
					(mid 4.3053 0)
					(end -4.3053 0)
				)
			)
			(stroke
				(width 0)
				(type default)
			)
			(fill no)
			(layer "F.Fab")
		)
		(pad "1" thru_hole circle
			(at 0 0)
			(size 8.001 8.001)
			(drill 4.0132)
			(layers "*.Cu" "*.Mask")
			(remove_unused_layers no)
			(net "GND")
			(clearance -1.4859)
			(thermal_gap 0.3048)
			(padstack
				(mode front_inner_back)
				(layer "Inner"
					(shape circle)
					(size 4.4196 4.4196)
					(clearance 0.3048)
				)
				(layer "B.Cu"
					(shape circle)
					(size 8.001 8.001)
					(clearance -1.4859)
				)
			)
		)
	)
	(footprint ""
		(layer "F.Cu")
		(at 4.040124 -17.29994 -90)
		(property "Reference" "CN6"
			(at 0 0 270)
			(layer "F.SilkS")
			(hide yes)
			(effects
				(font
					(size 1.27 1.27)
				)
			)
		)
		(property "Value" "JWT-CON5-42-GP"
			(at -7.8105 2.9591 270)
			(unlocked yes)
			(layer "F.Fab")
			(hide yes)
			(effects
				(font
					(size 1.016 1.016)
					(thickness 0.1524)
				)
			)
		)
		(property "Device Type" "A2541WR0-1TX5PA-6T-0E"
			(at -7.8105 1.4351 270)
			(unlocked yes)
			(layer "F.Fab")
			(hide yes)
			(effects
				(font
					(size 1.016 1.016)
					(thickness 0.1524)
				)
			)
		)
		(duplicate_pad_numbers_are_jumpers no)
		(fp_line
			(start -6.604 10.287)
			(end 6.604 10.287)
			(stroke
				(width 0.1524)
				(type default)
			)
			(layer "F.SilkS")
		)
		(fp_line
			(start 6.604 10.287)
			(end 6.604 -0.9652)
			(stroke
				(width 0.1524)
				(type default)
			)
			(layer "F.SilkS")
		)
		(fp_line
			(start -6.604 -0.9652)
			(end -6.604 10.287)
			(stroke
				(width 0.1524)
				(type default)
			)
			(layer "F.SilkS")
		)
		(fp_line
			(start 6.604 -0.9652)
			(end -6.604 -0.9652)
			(stroke
				(width 0.1524)
				(type default)
			)
			(layer "F.SilkS")
		)
		(fp_line
			(start -6.731 -1.0922)
			(end -6.731 0.1778)
			(stroke
				(width 0.4064)
				(type default)
			)
			(layer "F.SilkS")
		)
		(fp_line
			(start -5.461 -1.0922)
			(end -6.731 -1.0922)
			(stroke
				(width 0.4064)
				(type default)
			)
			(layer "F.SilkS")
		)
		(fp_circle
			(center -5.08 0)
			(end -5.08 -1.0668)
			(stroke
				(width 0.3048)
				(type default)
			)
			(fill no)
			(layer "F.SilkS")
		)
		(fp_circle
			(center -2.54 0)
			(end -2.54 -1.0668)
			(stroke
				(width 0.3048)
				(type default)
			)
			(fill no)
			(layer "F.SilkS")
		)
		(fp_circle
			(center 0 0)
			(end 0 -1.0668)
			(stroke
				(width 0.3048)
				(type default)
			)
			(fill no)
			(layer "F.SilkS")
		)
		(fp_circle
			(center 2.54 0)
			(end 2.54 -1.0668)
			(stroke
				(width 0.3048)
				(type default)
			)
			(fill no)
			(layer "F.SilkS")
		)
		(fp_circle
			(center 5.08 0)
			(end 5.08 -1.0668)
			(stroke
				(width 0.3048)
				(type default)
			)
			(fill no)
			(layer "F.SilkS")
		)
		(fp_rect
			(start -6.35 10.033)
			(end 6.35 -0.3302)
			(stroke
				(width 0)
				(type default)
			)
			(fill no)
			(layer "F.CrtYd")
		)
		(fp_poly
			(pts
				(xy -6.35 -0.3302) (xy 6.858 -0.3302) (xy 6.858 -1.2192) (xy -6.858 -1.2192) (xy -6.858 10.541)
				(xy 6.858 10.541) (xy 6.858 -0.3175) (xy 6.35 -0.3175) (xy 6.35 10.033) (xy -6.35 10.033)
			)
			(stroke
				(width 0)
				(type default)
			)
			(fill no)
			(layer "F.CrtYd")
		)
		(fp_rect
			(start -6.858 10.541)
			(end 6.858 -1.2192)
			(stroke
				(width 0)
				(type default)
			)
			(fill no)
			(layer "F.Fab")
		)
		(pad "1" thru_hole circle
			(at -5.08 0 270)
			(size 1.4224 1.4224)
			(drill 1.016)
			(layers "*.Cu" "*.Mask")
			(remove_unused_layers no)
			(net "GND")
			(clearance 0.1524)
			(thermal_gap 0.1524)
		)
		(pad "2" thru_hole circle
			(at -2.54 0 270)
			(size 1.4224 1.4224)
			(drill 1.016)
			(layers "*.Cu" "*.Mask")
			(remove_unused_layers no)
			(net "P12V_FAN6")
			(clearance 0.1524)
			(thermal_gap 0.1524)
		)
		(pad "3" thru_hole circle
			(at 0 0 270)
			(size 1.4224 1.4224)
			(drill 1.016)
			(layers "*.Cu" "*.Mask")
			(remove_unused_layers no)
			(net "FAN_TACH12")
			(clearance 0.1524)
			(thermal_gap 0.1524)
		)
		(pad "4" thru_hole circle
			(at 2.54 0 270)
			(size 1.4224 1.4224)
			(drill 1.016)
			(layers "*.Cu" "*.Mask")
			(remove_unused_layers no)
			(net "PWM_OUT_FAN6_NET")
			(clearance 0.1524)
			(thermal_gap 0.1524)
		)
		(pad "5" thru_hole circle
			(at 5.08 0 270)
			(size 1.4224 1.4224)
			(drill 1.016)
			(layers "*.Cu" "*.Mask")
			(remove_unused_layers no)
			(net "FAN_TACH11")
			(clearance 0.1524)
			(thermal_gap 0.1524)
		)
	)
	(footprint ""
		(layer "F.Cu")
		(at 47.0154 -419.7858 90)
		(property "Reference" "C26"
			(at 0 0 90)
			(layer "F.SilkS")
			(hide yes)
			(effects
				(font
					(size 1.27 1.27)
				)
			)
		)
		(property "Value" "SC1U25V3KX-1-GP"
			(at 0 -2.8194 90)
			(unlocked yes)
			(layer "F.Fab")
			(hide yes)
			(effects
				(font
					(size 1.016 1.016)
					(thickness 0.1524)
				)
			)
		)
		(property "Device Type" "C603H36"
			(at 0 -4.3434 90)
			(unlocked yes)
			(layer "F.Fab")
			(hide yes)
			(effects
				(font
					(size 1.016 1.016)
					(thickness 0.1524)
				)
			)
		)
		(duplicate_pad_numbers_are_jumpers no)
		(fp_line
			(start 0.508 0)
			(end -0.508 0)
			(stroke
				(width 0.2032)
				(type default)
			)
			(layer "F.SilkS")
		)
		(fp_rect
			(start -0.5842 1.3335)
			(end 0.5842 -1.3335)
			(stroke
				(width 0)
				(type default)
			)
			(fill no)
			(layer "F.CrtYd")
		)
		(fp_rect
			(start -0.5842 1.3335)
			(end 0.5842 -1.3335)
			(stroke
				(width 0)
				(type default)
			)
			(fill no)
			(layer "F.Fab")
		)
		(pad "1" smd custom
			(at 0 -0.762 90)
			(size 0.2159 0.2159)
			(layers "F.Cu" "F.Mask" "F.Paste")
			(net "P12V_AUX")
			(options
				(clearance outline)
				(anchor circle)
			)
			(primitives
				(gr_poly
					(pts
						(arc
							(start -0.3302 -0.4318)
							(mid -0.402042 -0.402042)
							(end -0.4318 -0.3302)
						)
						(arc
							(start -0.4318 0.3302)
							(mid -0.402042 0.402042)
							(end -0.3302 0.4318)
						)
						(arc
							(start 0.3302 0.4318)
							(mid 0.402042 0.402042)
							(end 0.4318 0.3302)
						)
						(arc
							(start 0.4318 -0.3302)
							(mid 0.402042 -0.402042)
							(end 0.3302 -0.4318)
						)
					)
					(width 0)
					(fill yes)
				)
			)
		)
		(pad "2" smd custom
			(at 0 0.762 90)
			(size 0.2159 0.2159)
			(layers "F.Cu" "F.Mask" "F.Paste")
			(net "GND")
			(options
				(clearance outline)
				(anchor circle)
			)
			(primitives
				(gr_poly
					(pts
						(arc
							(start -0.3302 -0.4318)
							(mid -0.402042 -0.402042)
							(end -0.4318 -0.3302)
						)
						(arc
							(start -0.4318 0.3302)
							(mid -0.402042 0.402042)
							(end -0.3302 0.4318)
						)
						(arc
							(start 0.3302 0.4318)
							(mid 0.402042 0.402042)
							(end 0.4318 0.3302)
						)
						(arc
							(start 0.4318 -0.3302)
							(mid 0.402042 -0.402042)
							(end 0.3302 -0.4318)
						)
					)
					(width 0)
					(fill yes)
				)
			)
		)
	)
	(footprint ""
		(layer "F.Cu")
		(at 39.784274 -363.062774 180)
		(property "Reference" "PR42"
			(at 0 0 180)
			(layer "F.SilkS")
			(hide yes)
			(effects
				(font
					(size 1.27 1.27)
				)
			)
		)
		(property "Value" "10KR2F-2-GP"
			(at 0.064008 -3.993896 180)
			(unlocked yes)
			(layer "F.Fab")
			(hide yes)
			(effects
				(font
					(size 1.016 1.016)
					(thickness 0.1524)
				)
			)
		)
		(property "Device Type" "R402H16"
			(at 0.064008 -5.517896 180)
			(unlocked yes)
			(layer "F.Fab")
			(hide yes)
			(effects
				(font
					(size 1.016 1.016)
					(thickness 0.1524)
				)
			)
		)
		(duplicate_pad_numbers_are_jumpers no)
		(fp_line
			(start 0.508 -0.9398)
			(end -0.508 -0.9398)
			(stroke
				(width 0.1524)
				(type default)
			)
			(layer "F.SilkS")
		)
		(fp_line
			(start -0.508 -0.9398)
			(end -0.508 0.9398)
			(stroke
				(width 0.1524)
				(type default)
			)
			(layer "F.SilkS")
		)
		(fp_rect
			(start -0.508 0.9398)
			(end 0.508 -0.9398)
			(stroke
				(width 0)
				(type default)
			)
			(fill no)
			(layer "F.CrtYd")
		)
		(fp_rect
			(start -0.508 0.9398)
			(end 0.508 -0.9398)
			(stroke
				(width 0)
				(type default)
			)
			(fill no)
			(layer "F.Fab")
		)
		(pad "1" smd custom
			(at 0 -0.4445 180)
			(size 0.1397 0.1397)
			(layers "F.Cu" "F.Mask" "F.Paste")
			(net "TEMP_ALM#_JP_1")
			(options
				(clearance outline)
				(anchor circle)
			)
			(primitives
				(gr_poly
					(pts
						(arc
							(start -0.1778 -0.2794)
							(mid -0.249642 -0.249642)
							(end -0.2794 -0.1778)
						)
						(arc
							(start -0.2794 0.1778)
							(mid -0.249642 0.249642)
							(end -0.1778 0.2794)
						)
						(arc
							(start 0.1778 0.2794)
							(mid 0.249642 0.249642)
							(end 0.2794 0.1778)
						)
						(arc
							(start 0.2794 -0.1778)
							(mid 0.249642 -0.249642)
							(end 0.1778 -0.2794)
						)
					)
					(width 0)
					(fill yes)
				)
			)
		)
		(pad "2" smd custom
			(at 0 0.4445 180)
			(size 0.1397 0.1397)
			(layers "F.Cu" "F.Mask" "F.Paste")
			(net "TEMP_ALM#_REVERSE")
			(options
				(clearance outline)
				(anchor circle)
			)
			(primitives
				(gr_poly
					(pts
						(arc
							(start -0.1778 -0.2794)
							(mid -0.249642 -0.249642)
							(end -0.2794 -0.1778)
						)
						(arc
							(start -0.2794 0.1778)
							(mid -0.249642 0.249642)
							(end -0.1778 0.2794)
						)
						(arc
							(start 0.1778 0.2794)
							(mid 0.249642 0.249642)
							(end 0.2794 0.1778)
						)
						(arc
							(start 0.2794 -0.1778)
							(mid 0.249642 -0.249642)
							(end 0.1778 -0.2794)
						)
					)
					(width 0)
					(fill yes)
				)
			)
		)
	)
	(footprint ""
		(layer "F.Cu")
		(at 27.500072 -144.999964 90)
		(property "Reference" "Q1"
			(at 0 0 90)
			(layer "F.SilkS")
			(hide yes)
			(effects
				(font
					(size 1.27 1.27)
				)
			)
		)
		(property "Value" "PMBS3904-1-GP"
			(at 0 -9.0932 90)
			(unlocked yes)
			(layer "F.Fab")
			(hide yes)
			(effects
				(font
					(size 1.016 1.016)
					(thickness 0.1524)
				)
			)
		)
		(property "Device Type" "SOT-23-10H44"
			(at 0 -10.6172 90)
			(unlocked yes)
			(layer "F.Fab")
			(hide yes)
			(effects
				(font
					(size 1.016 1.016)
					(thickness 0.1524)
				)
			)
		)
		(duplicate_pad_numbers_are_jumpers no)
		(fp_line
			(start 1.651 -1.778)
			(end -1.651 -1.778)
			(stroke
				(width 0.1524)
				(type default)
			)
			(layer "F.SilkS")
		)
		(fp_line
			(start -1.651 -1.778)
			(end -1.651 1.778)
			(stroke
				(width 0.1524)
				(type default)
			)
			(layer "F.SilkS")
		)
		(fp_line
			(start 1.651 1.778)
			(end 1.651 -1.778)
			(stroke
				(width 0.1524)
				(type default)
			)
			(layer "F.SilkS")
		)
		(fp_line
			(start -1.651 1.778)
			(end 1.651 1.778)
			(stroke
				(width 0.1524)
				(type default)
			)
			(layer "F.SilkS")
		)
		(fp_line
			(start -0.9906 1.86309)
			(end -0.701294 2.15265)
			(stroke
				(width 0.0127)
				(type default)
			)
			(layer "F.SilkS")
		)
		(fp_line
			(start -0.994156 1.8669)
			(end -0.987044 1.8669)
			(stroke
				(width 0.0127)
				(type default)
			)
			(layer "F.SilkS")
		)
		(fp_line
			(start -1.003808 1.876552)
			(end -0.977646 1.876552)
			(stroke
				(width 0.0127)
				(type default)
			)
			(layer "F.SilkS")
		)
		(fp_line
			(start -0.635 1.8796)
			(end -1.7526 1.8796)
			(stroke
				(width 0.3302)
				(type default)
			)
			(layer "F.SilkS")
		)
		(fp_line
			(start -1.7526 1.8796)
			(end -1.7526 0.9906)
			(stroke
				(width 0.3302)
				(type default)
			)
			(layer "F.SilkS")
		)
		(fp_line
			(start -1.013206 1.88595)
			(end -0.967994 1.88595)
			(stroke
				(width 0.0127)
				(type default)
			)
			(layer "F.SilkS")
		)
		(fp_line
			(start -1.022858 1.895602)
			(end -0.958596 1.895602)
			(stroke
				(width 0.0127)
				(type default)
			)
			(layer "F.SilkS")
		)
		(fp_line
			(start -1.032256 1.905)
			(end -0.948944 1.905)
			(stroke
				(width 0.0127)
				(type default)
			)
			(layer "F.SilkS")
		)
		(fp_line
			(start -1.041908 1.914652)
			(end -0.939546 1.914652)
			(stroke
				(width 0.0127)
				(type default)
			)
			(layer "F.SilkS")
		)
		(fp_line
			(start -1.051306 1.92405)
			(end -0.929894 1.92405)
			(stroke
				(width 0.0127)
				(type default)
			)
			(layer "F.SilkS")
		)
		(fp_line
			(start -1.060958 1.933702)
			(end -0.920496 1.933702)
			(stroke
				(width 0.0127)
				(type default)
			)
			(layer "F.SilkS")
		)
		(fp_line
			(start -1.070356 1.9431)
			(end -0.910844 1.9431)
			(stroke
				(width 0.0127)
				(type default)
			)
			(layer "F.SilkS")
		)
		(fp_line
			(start -1.080008 1.952752)
			(end -0.901446 1.952752)
			(stroke
				(width 0.0127)
				(type default)
			)
			(layer "F.SilkS")
		)
		(fp_line
			(start -1.089406 1.96215)
			(end -0.891794 1.96215)
			(stroke
				(width 0.0127)
				(type default)
			)
			(layer "F.SilkS")
		)
		(fp_line
			(start -1.099058 1.971802)
			(end -0.882396 1.971802)
			(stroke
				(width 0.0127)
				(type default)
			)
			(layer "F.SilkS")
		)
		(fp_line
			(start -1.108456 1.9812)
			(end -0.872744 1.9812)
			(stroke
				(width 0.0127)
				(type default)
			)
			(layer "F.SilkS")
		)
		(fp_line
			(start -1.118108 1.990852)
			(end -0.863346 1.990852)
			(stroke
				(width 0.0127)
				(type default)
			)
			(layer "F.SilkS")
		)
		(fp_line
			(start -1.127506 2.00025)
			(end -0.853694 2.00025)
			(stroke
				(width 0.0127)
				(type default)
			)
			(layer "F.SilkS")
		)
		(fp_line
			(start -1.137158 2.009902)
			(end -0.844296 2.009902)
			(stroke
				(width 0.0127)
				(type default)
			)
			(layer "F.SilkS")
		)
		(fp_line
			(start -1.146556 2.0193)
			(end -0.834644 2.0193)
			(stroke
				(width 0.0127)
				(type default)
			)
			(layer "F.SilkS")
		)
		(fp_line
			(start -1.156208 2.028952)
			(end -0.825246 2.028952)
			(stroke
				(width 0.0127)
				(type default)
			)
			(layer "F.SilkS")
		)
		(fp_line
			(start -1.165606 2.03835)
			(end -0.815594 2.03835)
			(stroke
				(width 0.0127)
				(type default)
			)
			(layer "F.SilkS")
		)
		(fp_line
			(start -1.175258 2.048002)
			(end -0.806196 2.048002)
			(stroke
				(width 0.0127)
				(type default)
			)
			(layer "F.SilkS")
		)
		(fp_line
			(start -1.184656 2.0574)
			(end -0.796544 2.0574)
			(stroke
				(width 0.0127)
				(type default)
			)
			(layer "F.SilkS")
		)
		(fp_line
			(start -1.194308 2.067052)
			(end -0.787146 2.067052)
			(stroke
				(width 0.0127)
				(type default)
			)
			(layer "F.SilkS")
		)
		(fp_line
			(start -1.203706 2.07645)
			(end -0.777494 2.07645)
			(stroke
				(width 0.0127)
				(type default)
			)
			(layer "F.SilkS")
		)
		(fp_line
			(start -1.213358 2.086102)
			(end -0.768096 2.086102)
			(stroke
				(width 0.0127)
				(type default)
			)
			(layer "F.SilkS")
		)
		(fp_line
			(start -1.222756 2.0955)
			(end -0.758444 2.0955)
			(stroke
				(width 0.0127)
				(type default)
			)
			(layer "F.SilkS")
		)
		(fp_line
			(start -1.232408 2.105152)
			(end -0.749046 2.105152)
			(stroke
				(width 0.0127)
				(type default)
			)
			(layer "F.SilkS")
		)
		(fp_line
			(start -1.241806 2.11455)
			(end -0.739394 2.11455)
			(stroke
				(width 0.0127)
				(type default)
			)
			(layer "F.SilkS")
		)
		(fp_line
			(start -1.251458 2.124202)
			(end -0.729996 2.124202)
			(stroke
				(width 0.0127)
				(type default)
			)
			(layer "F.SilkS")
		)
		(fp_line
			(start -1.260856 2.1336)
			(end -0.720344 2.1336)
			(stroke
				(width 0.0127)
				(type default)
			)
			(layer "F.SilkS")
		)
		(fp_line
			(start -0.719074 2.145538)
			(end -1.265936 2.14122)
			(stroke
				(width 0.0127)
				(type default)
			)
			(layer "F.SilkS")
		)
		(fp_line
			(start -1.279398 2.152142)
			(end -0.9906 1.86309)
			(stroke
				(width 0.0127)
				(type default)
			)
			(layer "F.SilkS")
		)
		(fp_line
			(start -0.71628 2.15265)
			(end -1.26492 2.15265)
			(stroke
				(width 0.0127)
				(type default)
			)
			(layer "F.SilkS")
		)
		(fp_line
			(start -1.279144 2.15265)
			(end -0.701294 2.15265)
			(stroke
				(width 0.0127)
				(type default)
			)
			(layer "F.SilkS")
		)
		(fp_poly
			(pts
				(xy -1.285748 2.159) (xy -1.285748 1.8796) (xy -1.778 1.8796) (xy -1.778 -1.8796) (xy 1.778 -1.8796)
				(xy 1.778 1.8796) (xy -0.694944 1.8796) (xy -0.694944 2.159)
			)
			(stroke
				(width 0)
				(type default)
			)
			(fill no)
			(layer "F.CrtYd")
		)
		(fp_poly
			(pts
				(xy -1.285748 2.159) (xy -1.285748 1.8796) (xy -1.778 1.8796) (xy -1.778 -1.8796) (xy 1.778 -1.8796)
				(xy 1.778 1.8796) (xy -0.694944 1.8796) (xy -0.694944 2.159)
			)
			(stroke
				(width 0)
				(type default)
			)
			(fill no)
			(layer "F.Fab")
		)
		(pad "1" smd rect
			(at -0.98425 0.9525 90)
			(size 0.762 1.143)
			(layers "F.Cu" "F.Mask" "F.Paste")
			(net "NCT7904_D1+")
		)
		(pad "2" smd rect
			(at 0.98425 0.9525 90)
			(size 0.762 1.143)
			(layers "F.Cu" "F.Mask" "F.Paste")
			(net "NCT7904_D1-")
		)
		(pad "3" smd rect
			(at 0 -0.9525 90)
			(size 0.762 1.143)
			(layers "F.Cu" "F.Mask" "F.Paste")
			(net "NCT7904_D1+")
		)
	)
	(footprint ""
		(layer "F.Cu")
		(at 39.8018 -159.2072 90)
		(property "Reference" "TP12"
			(at 0 0 90)
			(layer "F.SilkS")
			(hide yes)
			(effects
				(font
					(size 1.27 1.27)
				)
			)
		)
		(property "Value" "TPAD32-GP"
			(at 0 -3.166364 90)
			(unlocked yes)
			(layer "F.Fab")
			(hide yes)
			(effects
				(font
					(size 1.016 1.016)
					(thickness 0.1524)
				)
			)
		)
		(property "Device Type" "TPAD32"
			(at 0 -4.690618 90)
			(unlocked yes)
			(layer "F.Fab")
			(hide yes)
			(effects
				(font
					(size 1.016 1.016)
					(thickness 0.1524)
				)
			)
		)
		(duplicate_pad_numbers_are_jumpers no)
		(fp_poly
			(pts
				(arc
					(start 0 0.7112)
					(mid 0 -0.7112)
					(end 0 0.7112)
				)
			)
			(stroke
				(width 0)
				(type default)
			)
			(fill no)
			(layer "F.CrtYd")
		)
		(fp_poly
			(pts
				(arc
					(start 0 0.7112)
					(mid 0 -0.7112)
					(end 0 0.7112)
				)
			)
			(stroke
				(width 0)
				(type default)
			)
			(fill no)
			(layer "F.Fab")
		)
		(pad "1" smd circle
			(at 0 0 90)
			(size 0.8128 0.8128)
			(layers "F.Cu" "F.Mask" "F.Paste")
			(net "NCT7904_PECI")
		)
	)
	(footprint ""
		(layer "F.Cu")
		(at 21.8948 -197.2818 90)
		(property "Reference" "R180"
			(at 0 0 90)
			(layer "F.SilkS")
			(hide yes)
			(effects
				(font
					(size 1.27 1.27)
				)
			)
		)
		(property "Value" "0R1206-PAD-1-GP"
			(at 0 -5.0292 90)
			(unlocked yes)
			(layer "F.Fab")
			(hide yes)
			(effects
				(font
					(size 1.016 1.016)
					(thickness 0.1524)
				)
			)
		)
		(property "Device Type" "0R1206-PAD-1"
			(at 0 -6.5532 90)
			(unlocked yes)
			(layer "F.Fab")
			(hide yes)
			(effects
				(font
					(size 1.016 1.016)
					(thickness 0.1524)
				)
			)
		)
		(duplicate_pad_numbers_are_jumpers no)
		(fp_line
			(start 1.016 -2.2352)
			(end -1.016 -2.2352)
			(stroke
				(width 0.1524)
				(type default)
			)
			(layer "F.SilkS")
		)
		(fp_line
			(start -1.016 -2.2352)
			(end -1.016 2.2352)
			(stroke
				(width 0.1524)
				(type default)
			)
			(layer "F.SilkS")
		)
		(fp_line
			(start 1.016 2.2352)
			(end 1.016 -2.2352)
			(stroke
				(width 0.1524)
				(type default)
			)
			(layer "F.SilkS")
		)
		(fp_line
			(start -1.016 2.2352)
			(end 1.016 2.2352)
			(stroke
				(width 0.1524)
				(type default)
			)
			(layer "F.SilkS")
		)
		(fp_rect
			(start -1.0922 2.3114)
			(end 1.0922 -2.3114)
			(stroke
				(width 0)
				(type default)
			)
			(fill no)
			(layer "F.CrtYd")
		)
		(fp_poly
			(pts
				(xy -1.0922 -2.3114) (xy 1.0922 -2.3114) (xy 1.0922 2.3114) (xy -1.0922 2.3114)
			)
			(stroke
				(width 0)
				(type default)
			)
			(fill no)
			(layer "F.Fab")
		)
		(pad "1" smd rect
			(at 0 -1.397 90)
			(size 1.651 2.0574)
			(drill
				(offset 0 0.3937)
			)
			(layers "F.Cu" "F.Mask" "F.Paste")
			(net "P12V_FAN4")
		)
		(pad "2" smd rect
			(at 0 1.397 90)
			(size 1.651 2.0574)
			(drill
				(offset 0 -0.3937)
			)
			(layers "F.Cu" "F.Mask" "F.Paste")
			(net "P12V")
		)
	)
	(footprint ""
		(layer "F.Cu")
		(at 33.401 -240.3094 180)
		(property "Reference" "R54"
			(at 0 0 180)
			(layer "F.SilkS")
			(hide yes)
			(effects
				(font
					(size 1.27 1.27)
				)
			)
		)
		(property "Value" "4K7R2J-2-GP"
			(at 0.064008 -3.993896 180)
			(unlocked yes)
			(layer "F.Fab")
			(hide yes)
			(effects
				(font
					(size 1.016 1.016)
					(thickness 0.1524)
				)
			)
		)
		(property "Device Type" "R402H16"
			(at 0.064008 -5.517896 180)
			(unlocked yes)
			(layer "F.Fab")
			(hide yes)
			(effects
				(font
					(size 1.016 1.016)
					(thickness 0.1524)
				)
			)
		)
		(duplicate_pad_numbers_are_jumpers no)
		(fp_line
			(start 0.508 -0.9398)
			(end -0.508 -0.9398)
			(stroke
				(width 0.1524)
				(type default)
			)
			(layer "F.SilkS")
		)
		(fp_line
			(start -0.508 -0.9398)
			(end -0.508 0.9398)
			(stroke
				(width 0.1524)
				(type default)
			)
			(layer "F.SilkS")
		)
		(fp_rect
			(start -0.508 0.9398)
			(end 0.508 -0.9398)
			(stroke
				(width 0)
				(type default)
			)
			(fill no)
			(layer "F.CrtYd")
		)
		(fp_rect
			(start -0.508 0.9398)
			(end 0.508 -0.9398)
			(stroke
				(width 0)
				(type default)
			)
			(fill no)
			(layer "F.Fab")
		)
		(pad "1" smd custom
			(at 0 -0.4445 180)
			(size 0.1397 0.1397)
			(layers "F.Cu" "F.Mask" "F.Paste")
			(net "GND")
			(options
				(clearance outline)
				(anchor circle)
			)
			(primitives
				(gr_poly
					(pts
						(arc
							(start -0.1778 -0.2794)
							(mid -0.249642 -0.249642)
							(end -0.2794 -0.1778)
						)
						(arc
							(start -0.2794 0.1778)
							(mid -0.249642 0.249642)
							(end -0.1778 0.2794)
						)
						(arc
							(start 0.1778 0.2794)
							(mid 0.249642 0.249642)
							(end 0.2794 0.1778)
						)
						(arc
							(start 0.2794 -0.1778)
							(mid 0.249642 -0.249642)
							(end 0.1778 -0.2794)
						)
					)
					(width 0)
					(fill yes)
				)
			)
		)
		(pad "2" smd custom
			(at 0 0.4445 180)
			(size 0.1397 0.1397)
			(layers "F.Cu" "F.Mask" "F.Paste")
			(net "LED_DRV_A0")
			(options
				(clearance outline)
				(anchor circle)
			)
			(primitives
				(gr_poly
					(pts
						(arc
							(start -0.1778 -0.2794)
							(mid -0.249642 -0.249642)
							(end -0.2794 -0.1778)
						)
						(arc
							(start -0.2794 0.1778)
							(mid -0.249642 0.249642)
							(end -0.1778 0.2794)
						)
						(arc
							(start 0.1778 0.2794)
							(mid 0.249642 0.249642)
							(end 0.2794 0.1778)
						)
						(arc
							(start 0.2794 -0.1778)
							(mid 0.249642 -0.249642)
							(end 0.1778 -0.2794)
						)
					)
					(width 0)
					(fill yes)
				)
			)
		)
	)
	(footprint ""
		(layer "F.Cu")
		(at 28.2956 -141.8082 90)
		(property "Reference" "PC97"
			(at 0 0 90)
			(layer "F.SilkS")
			(hide yes)
			(effects
				(font
					(size 1.27 1.27)
				)
			)
		)
		(property "Value" "SC10U25V5KX-GP"
			(at -0.0762 -6.1214 90)
			(unlocked yes)
			(layer "F.Fab")
			(hide yes)
			(effects
				(font
					(size 1.016 1.016)
					(thickness 0.1524)
				)
			)
		)
		(property "Device Type" "C805H56"
			(at -0.0762 -8.1534 90)
			(unlocked yes)
			(layer "F.Fab")
			(hide yes)
			(effects
				(font
					(size 1.016 1.016)
					(thickness 0.1524)
				)
			)
		)
		(duplicate_pad_numbers_are_jumpers no)
		(fp_line
			(start 0.635 0)
			(end -0.635 0)
			(stroke
				(width 0.508)
				(type default)
			)
			(layer "F.SilkS")
		)
		(fp_rect
			(start -0.9652 1.778)
			(end 0.9652 -1.778)
			(stroke
				(width 0)
				(type default)
			)
			(fill no)
			(layer "F.CrtYd")
		)
		(fp_poly
			(pts
				(xy -0.9652 -1.778) (xy 0.9652 -1.778) (xy 0.9652 1.778) (xy -0.9652 1.778)
			)
			(stroke
				(width 0)
				(type default)
			)
			(fill no)
			(layer "F.Fab")
		)
		(pad "1" smd rect
			(at 0 -0.9652 90)
			(size 1.397 1.143)
			(layers "F.Cu" "F.Mask" "F.Paste")
			(net "P12VU_2490_EN_2")
		)
		(pad "2" smd rect
			(at 0 0.9652 90)
			(size 1.397 1.143)
			(layers "F.Cu" "F.Mask" "F.Paste")
			(net "GND")
		)
	)
	(footprint ""
		(layer "F.Cu")
		(at 32.399224 -174.76851 90)
		(property "Reference" "R18"
			(at 0 0 90)
			(layer "F.SilkS")
			(hide yes)
			(effects
				(font
					(size 1.27 1.27)
				)
			)
		)
		(property "Value" "100KR2F-L1-GP"
			(at 0.064008 -3.993896 90)
			(unlocked yes)
			(layer "F.Fab")
			(hide yes)
			(effects
				(font
					(size 1.016 1.016)
					(thickness 0.1524)
				)
			)
		)
		(property "Device Type" "R402H16"
			(at 0.064008 -5.517896 90)
			(unlocked yes)
			(layer "F.Fab")
			(hide yes)
			(effects
				(font
					(size 1.016 1.016)
					(thickness 0.1524)
				)
			)
		)
		(duplicate_pad_numbers_are_jumpers no)
		(fp_line
			(start 0.508 -0.9398)
			(end -0.508 -0.9398)
			(stroke
				(width 0.1524)
				(type default)
			)
			(layer "F.SilkS")
		)
		(fp_line
			(start -0.508 -0.9398)
			(end -0.508 0.9398)
			(stroke
				(width 0.1524)
				(type default)
			)
			(layer "F.SilkS")
		)
		(fp_rect
			(start -0.508 0.9398)
			(end 0.508 -0.9398)
			(stroke
				(width 0)
				(type default)
			)
			(fill no)
			(layer "F.CrtYd")
		)
		(fp_rect
			(start -0.508 0.9398)
			(end 0.508 -0.9398)
			(stroke
				(width 0)
				(type default)
			)
			(fill no)
			(layer "F.Fab")
		)
		(pad "1" smd custom
			(at 0 -0.4445 90)
			(size 0.1397 0.1397)
			(layers "F.Cu" "F.Mask" "F.Paste")
			(net "PWM_EXP_1B")
			(options
				(clearance outline)
				(anchor circle)
			)
			(primitives
				(gr_poly
					(pts
						(arc
							(start -0.1778 -0.2794)
							(mid -0.249642 -0.249642)
							(end -0.2794 -0.1778)
						)
						(arc
							(start -0.2794 0.1778)
							(mid -0.249642 0.249642)
							(end -0.1778 0.2794)
						)
						(arc
							(start 0.1778 0.2794)
							(mid 0.249642 0.249642)
							(end 0.2794 0.1778)
						)
						(arc
							(start 0.2794 -0.1778)
							(mid 0.249642 -0.249642)
							(end 0.1778 -0.2794)
						)
					)
					(width 0)
					(fill yes)
				)
			)
		)
		(pad "2" smd custom
			(at 0 0.4445 90)
			(size 0.1397 0.1397)
			(layers "F.Cu" "F.Mask" "F.Paste")
			(net "GND")
			(options
				(clearance outline)
				(anchor circle)
			)
			(primitives
				(gr_poly
					(pts
						(arc
							(start -0.1778 -0.2794)
							(mid -0.249642 -0.249642)
							(end -0.2794 -0.1778)
						)
						(arc
							(start -0.2794 0.1778)
							(mid -0.249642 0.249642)
							(end -0.1778 0.2794)
						)
						(arc
							(start 0.1778 0.2794)
							(mid 0.249642 0.249642)
							(end 0.2794 0.1778)
						)
						(arc
							(start 0.2794 -0.1778)
							(mid 0.249642 -0.249642)
							(end 0.1778 -0.2794)
						)
					)
					(width 0)
					(fill yes)
				)
			)
		)
	)
	(footprint ""
		(layer "F.Cu")
		(at 39.0652 -361.5436 90)
		(property "Reference" "PR46"
			(at 0 0 90)
			(layer "F.SilkS")
			(hide yes)
			(effects
				(font
					(size 1.27 1.27)
				)
			)
		)
		(property "Value" "51KR2F-L-GP"
			(at 0.064008 -3.993896 90)
			(unlocked yes)
			(layer "F.Fab")
			(hide yes)
			(effects
				(font
					(size 1.016 1.016)
					(thickness 0.1524)
				)
			)
		)
		(property "Device Type" "R402H16"
			(at 0.064008 -5.517896 90)
			(unlocked yes)
			(layer "F.Fab")
			(hide yes)
			(effects
				(font
					(size 1.016 1.016)
					(thickness 0.1524)
				)
			)
		)
		(duplicate_pad_numbers_are_jumpers no)
		(fp_line
			(start 0.508 -0.9398)
			(end -0.508 -0.9398)
			(stroke
				(width 0.1524)
				(type default)
			)
			(layer "F.SilkS")
		)
		(fp_line
			(start -0.508 -0.9398)
			(end -0.508 0.9398)
			(stroke
				(width 0.1524)
				(type default)
			)
			(layer "F.SilkS")
		)
		(fp_rect
			(start -0.508 0.9398)
			(end 0.508 -0.9398)
			(stroke
				(width 0)
				(type default)
			)
			(fill no)
			(layer "F.CrtYd")
		)
		(fp_rect
			(start -0.508 0.9398)
			(end 0.508 -0.9398)
			(stroke
				(width 0)
				(type default)
			)
			(fill no)
			(layer "F.Fab")
		)
		(pad "1" smd custom
			(at 0 -0.4445 90)
			(size 0.1397 0.1397)
			(layers "F.Cu" "F.Mask" "F.Paste")
			(net "P12V_AUX")
			(options
				(clearance outline)
				(anchor circle)
			)
			(primitives
				(gr_poly
					(pts
						(arc
							(start -0.1778 -0.2794)
							(mid -0.249642 -0.249642)
							(end -0.2794 -0.1778)
						)
						(arc
							(start -0.2794 0.1778)
							(mid -0.249642 0.249642)
							(end -0.1778 0.2794)
						)
						(arc
							(start 0.1778 0.2794)
							(mid 0.249642 0.249642)
							(end 0.2794 0.1778)
						)
						(arc
							(start 0.2794 -0.1778)
							(mid 0.249642 -0.249642)
							(end 0.1778 -0.2794)
						)
					)
					(width 0)
					(fill yes)
				)
			)
		)
		(pad "2" smd custom
			(at 0 0.4445 90)
			(size 0.1397 0.1397)
			(layers "F.Cu" "F.Mask" "F.Paste")
			(net "TEMP_ALM#_JP_1")
			(options
				(clearance outline)
				(anchor circle)
			)
			(primitives
				(gr_poly
					(pts
						(arc
							(start -0.1778 -0.2794)
							(mid -0.249642 -0.249642)
							(end -0.2794 -0.1778)
						)
						(arc
							(start -0.2794 0.1778)
							(mid -0.249642 0.249642)
							(end -0.1778 0.2794)
						)
						(arc
							(start 0.1778 0.2794)
							(mid 0.249642 0.249642)
							(end 0.2794 0.1778)
						)
						(arc
							(start 0.2794 -0.1778)
							(mid 0.249642 -0.249642)
							(end 0.1778 -0.2794)
						)
					)
					(width 0)
					(fill yes)
				)
			)
		)
	)
	(footprint ""
		(layer "F.Cu")
		(at 11.9634 -232.7656 90)
		(property "Reference" "R34"
			(at 0 0 90)
			(layer "F.SilkS")
			(hide yes)
			(effects
				(font
					(size 1.27 1.27)
				)
			)
		)
		(property "Value" "0R2J-2-GP"
			(at 0.064008 -3.993896 90)
			(unlocked yes)
			(layer "F.Fab")
			(hide yes)
			(effects
				(font
					(size 1.016 1.016)
					(thickness 0.1524)
				)
			)
		)
		(property "Device Type" "R402H16"
			(at 0.064008 -5.517896 90)
			(unlocked yes)
			(layer "F.Fab")
			(hide yes)
			(effects
				(font
					(size 1.016 1.016)
					(thickness 0.1524)
				)
			)
		)
		(duplicate_pad_numbers_are_jumpers no)
		(fp_line
			(start 0.508 -0.9398)
			(end -0.508 -0.9398)
			(stroke
				(width 0.1524)
				(type default)
			)
			(layer "F.SilkS")
		)
		(fp_line
			(start -0.508 -0.9398)
			(end -0.508 0.9398)
			(stroke
				(width 0.1524)
				(type default)
			)
			(layer "F.SilkS")
		)
		(fp_rect
			(start -0.508 0.9398)
			(end 0.508 -0.9398)
			(stroke
				(width 0)
				(type default)
			)
			(fill no)
			(layer "F.CrtYd")
		)
		(fp_rect
			(start -0.508 0.9398)
			(end 0.508 -0.9398)
			(stroke
				(width 0)
				(type default)
			)
			(fill no)
			(layer "F.Fab")
		)
		(pad "1" smd custom
			(at 0 -0.4445 90)
			(size 0.1397 0.1397)
			(layers "F.Cu" "F.Mask" "F.Paste")
			(net "LED_DR_LED3_K")
			(options
				(clearance outline)
				(anchor circle)
			)
			(primitives
				(gr_poly
					(pts
						(arc
							(start -0.1778 -0.2794)
							(mid -0.249642 -0.249642)
							(end -0.2794 -0.1778)
						)
						(arc
							(start -0.2794 0.1778)
							(mid -0.249642 0.249642)
							(end -0.1778 0.2794)
						)
						(arc
							(start 0.1778 0.2794)
							(mid 0.249642 0.249642)
							(end 0.2794 0.1778)
						)
						(arc
							(start 0.2794 -0.1778)
							(mid 0.249642 -0.249642)
							(end 0.1778 -0.2794)
						)
					)
					(width 0)
					(fill yes)
				)
			)
		)
		(pad "2" smd custom
			(at 0 0.4445 90)
			(size 0.1397 0.1397)
			(layers "F.Cu" "F.Mask" "F.Paste")
			(net "GND")
			(options
				(clearance outline)
				(anchor circle)
			)
			(primitives
				(gr_poly
					(pts
						(arc
							(start -0.1778 -0.2794)
							(mid -0.249642 -0.249642)
							(end -0.2794 -0.1778)
						)
						(arc
							(start -0.2794 0.1778)
							(mid -0.249642 0.249642)
							(end -0.1778 0.2794)
						)
						(arc
							(start 0.1778 0.2794)
							(mid 0.249642 0.249642)
							(end 0.2794 0.1778)
						)
						(arc
							(start 0.2794 -0.1778)
							(mid 0.249642 -0.249642)
							(end 0.1778 -0.2794)
						)
					)
					(width 0)
					(fill yes)
				)
			)
		)
	)
	(footprint ""
		(layer "F.Cu")
		(at 23.1902 -145.161 180)
		(property "Reference" "PR112"
			(at 0 0 180)
			(layer "F.SilkS")
			(hide yes)
			(effects
				(font
					(size 1.27 1.27)
				)
			)
		)
		(property "Value" "6K81R2F-1-GP"
			(at 0.064008 -3.993896 180)
			(unlocked yes)
			(layer "F.Fab")
			(hide yes)
			(effects
				(font
					(size 1.016 1.016)
					(thickness 0.1524)
				)
			)
		)
		(property "Device Type" "R402H16"
			(at 0.064008 -5.517896 180)
			(unlocked yes)
			(layer "F.Fab")
			(hide yes)
			(effects
				(font
					(size 1.016 1.016)
					(thickness 0.1524)
				)
			)
		)
		(duplicate_pad_numbers_are_jumpers no)
		(fp_line
			(start 0.508 -0.9398)
			(end -0.508 -0.9398)
			(stroke
				(width 0.1524)
				(type default)
			)
			(layer "F.SilkS")
		)
		(fp_line
			(start -0.508 -0.9398)
			(end -0.508 0.9398)
			(stroke
				(width 0.1524)
				(type default)
			)
			(layer "F.SilkS")
		)
		(fp_rect
			(start -0.508 0.9398)
			(end 0.508 -0.9398)
			(stroke
				(width 0)
				(type default)
			)
			(fill no)
			(layer "F.CrtYd")
		)
		(fp_rect
			(start -0.508 0.9398)
			(end 0.508 -0.9398)
			(stroke
				(width 0)
				(type default)
			)
			(fill no)
			(layer "F.Fab")
		)
		(pad "1" smd custom
			(at 0 -0.4445 180)
			(size 0.1397 0.1397)
			(layers "F.Cu" "F.Mask" "F.Paste")
			(net "P12VU_2490_EN_2")
			(options
				(clearance outline)
				(anchor circle)
			)
			(primitives
				(gr_poly
					(pts
						(arc
							(start -0.1778 -0.2794)
							(mid -0.249642 -0.249642)
							(end -0.2794 -0.1778)
						)
						(arc
							(start -0.2794 0.1778)
							(mid -0.249642 0.249642)
							(end -0.1778 0.2794)
						)
						(arc
							(start 0.1778 0.2794)
							(mid 0.249642 0.249642)
							(end 0.2794 0.1778)
						)
						(arc
							(start 0.2794 -0.1778)
							(mid 0.249642 -0.249642)
							(end 0.1778 -0.2794)
						)
					)
					(width 0)
					(fill yes)
				)
			)
		)
		(pad "2" smd custom
			(at 0 0.4445 180)
			(size 0.1397 0.1397)
			(layers "F.Cu" "F.Mask" "F.Paste")
			(net "GND")
			(options
				(clearance outline)
				(anchor circle)
			)
			(primitives
				(gr_poly
					(pts
						(arc
							(start -0.1778 -0.2794)
							(mid -0.249642 -0.249642)
							(end -0.2794 -0.1778)
						)
						(arc
							(start -0.2794 0.1778)
							(mid -0.249642 0.249642)
							(end -0.1778 0.2794)
						)
						(arc
							(start 0.1778 0.2794)
							(mid 0.249642 0.249642)
							(end 0.2794 0.1778)
						)
						(arc
							(start 0.2794 -0.1778)
							(mid 0.249642 -0.249642)
							(end 0.1778 -0.2794)
						)
					)
					(width 0)
					(fill yes)
				)
			)
		)
	)
	(footprint ""
		(layer "F.Cu")
		(at 40.26789 -154.147266 180)
		(property "Reference" "L1"
			(at 0 0 180)
			(layer "F.SilkS")
			(hide yes)
			(effects
				(font
					(size 1.27 1.27)
				)
			)
		)
		(property "Value" "FCM1608CF-121T03-GP"
			(at -0.0254 -2.8956 180)
			(unlocked yes)
			(layer "F.Fab")
			(hide yes)
			(effects
				(font
					(size 1.016 1.016)
					(thickness 0.1524)
				)
			)
		)
		(property "Device Type" "L1608-UH38"
			(at -0.0254 -4.4196 180)
			(unlocked yes)
			(layer "F.Fab")
			(hide yes)
			(effects
				(font
					(size 1.016 1.016)
					(thickness 0.1524)
				)
			)
		)
		(duplicate_pad_numbers_are_jumpers no)
		(fp_line
			(start 0.254 0)
			(end -0.254 0)
			(stroke
				(width 0.2032)
				(type default)
			)
			(layer "F.SilkS")
		)
		(fp_rect
			(start -0.5842 1.3335)
			(end 0.5842 -1.3335)
			(stroke
				(width 0)
				(type default)
			)
			(fill no)
			(layer "F.CrtYd")
		)
		(fp_rect
			(start -0.5842 1.3335)
			(end 0.5842 -1.3335)
			(stroke
				(width 0)
				(type default)
			)
			(fill no)
			(layer "F.Fab")
		)
		(pad "1" smd custom
			(at 0 -0.762 180)
			(size 0.2159 0.2159)
			(layers "F.Cu" "F.Mask" "F.Paste")
			(net "P3V3")
			(options
				(clearance outline)
				(anchor circle)
			)
			(primitives
				(gr_poly
					(pts
						(arc
							(start -0.3302 -0.4318)
							(mid -0.402042 -0.402042)
							(end -0.4318 -0.3302)
						)
						(arc
							(start -0.4318 0.3302)
							(mid -0.402042 0.402042)
							(end -0.3302 0.4318)
						)
						(arc
							(start 0.3302 0.4318)
							(mid 0.402042 0.402042)
							(end 0.4318 0.3302)
						)
						(arc
							(start 0.4318 -0.3302)
							(mid 0.402042 -0.402042)
							(end 0.3302 -0.4318)
						)
					)
					(width 0)
					(fill yes)
				)
			)
		)
		(pad "2" smd custom
			(at 0 0.762 180)
			(size 0.2159 0.2159)
			(layers "F.Cu" "F.Mask" "F.Paste")
			(net "NCT7904_3VDD")
			(options
				(clearance outline)
				(anchor circle)
			)
			(primitives
				(gr_poly
					(pts
						(arc
							(start -0.3302 -0.4318)
							(mid -0.402042 -0.402042)
							(end -0.4318 -0.3302)
						)
						(arc
							(start -0.4318 0.3302)
							(mid -0.402042 0.402042)
							(end -0.3302 0.4318)
						)
						(arc
							(start 0.3302 0.4318)
							(mid 0.402042 0.402042)
							(end 0.4318 0.3302)
						)
						(arc
							(start 0.4318 -0.3302)
							(mid 0.402042 -0.402042)
							(end 0.3302 -0.4318)
						)
					)
					(width 0)
					(fill yes)
				)
			)
		)
	)
	(footprint ""
		(layer "F.Cu")
		(at 28.8544 -357.6828 90)
		(property "Reference" "R366"
			(at 0 0 90)
			(layer "F.SilkS")
			(hide yes)
			(effects
				(font
					(size 1.27 1.27)
				)
			)
		)
		(property "Value" "10KR2F-2-GP"
			(at 0.064008 -3.993896 90)
			(unlocked yes)
			(layer "F.Fab")
			(hide yes)
			(effects
				(font
					(size 1.016 1.016)
					(thickness 0.1524)
				)
			)
		)
		(property "Device Type" "R402H16"
			(at 0.064008 -5.517896 90)
			(unlocked yes)
			(layer "F.Fab")
			(hide yes)
			(effects
				(font
					(size 1.016 1.016)
					(thickness 0.1524)
				)
			)
		)
		(duplicate_pad_numbers_are_jumpers no)
		(fp_line
			(start 0.508 -0.9398)
			(end -0.508 -0.9398)
			(stroke
				(width 0.1524)
				(type default)
			)
			(layer "F.SilkS")
		)
		(fp_line
			(start -0.508 -0.9398)
			(end -0.508 0.9398)
			(stroke
				(width 0.1524)
				(type default)
			)
			(layer "F.SilkS")
		)
		(fp_rect
			(start -0.508 0.9398)
			(end 0.508 -0.9398)
			(stroke
				(width 0)
				(type default)
			)
			(fill no)
			(layer "F.CrtYd")
		)
		(fp_rect
			(start -0.508 0.9398)
			(end 0.508 -0.9398)
			(stroke
				(width 0)
				(type default)
			)
			(fill no)
			(layer "F.Fab")
		)
		(pad "1" smd custom
			(at 0 -0.4445 90)
			(size 0.1397 0.1397)
			(layers "F.Cu" "F.Mask" "F.Paste")
			(net "P3V3")
			(options
				(clearance outline)
				(anchor circle)
			)
			(primitives
				(gr_poly
					(pts
						(arc
							(start -0.1778 -0.2794)
							(mid -0.249642 -0.249642)
							(end -0.2794 -0.1778)
						)
						(arc
							(start -0.2794 0.1778)
							(mid -0.249642 0.249642)
							(end -0.1778 0.2794)
						)
						(arc
							(start 0.1778 0.2794)
							(mid 0.249642 0.249642)
							(end 0.2794 0.1778)
						)
						(arc
							(start 0.2794 -0.1778)
							(mid 0.249642 -0.249642)
							(end 0.1778 -0.2794)
						)
					)
					(width 0)
					(fill yes)
				)
			)
		)
		(pad "2" smd custom
			(at 0 0.4445 90)
			(size 0.1397 0.1397)
			(layers "F.Cu" "F.Mask" "F.Paste")
			(net "TEMP_ALM#")
			(options
				(clearance outline)
				(anchor circle)
			)
			(primitives
				(gr_poly
					(pts
						(arc
							(start -0.1778 -0.2794)
							(mid -0.249642 -0.249642)
							(end -0.2794 -0.1778)
						)
						(arc
							(start -0.2794 0.1778)
							(mid -0.249642 0.249642)
							(end -0.1778 0.2794)
						)
						(arc
							(start 0.1778 0.2794)
							(mid 0.249642 0.249642)
							(end 0.2794 0.1778)
						)
						(arc
							(start 0.2794 -0.1778)
							(mid 0.249642 -0.249642)
							(end 0.1778 -0.2794)
						)
					)
					(width 0)
					(fill yes)
				)
			)
		)
	)
	(footprint ""
		(layer "F.Cu")
		(at 26.6446 -167.767 180)
		(property "Reference" "R163"
			(at 0 0 180)
			(layer "F.SilkS")
			(hide yes)
			(effects
				(font
					(size 1.27 1.27)
				)
			)
		)
		(property "Value" "0R2J-2-GP"
			(at 0.064008 -3.993896 180)
			(unlocked yes)
			(layer "F.Fab")
			(hide yes)
			(effects
				(font
					(size 1.016 1.016)
					(thickness 0.1524)
				)
			)
		)
		(property "Device Type" "R402H16"
			(at 0.064008 -5.517896 180)
			(unlocked yes)
			(layer "F.Fab")
			(hide yes)
			(effects
				(font
					(size 1.016 1.016)
					(thickness 0.1524)
				)
			)
		)
		(duplicate_pad_numbers_are_jumpers no)
		(fp_line
			(start 0.508 -0.9398)
			(end -0.508 -0.9398)
			(stroke
				(width 0.1524)
				(type default)
			)
			(layer "F.SilkS")
		)
		(fp_line
			(start -0.508 -0.9398)
			(end -0.508 0.9398)
			(stroke
				(width 0.1524)
				(type default)
			)
			(layer "F.SilkS")
		)
		(fp_rect
			(start -0.508 0.9398)
			(end 0.508 -0.9398)
			(stroke
				(width 0)
				(type default)
			)
			(fill no)
			(layer "F.CrtYd")
		)
		(fp_rect
			(start -0.508 0.9398)
			(end 0.508 -0.9398)
			(stroke
				(width 0)
				(type default)
			)
			(fill no)
			(layer "F.Fab")
		)
		(pad "1" smd custom
			(at 0 -0.4445 180)
			(size 0.1397 0.1397)
			(layers "F.Cu" "F.Mask" "F.Paste")
			(net "NCT7904D_PWM3")
			(options
				(clearance outline)
				(anchor circle)
			)
			(primitives
				(gr_poly
					(pts
						(arc
							(start -0.1778 -0.2794)
							(mid -0.249642 -0.249642)
							(end -0.2794 -0.1778)
						)
						(arc
							(start -0.2794 0.1778)
							(mid -0.249642 0.249642)
							(end -0.1778 0.2794)
						)
						(arc
							(start 0.1778 0.2794)
							(mid 0.249642 0.249642)
							(end 0.2794 0.1778)
						)
						(arc
							(start 0.2794 -0.1778)
							(mid 0.249642 -0.249642)
							(end 0.1778 -0.2794)
						)
					)
					(width 0)
					(fill yes)
				)
			)
		)
		(pad "2" smd custom
			(at 0 0.4445 180)
			(size 0.1397 0.1397)
			(layers "F.Cu" "F.Mask" "F.Paste")
			(net "PWM_BUFFER_IN_FAN5_FAN6")
			(options
				(clearance outline)
				(anchor circle)
			)
			(primitives
				(gr_poly
					(pts
						(arc
							(start -0.1778 -0.2794)
							(mid -0.249642 -0.249642)
							(end -0.2794 -0.1778)
						)
						(arc
							(start -0.2794 0.1778)
							(mid -0.249642 0.249642)
							(end -0.1778 0.2794)
						)
						(arc
							(start 0.1778 0.2794)
							(mid 0.249642 0.249642)
							(end 0.2794 0.1778)
						)
						(arc
							(start 0.2794 -0.1778)
							(mid 0.249642 -0.249642)
							(end 0.1778 -0.2794)
						)
					)
					(width 0)
					(fill yes)
				)
			)
		)
	)
	(footprint ""
		(layer "F.Cu")
		(at 22.1996 -146.2786 180)
		(property "Reference" "PC93"
			(at 0 0 180)
			(layer "F.SilkS")
			(hide yes)
			(effects
				(font
					(size 1.27 1.27)
				)
			)
		)
		(property "Value" "SC220P50V2KX-3GP"
			(at 1.1811 -2.7051 180)
			(unlocked yes)
			(layer "F.Fab")
			(hide yes)
			(effects
				(font
					(size 1.016 1.016)
					(thickness 0.1524)
				)
			)
		)
		(property "Device Type" "C402H22"
			(at 1.1811 -4.2291 180)
			(unlocked yes)
			(layer "F.Fab")
			(hide yes)
			(effects
				(font
					(size 1.016 1.016)
					(thickness 0.1524)
				)
			)
		)
		(duplicate_pad_numbers_are_jumpers no)
		(fp_rect
			(start -0.4318 0.9525)
			(end 0.4318 -0.9525)
			(stroke
				(width 0)
				(type default)
			)
			(fill no)
			(layer "F.CrtYd")
		)
		(fp_rect
			(start -0.4318 0.9525)
			(end 0.4318 -0.9525)
			(stroke
				(width 0)
				(type default)
			)
			(fill no)
			(layer "F.Fab")
		)
		(pad "1" smd custom
			(at 0 -0.4445 180)
			(size 0.1524 0.1524)
			(layers "F.Cu" "F.Mask" "F.Paste")
			(net "P12VU_2490_VREF")
			(options
				(clearance outline)
				(anchor circle)
			)
			(primitives
				(gr_poly
					(pts
						(arc
							(start 0.3048 -0.2032)
							(mid 0.275042 -0.275042)
							(end 0.2032 -0.3048)
						)
						(arc
							(start -0.2032 -0.3048)
							(mid -0.275042 -0.275042)
							(end -0.3048 -0.2032)
						)
						(arc
							(start -0.3048 0.2032)
							(mid -0.275042 0.275042)
							(end -0.2032 0.3048)
						)
						(arc
							(start 0.2032 0.3048)
							(mid 0.275042 0.275042)
							(end 0.3048 0.2032)
						)
					)
					(width 0)
					(fill yes)
				)
			)
		)
		(pad "2" smd custom
			(at 0 0.4445 180)
			(size 0.1524 0.1524)
			(layers "F.Cu" "F.Mask" "F.Paste")
			(net "GND")
			(options
				(clearance outline)
				(anchor circle)
			)
			(primitives
				(gr_poly
					(pts
						(arc
							(start 0.3048 -0.2032)
							(mid 0.275042 -0.275042)
							(end 0.2032 -0.3048)
						)
						(arc
							(start -0.2032 -0.3048)
							(mid -0.275042 -0.275042)
							(end -0.3048 -0.2032)
						)
						(arc
							(start -0.3048 0.2032)
							(mid -0.275042 0.275042)
							(end -0.2032 0.3048)
						)
						(arc
							(start 0.2032 0.3048)
							(mid 0.275042 0.275042)
							(end 0.3048 0.2032)
						)
					)
					(width 0)
					(fill yes)
				)
			)
		)
	)
	(footprint ""
		(layer "F.Cu")
		(at 32.766 -381 180)
		(property "Reference" "PR22"
			(at 0 0 180)
			(layer "F.SilkS")
			(hide yes)
			(effects
				(font
					(size 1.27 1.27)
				)
			)
		)
		(property "Value" "10R2F-L-GP"
			(at 0.064008 -3.993896 180)
			(unlocked yes)
			(layer "F.Fab")
			(hide yes)
			(effects
				(font
					(size 1.016 1.016)
					(thickness 0.1524)
				)
			)
		)
		(property "Device Type" "R402H14"
			(at 0.064008 -5.517896 180)
			(unlocked yes)
			(layer "F.Fab")
			(hide yes)
			(effects
				(font
					(size 1.016 1.016)
					(thickness 0.1524)
				)
			)
		)
		(duplicate_pad_numbers_are_jumpers no)
		(fp_line
			(start 0.508 -0.9398)
			(end -0.508 -0.9398)
			(stroke
				(width 0.1524)
				(type default)
			)
			(layer "F.SilkS")
		)
		(fp_line
			(start -0.508 -0.9398)
			(end -0.508 0.9398)
			(stroke
				(width 0.1524)
				(type default)
			)
			(layer "F.SilkS")
		)
		(fp_rect
			(start -0.508 0.9398)
			(end 0.508 -0.9398)
			(stroke
				(width 0)
				(type default)
			)
			(fill no)
			(layer "F.CrtYd")
		)
		(fp_rect
			(start -0.508 0.9398)
			(end 0.508 -0.9398)
			(stroke
				(width 0)
				(type default)
			)
			(fill no)
			(layer "F.Fab")
		)
		(pad "1" smd custom
			(at 0 -0.4445 180)
			(size 0.1397 0.1397)
			(layers "F.Cu" "F.Mask" "F.Paste")
			(net "ADM1276_SENSE-")
			(options
				(clearance outline)
				(anchor circle)
			)
			(primitives
				(gr_poly
					(pts
						(arc
							(start -0.1778 -0.2794)
							(mid -0.249642 -0.249642)
							(end -0.2794 -0.1778)
						)
						(arc
							(start -0.2794 0.1778)
							(mid -0.249642 0.249642)
							(end -0.1778 0.2794)
						)
						(arc
							(start 0.1778 0.2794)
							(mid 0.249642 0.249642)
							(end 0.2794 0.1778)
						)
						(arc
							(start 0.2794 -0.1778)
							(mid 0.249642 -0.249642)
							(end 0.1778 -0.2794)
						)
					)
					(width 0)
					(fill yes)
				)
			)
		)
		(pad "2" smd custom
			(at 0 0.4445 180)
			(size 0.1397 0.1397)
			(layers "F.Cu" "F.Mask" "F.Paste")
			(net "SENSE-_R2")
			(options
				(clearance outline)
				(anchor circle)
			)
			(primitives
				(gr_poly
					(pts
						(arc
							(start -0.1778 -0.2794)
							(mid -0.249642 -0.249642)
							(end -0.2794 -0.1778)
						)
						(arc
							(start -0.2794 0.1778)
							(mid -0.249642 0.249642)
							(end -0.1778 0.2794)
						)
						(arc
							(start 0.1778 0.2794)
							(mid 0.249642 0.249642)
							(end 0.2794 0.1778)
						)
						(arc
							(start 0.2794 -0.1778)
							(mid 0.249642 -0.249642)
							(end 0.1778 -0.2794)
						)
					)
					(width 0)
					(fill yes)
				)
			)
		)
	)
	(footprint ""
		(layer "F.Cu")
		(at 7.949946 -88.535002 -90)
		(property "Reference" "LED5"
			(at 0 0 270)
			(layer "F.SilkS")
			(hide yes)
			(effects
				(font
					(size 1.27 1.27)
				)
			)
		)
		(property "Value" "LED-RB-6-GP"
			(at -4.6736 3.8354 270)
			(unlocked yes)
			(layer "F.Fab")
			(hide yes)
			(effects
				(font
					(size 1.016 1.016)
					(thickness 0.1524)
				)
			)
		)
		(property "Device Type" "LED-100-3P-067106H325"
			(at -4.6736 2.3114 270)
			(unlocked yes)
			(layer "F.Fab")
			(hide yes)
			(effects
				(font
					(size 1.016 1.016)
					(thickness 0.1524)
				)
			)
		)
		(duplicate_pad_numbers_are_jumpers no)
		(fp_line
			(start -1.7526 10.414)
			(end -1.7526 6.6548)
			(stroke
				(width 0.1524)
				(type default)
			)
			(layer "F.SilkS")
		)
		(fp_line
			(start 1.7526 10.414)
			(end -1.7526 10.414)
			(stroke
				(width 0.1524)
				(type default)
			)
			(layer "F.SilkS")
		)
		(fp_line
			(start -3.6068 6.6548)
			(end -3.6068 -0.889)
			(stroke
				(width 0.1524)
				(type default)
			)
			(layer "F.SilkS")
		)
		(fp_line
			(start -1.7526 6.6548)
			(end -3.6068 6.6548)
			(stroke
				(width 0.1524)
				(type default)
			)
			(layer "F.SilkS")
		)
		(fp_line
			(start 1.7526 6.6548)
			(end 1.7526 10.414)
			(stroke
				(width 0.1524)
				(type default)
			)
			(layer "F.SilkS")
		)
		(fp_line
			(start 3.6068 6.6548)
			(end 1.7526 6.6548)
			(stroke
				(width 0.1524)
				(type default)
			)
			(layer "F.SilkS")
		)
		(fp_line
			(start -3.6068 -0.889)
			(end 3.6068 -0.889)
			(stroke
				(width 0.1524)
				(type default)
			)
			(layer "F.SilkS")
		)
		(fp_line
			(start 3.6068 -0.889)
			(end 3.6068 6.6548)
			(stroke
				(width 0.1524)
				(type default)
			)
			(layer "F.SilkS")
		)
		(fp_circle
			(center -2.54 0)
			(end -2.54 -0.9906)
			(stroke
				(width 0.3048)
				(type default)
			)
			(fill no)
			(layer "F.SilkS")
		)
		(fp_circle
			(center 0 0)
			(end 0 -0.9906)
			(stroke
				(width 0.3048)
				(type default)
			)
			(fill no)
			(layer "F.SilkS")
		)
		(fp_circle
			(center 2.54 0)
			(end 2.54 -0.9906)
			(stroke
				(width 0.3048)
				(type default)
			)
			(fill no)
			(layer "F.SilkS")
		)
		(fp_poly
			(pts
				(xy -1.4986 10.1473) (xy -1.4986 6.4008) (xy -3.3528 6.4008) (xy -3.3528 -0.3937) (xy 3.3528 -0.3937)
				(xy 3.3528 6.4008) (xy 1.4986 6.4008) (xy 1.4986 10.1473)
			)
			(stroke
				(width 0)
				(type default)
			)
			(fill no)
			(layer "F.CrtYd")
		)
		(fp_poly
			(pts
				(xy -2.0066 10.668) (xy 2.0066 10.668) (xy 2.0066 6.9088) (xy 3.8608 6.9088) (xy 3.8608 2.2098)
				(xy 3.3528 2.2098) (xy 3.3528 6.4008) (xy 1.4986 6.4008) (xy 1.4986 10.1473) (xy -1.4986 10.1473)
				(xy -1.4986 6.4008) (xy -3.3528 6.4008) (xy -3.3528 -0.3937) (xy 3.3528 -0.3937) (xy 3.3528 2.1971)
				(xy 3.8608 2.1971) (xy 3.8608 -1.143) (xy -3.8608 -1.143) (xy -3.8608 6.9088) (xy -2.0066 6.9088)
			)
			(stroke
				(width 0)
				(type default)
			)
			(fill no)
			(layer "F.CrtYd")
		)
		(fp_poly
			(pts
				(xy -2.0066 10.668) (xy -2.0066 6.9088) (xy -3.8608 6.9088) (xy -3.8608 -1.143) (xy 3.8608 -1.143)
				(xy 3.8608 6.9088) (xy 2.0066 6.9088) (xy 2.0066 10.668)
			)
			(stroke
				(width 0)
				(type default)
			)
			(fill no)
			(layer "F.Fab")
		)
		(pad "1" thru_hole circle
			(at 2.54 0 270)
			(size 1.27 1.27)
			(drill 0.889)
			(layers "*.Cu" "*.Mask")
			(remove_unused_layers no)
			(net "LED_DR_LED4_BLUE")
			(clearance 0.1651)
			(thermal_gap 0.1651)
		)
		(pad "2" thru_hole circle
			(at 0 0 270)
			(size 1.27 1.27)
			(drill 0.889)
			(layers "*.Cu" "*.Mask")
			(remove_unused_layers no)
			(net "LED_DR_LED4_K")
			(clearance 0.1651)
			(thermal_gap 0.1651)
		)
		(pad "3" thru_hole circle
			(at -2.54 0 270)
			(size 1.27 1.27)
			(drill 0.889)
			(layers "*.Cu" "*.Mask")
			(remove_unused_layers no)
			(net "LED_DR_LED4")
			(clearance 0.1651)
			(thermal_gap 0.1651)
		)
	)
	(footprint ""
		(layer "F.Cu")
		(at 20.7518 -173.2788 -90)
		(property "Reference" "R183"
			(at 0 0 270)
			(layer "F.SilkS")
			(hide yes)
			(effects
				(font
					(size 1.27 1.27)
				)
			)
		)
		(property "Value" "0R2J-2-GP"
			(at 0.064008 -3.993896 270)
			(unlocked yes)
			(layer "F.Fab")
			(hide yes)
			(effects
				(font
					(size 1.016 1.016)
					(thickness 0.1524)
				)
			)
		)
		(property "Device Type" "R402H16"
			(at 0.064008 -5.517896 270)
			(unlocked yes)
			(layer "F.Fab")
			(hide yes)
			(effects
				(font
					(size 1.016 1.016)
					(thickness 0.1524)
				)
			)
		)
		(duplicate_pad_numbers_are_jumpers no)
		(fp_line
			(start -0.508 -0.9398)
			(end -0.508 0.9398)
			(stroke
				(width 0.1524)
				(type default)
			)
			(layer "F.SilkS")
		)
		(fp_line
			(start 0.508 -0.9398)
			(end -0.508 -0.9398)
			(stroke
				(width 0.1524)
				(type default)
			)
			(layer "F.SilkS")
		)
		(fp_rect
			(start -0.508 0.9398)
			(end 0.508 -0.9398)
			(stroke
				(width 0)
				(type default)
			)
			(fill no)
			(layer "F.CrtYd")
		)
		(fp_rect
			(start -0.508 0.9398)
			(end 0.508 -0.9398)
			(stroke
				(width 0)
				(type default)
			)
			(fill no)
			(layer "F.Fab")
		)
		(pad "1" smd custom
			(at 0 -0.4445 270)
			(size 0.1397 0.1397)
			(layers "F.Cu" "F.Mask" "F.Paste")
			(net "THERMHOT#")
			(options
				(clearance outline)
				(anchor circle)
			)
			(primitives
				(gr_poly
					(pts
						(arc
							(start -0.1778 -0.2794)
							(mid -0.249642 -0.249642)
							(end -0.2794 -0.1778)
						)
						(arc
							(start -0.2794 0.1778)
							(mid -0.249642 0.249642)
							(end -0.1778 0.2794)
						)
						(arc
							(start 0.1778 0.2794)
							(mid 0.249642 0.249642)
							(end 0.2794 0.1778)
						)
						(arc
							(start 0.2794 -0.1778)
							(mid 0.249642 -0.249642)
							(end 0.1778 -0.2794)
						)
					)
					(width 0)
					(fill yes)
				)
			)
		)
		(pad "2" smd custom
			(at 0 0.4445 270)
			(size 0.1397 0.1397)
			(layers "F.Cu" "F.Mask" "F.Paste")
			(net "THERMHOT#_R")
			(options
				(clearance outline)
				(anchor circle)
			)
			(primitives
				(gr_poly
					(pts
						(arc
							(start -0.1778 -0.2794)
							(mid -0.249642 -0.249642)
							(end -0.2794 -0.1778)
						)
						(arc
							(start -0.2794 0.1778)
							(mid -0.249642 0.249642)
							(end -0.1778 0.2794)
						)
						(arc
							(start 0.1778 0.2794)
							(mid 0.249642 0.249642)
							(end 0.2794 0.1778)
						)
						(arc
							(start 0.2794 -0.1778)
							(mid 0.249642 -0.249642)
							(end 0.1778 -0.2794)
						)
					)
					(width 0)
					(fill yes)
				)
			)
		)
	)
	(footprint ""
		(layer "F.Cu")
		(at 43.18 -400.177)
		(property "Reference" "PQ3"
			(at 0 0 0)
			(layer "F.SilkS")
			(hide yes)
			(effects
				(font
					(size 1.27 1.27)
				)
			)
		)
		(property "Value" "PH0925CL-GP"
			(at -4.2799 -0.4572 0)
			(unlocked yes)
			(layer "F.Fab")
			(hide yes)
			(effects
				(font
					(size 1.016 1.016)
					(thickness 0.1524)
				)
			)
		)
		(property "Device Type" "LFPAK-5PH48-U"
			(at -4.2799 -1.9812 0)
			(unlocked yes)
			(layer "F.Fab")
			(hide yes)
			(effects
				(font
					(size 1.016 1.016)
					(thickness 0.1524)
				)
			)
		)
		(duplicate_pad_numbers_are_jumpers no)
		(fp_line
			(start -2.7559 -6.5532)
			(end -2.7559 1.0668)
			(stroke
				(width 0.1524)
				(type default)
			)
			(layer "F.SilkS")
		)
		(fp_line
			(start -2.7559 1.0668)
			(end 2.7559 1.0668)
			(stroke
				(width 0.1524)
				(type default)
			)
			(layer "F.SilkS")
		)
		(fp_line
			(start -1.7272 1.1684)
			(end -2.1082 1.1684)
			(stroke
				(width 0.3302)
				(type default)
			)
			(layer "F.SilkS")
		)
		(fp_line
			(start 2.7559 -6.5532)
			(end -2.7559 -6.5532)
			(stroke
				(width 0.1524)
				(type default)
			)
			(layer "F.SilkS")
		)
		(fp_line
			(start 2.7559 1.0668)
			(end 2.7559 -6.5532)
			(stroke
				(width 0.1524)
				(type default)
			)
			(layer "F.SilkS")
		)
		(fp_poly
			(pts
				(xy -2.3368 1.5748) (xy -1.905 1.143) (xy -1.4732 1.5748)
			)
			(stroke
				(width 0)
				(type default)
			)
			(fill yes)
			(layer "F.SilkS")
		)
		(fp_poly
			(pts
				(xy -2.5019 -4.02971) (xy -0.3302 -4.02971) (xy -0.3302 -6.30301) (xy -2.5019 -6.30301)
			)
			(stroke
				(width 0)
				(type default)
			)
			(fill yes)
			(layer "F.Paste")
		)
		(fp_poly
			(pts
				(xy -2.5019 -1.09601) (xy -0.3302 -1.09601) (xy -0.3302 -3.36931) (xy -2.5019 -3.36931)
			)
			(stroke
				(width 0)
				(type default)
			)
			(fill yes)
			(layer "F.Paste")
		)
		(fp_poly
			(pts
				(xy 0.3302 -4.02971) (xy 2.5019 -4.02971) (xy 2.5019 -6.30301) (xy 0.3302 -6.30301)
			)
			(stroke
				(width 0)
				(type default)
			)
			(fill yes)
			(layer "F.Paste")
		)
		(fp_poly
			(pts
				(xy 0.3302 -1.09601) (xy 2.5019 -1.09601) (xy 2.5019 -3.36931) (xy 0.3302 -3.36931)
			)
			(stroke
				(width 0)
				(type default)
			)
			(fill yes)
			(layer "F.Paste")
		)
		(fp_rect
			(start -2.4511 0.3048)
			(end 2.4511 -5.6896)
			(stroke
				(width 0)
				(type default)
			)
			(fill no)
			(layer "F.CrtYd")
		)
		(fp_poly
			(pts
				(xy -3.0099 1.3208) (xy -3.0099 -6.8072) (xy 3.0099 -6.8072) (xy 3.0099 -1.016) (xy 2.4511 -1.016)
				(xy 2.4511 -5.6896) (xy -2.4511 -5.6896) (xy -2.4511 0.3048) (xy 2.4511 0.3048) (xy 2.4511 -1.0033)
				(xy 3.0099 -1.0033) (xy 3.0099 1.3208)
			)
			(stroke
				(width 0)
				(type default)
			)
			(fill no)
			(layer "F.CrtYd")
		)
		(fp_rect
			(start -3.0099 1.3208)
			(end 3.0099 -6.8072)
			(stroke
				(width 0)
				(type default)
			)
			(fill no)
			(layer "F.Fab")
		)
		(pad "1" smd rect
			(at -1.905 0)
			(size 0.762 1.6256)
			(layers "F.Cu" "F.Mask" "F.Paste")
			(net "P12V")
		)
		(pad "2" smd rect
			(at -0.635 0)
			(size 0.762 1.6256)
			(layers "F.Cu" "F.Mask" "F.Paste")
			(net "P12V")
		)
		(pad "3" smd rect
			(at 0.635 0)
			(size 0.762 1.6256)
			(layers "F.Cu" "F.Mask" "F.Paste")
			(net "P12V")
		)
		(pad "4" smd rect
			(at 1.905 0)
			(size 0.762 1.6256)
			(layers "F.Cu" "F.Mask" "F.Paste")
			(net "ADM1276_GATE_DRV3")
		)
		(pad "5" smd rect
			(at 0 -3.69951)
			(size 5.0038 5.207)
			(layers "F.Cu" "F.Mask" "F.Paste")
			(net "P12V_SENSE_TRACE")
		)
	)
	(footprint ""
		(layer "F.Cu")
		(at 31.3182 -253.8984 180)
		(property "Reference" "R47"
			(at 0 0 180)
			(layer "F.SilkS")
			(hide yes)
			(effects
				(font
					(size 1.27 1.27)
				)
			)
		)
		(property "Value" "0R2J-2-GP"
			(at 0.064008 -3.993896 180)
			(unlocked yes)
			(layer "F.Fab")
			(hide yes)
			(effects
				(font
					(size 1.016 1.016)
					(thickness 0.1524)
				)
			)
		)
		(property "Device Type" "R402H16"
			(at 0.064008 -5.517896 180)
			(unlocked yes)
			(layer "F.Fab")
			(hide yes)
			(effects
				(font
					(size 1.016 1.016)
					(thickness 0.1524)
				)
			)
		)
		(duplicate_pad_numbers_are_jumpers no)
		(fp_line
			(start 0.508 -0.9398)
			(end -0.508 -0.9398)
			(stroke
				(width 0.1524)
				(type default)
			)
			(layer "F.SilkS")
		)
		(fp_line
			(start -0.508 -0.9398)
			(end -0.508 0.9398)
			(stroke
				(width 0.1524)
				(type default)
			)
			(layer "F.SilkS")
		)
		(fp_rect
			(start -0.508 0.9398)
			(end 0.508 -0.9398)
			(stroke
				(width 0)
				(type default)
			)
			(fill no)
			(layer "F.CrtYd")
		)
		(fp_rect
			(start -0.508 0.9398)
			(end 0.508 -0.9398)
			(stroke
				(width 0)
				(type default)
			)
			(fill no)
			(layer "F.Fab")
		)
		(pad "1" smd custom
			(at 0 -0.4445 180)
			(size 0.1397 0.1397)
			(layers "F.Cu" "F.Mask" "F.Paste")
			(net "I2C_C_SDA_EEPROM")
			(options
				(clearance outline)
				(anchor circle)
			)
			(primitives
				(gr_poly
					(pts
						(arc
							(start -0.1778 -0.2794)
							(mid -0.249642 -0.249642)
							(end -0.2794 -0.1778)
						)
						(arc
							(start -0.2794 0.1778)
							(mid -0.249642 0.249642)
							(end -0.1778 0.2794)
						)
						(arc
							(start 0.1778 0.2794)
							(mid 0.249642 0.249642)
							(end 0.2794 0.1778)
						)
						(arc
							(start 0.2794 -0.1778)
							(mid 0.249642 -0.249642)
							(end 0.1778 -0.2794)
						)
					)
					(width 0)
					(fill yes)
				)
			)
		)
		(pad "2" smd custom
			(at 0 0.4445 180)
			(size 0.1397 0.1397)
			(layers "F.Cu" "F.Mask" "F.Paste")
			(net "I2C_C_SDA")
			(options
				(clearance outline)
				(anchor circle)
			)
			(primitives
				(gr_poly
					(pts
						(arc
							(start -0.1778 -0.2794)
							(mid -0.249642 -0.249642)
							(end -0.2794 -0.1778)
						)
						(arc
							(start -0.2794 0.1778)
							(mid -0.249642 0.249642)
							(end -0.1778 0.2794)
						)
						(arc
							(start 0.1778 0.2794)
							(mid 0.249642 0.249642)
							(end 0.2794 0.1778)
						)
						(arc
							(start 0.2794 -0.1778)
							(mid 0.249642 -0.249642)
							(end 0.1778 -0.2794)
						)
					)
					(width 0)
					(fill yes)
				)
			)
		)
	)
	(footprint ""
		(layer "F.Cu")
		(at 21.766784 -216.6366 90)
		(property "Reference" "R132"
			(at 0 0 90)
			(layer "F.SilkS")
			(hide yes)
			(effects
				(font
					(size 1.27 1.27)
				)
			)
		)
		(property "Value" "4K7R2F-GP"
			(at 0.064008 -3.993896 90)
			(unlocked yes)
			(layer "F.Fab")
			(hide yes)
			(effects
				(font
					(size 1.016 1.016)
					(thickness 0.1524)
				)
			)
		)
		(property "Device Type" "R402H16"
			(at 0.064008 -5.517896 90)
			(unlocked yes)
			(layer "F.Fab")
			(hide yes)
			(effects
				(font
					(size 1.016 1.016)
					(thickness 0.1524)
				)
			)
		)
		(duplicate_pad_numbers_are_jumpers no)
		(fp_line
			(start 0.508 -0.9398)
			(end -0.508 -0.9398)
			(stroke
				(width 0.1524)
				(type default)
			)
			(layer "F.SilkS")
		)
		(fp_line
			(start -0.508 -0.9398)
			(end -0.508 0.9398)
			(stroke
				(width 0.1524)
				(type default)
			)
			(layer "F.SilkS")
		)
		(fp_rect
			(start -0.508 0.9398)
			(end 0.508 -0.9398)
			(stroke
				(width 0)
				(type default)
			)
			(fill no)
			(layer "F.CrtYd")
		)
		(fp_rect
			(start -0.508 0.9398)
			(end 0.508 -0.9398)
			(stroke
				(width 0)
				(type default)
			)
			(fill no)
			(layer "F.Fab")
		)
		(pad "1" smd custom
			(at 0 -0.4445 90)
			(size 0.1397 0.1397)
			(layers "F.Cu" "F.Mask" "F.Paste")
			(net "P3V3")
			(options
				(clearance outline)
				(anchor circle)
			)
			(primitives
				(gr_poly
					(pts
						(arc
							(start -0.1778 -0.2794)
							(mid -0.249642 -0.249642)
							(end -0.2794 -0.1778)
						)
						(arc
							(start -0.2794 0.1778)
							(mid -0.249642 0.249642)
							(end -0.1778 0.2794)
						)
						(arc
							(start 0.1778 0.2794)
							(mid 0.249642 0.249642)
							(end 0.2794 0.1778)
						)
						(arc
							(start 0.2794 -0.1778)
							(mid 0.249642 -0.249642)
							(end 0.1778 -0.2794)
						)
					)
					(width 0)
					(fill yes)
				)
			)
		)
		(pad "2" smd custom
			(at 0 0.4445 90)
			(size 0.1397 0.1397)
			(layers "F.Cu" "F.Mask" "F.Paste")
			(net "PWM_OUT_FAN4")
			(options
				(clearance outline)
				(anchor circle)
			)
			(primitives
				(gr_poly
					(pts
						(arc
							(start -0.1778 -0.2794)
							(mid -0.249642 -0.249642)
							(end -0.2794 -0.1778)
						)
						(arc
							(start -0.2794 0.1778)
							(mid -0.249642 0.249642)
							(end -0.1778 0.2794)
						)
						(arc
							(start 0.1778 0.2794)
							(mid 0.249642 0.249642)
							(end 0.2794 0.1778)
						)
						(arc
							(start 0.2794 -0.1778)
							(mid 0.249642 -0.249642)
							(end 0.1778 -0.2794)
						)
					)
					(width 0)
					(fill yes)
				)
			)
		)
	)
	(footprint ""
		(layer "F.Cu")
		(at 37.465 -366.014 180)
		(property "Reference" "PQ4"
			(at 0 0 180)
			(layer "F.SilkS")
			(hide yes)
			(effects
				(font
					(size 1.27 1.27)
				)
			)
		)
		(property "Value" "MMBT3906-3-GP"
			(at 0.10287 -10.29843 180)
			(unlocked yes)
			(layer "F.Fab")
			(hide yes)
			(effects
				(font
					(size 1.016 1.016)
					(thickness 0.1524)
				)
			)
		)
		(property "Device Type" "SOT23CBE2D4H44"
			(at 0.10287 -12.20343 180)
			(unlocked yes)
			(layer "F.Fab")
			(hide yes)
			(effects
				(font
					(size 1.016 1.016)
					(thickness 0.1524)
				)
			)
		)
		(duplicate_pad_numbers_are_jumpers no)
		(fp_line
			(start 1.651 1.778)
			(end 1.651 -1.778)
			(stroke
				(width 0.1524)
				(type default)
			)
			(layer "F.SilkS")
		)
		(fp_line
			(start 1.651 -1.778)
			(end -1.651 -1.778)
			(stroke
				(width 0.1524)
				(type default)
			)
			(layer "F.SilkS")
		)
		(fp_line
			(start -1.651 1.778)
			(end 1.651 1.778)
			(stroke
				(width 0.1524)
				(type default)
			)
			(layer "F.SilkS")
		)
		(fp_line
			(start -1.651 -1.778)
			(end -1.651 1.778)
			(stroke
				(width 0.1524)
				(type default)
			)
			(layer "F.SilkS")
		)
		(fp_poly
			(pts
				(xy -1.778 1.8796) (xy -1.778 -1.8796) (xy 1.778 -1.8796) (xy 1.778 1.8796)
			)
			(stroke
				(width 0)
				(type default)
			)
			(fill no)
			(layer "F.CrtYd")
		)
		(fp_poly
			(pts
				(xy -1.778 1.8796) (xy -1.778 -1.8796) (xy 1.778 -1.8796) (xy 1.778 1.8796)
			)
			(stroke
				(width 0)
				(type default)
			)
			(fill no)
			(layer "F.Fab")
		)
		(pad "B" smd custom
			(at -0.98425 0.9525 180)
			(size 0.1905 0.1905)
			(layers "F.Cu" "F.Mask" "F.Paste")
			(net "ADM1276_LATCH_B")
			(options
				(clearance outline)
				(anchor circle)
			)
			(primitives
				(gr_poly
					(pts
						(arc
							(start -0.1778 0.5715)
							(mid -0.321484 0.511984)
							(end -0.381 0.3683)
						)
						(arc
							(start -0.381 -0.3683)
							(mid -0.321484 -0.511984)
							(end -0.1778 -0.5715)
						)
						(arc
							(start 0.1778 -0.5715)
							(mid 0.321484 -0.511984)
							(end 0.381 -0.3683)
						)
						(arc
							(start 0.381 0.3683)
							(mid 0.321484 0.511984)
							(end 0.1778 0.5715)
						)
					)
					(width 0)
					(fill yes)
				)
			)
		)
		(pad "C" smd custom
			(at 0 -0.9525 180)
			(size 0.1905 0.1905)
			(layers "F.Cu" "F.Mask" "F.Paste")
			(net "TEMP_ALM#_REVERSE_R")
			(options
				(clearance outline)
				(anchor circle)
			)
			(primitives
				(gr_poly
					(pts
						(arc
							(start -0.1778 0.5715)
							(mid -0.321484 0.511984)
							(end -0.381 0.3683)
						)
						(arc
							(start -0.381 -0.3683)
							(mid -0.321484 -0.511984)
							(end -0.1778 -0.5715)
						)
						(arc
							(start 0.1778 -0.5715)
							(mid 0.321484 -0.511984)
							(end 0.381 -0.3683)
						)
						(arc
							(start 0.381 0.3683)
							(mid 0.321484 0.511984)
							(end 0.1778 0.5715)
						)
					)
					(width 0)
					(fill yes)
				)
			)
		)
		(pad "E" smd custom
			(at 0.98425 0.9525 180)
			(size 0.1905 0.1905)
			(layers "F.Cu" "F.Mask" "F.Paste")
			(net "ADM1276_EN_NET")
			(options
				(clearance outline)
				(anchor circle)
			)
			(primitives
				(gr_poly
					(pts
						(arc
							(start -0.1778 0.5715)
							(mid -0.321484 0.511984)
							(end -0.381 0.3683)
						)
						(arc
							(start -0.381 -0.3683)
							(mid -0.321484 -0.511984)
							(end -0.1778 -0.5715)
						)
						(arc
							(start 0.1778 -0.5715)
							(mid 0.321484 -0.511984)
							(end 0.381 -0.3683)
						)
						(arc
							(start 0.381 0.3683)
							(mid 0.321484 0.511984)
							(end 0.1778 0.5715)
						)
					)
					(width 0)
					(fill yes)
				)
			)
		)
	)
	(footprint ""
		(layer "F.Cu")
		(at 13.5636 -64.2112 -90)
		(property "Reference" "C56"
			(at 0 0 270)
			(layer "F.SilkS")
			(hide yes)
			(effects
				(font
					(size 1.27 1.27)
				)
			)
		)
		(property "Value" "SC220P50V3JN-GP"
			(at 0 -2.8194 270)
			(unlocked yes)
			(layer "F.Fab")
			(hide yes)
			(effects
				(font
					(size 1.016 1.016)
					(thickness 0.1524)
				)
			)
		)
		(property "Device Type" "C603H36"
			(at 0 -4.3434 270)
			(unlocked yes)
			(layer "F.Fab")
			(hide yes)
			(effects
				(font
					(size 1.016 1.016)
					(thickness 0.1524)
				)
			)
		)
		(duplicate_pad_numbers_are_jumpers no)
		(fp_line
			(start 0.508 0)
			(end -0.508 0)
			(stroke
				(width 0.2032)
				(type default)
			)
			(layer "F.SilkS")
		)
		(fp_rect
			(start -0.5842 1.3335)
			(end 0.5842 -1.3335)
			(stroke
				(width 0)
				(type default)
			)
			(fill no)
			(layer "F.CrtYd")
		)
		(fp_rect
			(start -0.5842 1.3335)
			(end 0.5842 -1.3335)
			(stroke
				(width 0)
				(type default)
			)
			(fill no)
			(layer "F.Fab")
		)
		(pad "1" smd custom
			(at 0 -0.762 270)
			(size 0.2159 0.2159)
			(layers "F.Cu" "F.Mask" "F.Paste")
			(net "I2C_C_SCL_CONN_R")
			(options
				(clearance outline)
				(anchor circle)
			)
			(primitives
				(gr_poly
					(pts
						(arc
							(start -0.3302 -0.4318)
							(mid -0.402042 -0.402042)
							(end -0.4318 -0.3302)
						)
						(arc
							(start -0.4318 0.3302)
							(mid -0.402042 0.402042)
							(end -0.3302 0.4318)
						)
						(arc
							(start 0.3302 0.4318)
							(mid 0.402042 0.402042)
							(end 0.4318 0.3302)
						)
						(arc
							(start 0.4318 -0.3302)
							(mid 0.402042 -0.402042)
							(end 0.3302 -0.4318)
						)
					)
					(width 0)
					(fill yes)
				)
			)
		)
		(pad "2" smd custom
			(at 0 0.762 270)
			(size 0.2159 0.2159)
			(layers "F.Cu" "F.Mask" "F.Paste")
			(net "GND")
			(options
				(clearance outline)
				(anchor circle)
			)
			(primitives
				(gr_poly
					(pts
						(arc
							(start -0.3302 -0.4318)
							(mid -0.402042 -0.402042)
							(end -0.4318 -0.3302)
						)
						(arc
							(start -0.4318 0.3302)
							(mid -0.402042 0.402042)
							(end -0.3302 0.4318)
						)
						(arc
							(start 0.3302 0.4318)
							(mid 0.402042 0.402042)
							(end 0.4318 0.3302)
						)
						(arc
							(start 0.4318 -0.3302)
							(mid 0.402042 -0.402042)
							(end 0.3302 -0.4318)
						)
					)
					(width 0)
					(fill yes)
				)
			)
		)
	)
	(footprint ""
		(layer "F.Cu")
		(at 18.7706 -139.7254 90)
		(property "Reference" "TP23"
			(at 0 0 90)
			(layer "F.SilkS")
			(hide yes)
			(effects
				(font
					(size 1.27 1.27)
				)
			)
		)
		(property "Value" "TPAD32-GP"
			(at 0 -3.166364 90)
			(unlocked yes)
			(layer "F.Fab")
			(hide yes)
			(effects
				(font
					(size 1.016 1.016)
					(thickness 0.1524)
				)
			)
		)
		(property "Device Type" "TPAD32"
			(at 0 -4.690618 90)
			(unlocked yes)
			(layer "F.Fab")
			(hide yes)
			(effects
				(font
					(size 1.016 1.016)
					(thickness 0.1524)
				)
			)
		)
		(duplicate_pad_numbers_are_jumpers no)
		(fp_poly
			(pts
				(arc
					(start 0.7112 0)
					(mid -0.7112 0)
					(end 0.7112 0)
				)
			)
			(stroke
				(width 0)
				(type default)
			)
			(fill no)
			(layer "F.CrtYd")
		)
		(fp_poly
			(pts
				(arc
					(start 0.7112 0)
					(mid -0.7112 0)
					(end 0.7112 0)
				)
			)
			(stroke
				(width 0)
				(type default)
			)
			(fill no)
			(layer "F.Fab")
		)
		(pad "1" smd circle
			(at 0 0 90)
			(size 0.8128 0.8128)
			(layers "F.Cu" "F.Mask" "F.Paste")
			(net "P12VU_2490_PG")
		)
	)
	(footprint ""
		(layer "F.Cu")
		(at 24.2824 -361.188 180)
		(property "Reference" "PR11"
			(at 0 0 180)
			(layer "F.SilkS")
			(hide yes)
			(effects
				(font
					(size 1.27 1.27)
				)
			)
		)
		(property "Value" "150KR2F-L-GP"
			(at 0.064008 -3.993896 180)
			(unlocked yes)
			(layer "F.Fab")
			(hide yes)
			(effects
				(font
					(size 1.016 1.016)
					(thickness 0.1524)
				)
			)
		)
		(property "Device Type" "R402H16"
			(at 0.064008 -5.517896 180)
			(unlocked yes)
			(layer "F.Fab")
			(hide yes)
			(effects
				(font
					(size 1.016 1.016)
					(thickness 0.1524)
				)
			)
		)
		(duplicate_pad_numbers_are_jumpers no)
		(fp_line
			(start 0.508 -0.9398)
			(end -0.508 -0.9398)
			(stroke
				(width 0.1524)
				(type default)
			)
			(layer "F.SilkS")
		)
		(fp_line
			(start -0.508 -0.9398)
			(end -0.508 0.9398)
			(stroke
				(width 0.1524)
				(type default)
			)
			(layer "F.SilkS")
		)
		(fp_rect
			(start -0.508 0.9398)
			(end 0.508 -0.9398)
			(stroke
				(width 0)
				(type default)
			)
			(fill no)
			(layer "F.CrtYd")
		)
		(fp_rect
			(start -0.508 0.9398)
			(end 0.508 -0.9398)
			(stroke
				(width 0)
				(type default)
			)
			(fill no)
			(layer "F.Fab")
		)
		(pad "1" smd custom
			(at 0 -0.4445 180)
			(size 0.1397 0.1397)
			(layers "F.Cu" "F.Mask" "F.Paste")
			(net "ADM1276_ADR")
			(options
				(clearance outline)
				(anchor circle)
			)
			(primitives
				(gr_poly
					(pts
						(arc
							(start -0.1778 -0.2794)
							(mid -0.249642 -0.249642)
							(end -0.2794 -0.1778)
						)
						(arc
							(start -0.2794 0.1778)
							(mid -0.249642 0.249642)
							(end -0.1778 0.2794)
						)
						(arc
							(start 0.1778 0.2794)
							(mid 0.249642 0.249642)
							(end 0.2794 0.1778)
						)
						(arc
							(start 0.2794 -0.1778)
							(mid 0.249642 -0.249642)
							(end 0.1778 -0.2794)
						)
					)
					(width 0)
					(fill yes)
				)
			)
		)
		(pad "2" smd custom
			(at 0 0.4445 180)
			(size 0.1397 0.1397)
			(layers "F.Cu" "F.Mask" "F.Paste")
			(net "GND")
			(options
				(clearance outline)
				(anchor circle)
			)
			(primitives
				(gr_poly
					(pts
						(arc
							(start -0.1778 -0.2794)
							(mid -0.249642 -0.249642)
							(end -0.2794 -0.1778)
						)
						(arc
							(start -0.2794 0.1778)
							(mid -0.249642 0.249642)
							(end -0.1778 0.2794)
						)
						(arc
							(start 0.1778 0.2794)
							(mid 0.249642 0.249642)
							(end 0.2794 0.1778)
						)
						(arc
							(start 0.2794 -0.1778)
							(mid 0.249642 -0.249642)
							(end 0.1778 -0.2794)
						)
					)
					(width 0)
					(fill yes)
				)
			)
		)
	)
	(footprint ""
		(layer "F.Cu")
		(at 20.585938 -15.595092 -90)
		(property "Reference" "R73"
			(at 0 0 270)
			(layer "F.SilkS")
			(hide yes)
			(effects
				(font
					(size 1.27 1.27)
				)
			)
		)
		(property "Value" "27KR3F-GP"
			(at -0.0254 -2.5146 270)
			(unlocked yes)
			(layer "F.Fab")
			(hide yes)
			(effects
				(font
					(size 1.016 1.016)
					(thickness 0.1524)
				)
			)
		)
		(property "Device Type" "R603H22"
			(at -0.0254 -4.0386 270)
			(unlocked yes)
			(layer "F.Fab")
			(hide yes)
			(effects
				(font
					(size 1.016 1.016)
					(thickness 0.1524)
				)
			)
		)
		(duplicate_pad_numbers_are_jumpers no)
		(fp_line
			(start -0.4826 0)
			(end -0.2032 0)
			(stroke
				(width 0.2032)
				(type default)
			)
			(layer "F.SilkS")
		)
		(fp_line
			(start 0.2032 0)
			(end 0.4826 0)
			(stroke
				(width 0.2032)
				(type default)
			)
			(layer "F.SilkS")
		)
		(fp_rect
			(start -0.5842 1.3335)
			(end 0.5842 -1.3335)
			(stroke
				(width 0)
				(type default)
			)
			(fill no)
			(layer "F.CrtYd")
		)
		(fp_rect
			(start -0.5842 1.3335)
			(end 0.5842 -1.3335)
			(stroke
				(width 0)
				(type default)
			)
			(fill no)
			(layer "F.Fab")
		)
		(pad "1" smd custom
			(at 0 -0.762 270)
			(size 0.2159 0.2159)
			(layers "F.Cu" "F.Mask" "F.Paste")
			(net "FANIN_11")
			(options
				(clearance outline)
				(anchor circle)
			)
			(primitives
				(gr_poly
					(pts
						(arc
							(start -0.3302 -0.4318)
							(mid -0.402042 -0.402042)
							(end -0.4318 -0.3302)
						)
						(arc
							(start -0.4318 0.3302)
							(mid -0.402042 0.402042)
							(end -0.3302 0.4318)
						)
						(arc
							(start 0.3302 0.4318)
							(mid 0.402042 0.402042)
							(end 0.4318 0.3302)
						)
						(arc
							(start 0.4318 -0.3302)
							(mid 0.402042 -0.402042)
							(end 0.3302 -0.4318)
						)
					)
					(width 0)
					(fill yes)
				)
			)
		)
		(pad "2" smd custom
			(at 0 0.762 270)
			(size 0.2159 0.2159)
			(layers "F.Cu" "F.Mask" "F.Paste")
			(net "FAN_TACH11")
			(options
				(clearance outline)
				(anchor circle)
			)
			(primitives
				(gr_poly
					(pts
						(arc
							(start -0.3302 -0.4318)
							(mid -0.402042 -0.402042)
							(end -0.4318 -0.3302)
						)
						(arc
							(start -0.4318 0.3302)
							(mid -0.402042 0.402042)
							(end -0.3302 0.4318)
						)
						(arc
							(start 0.3302 0.4318)
							(mid 0.402042 0.402042)
							(end 0.4318 0.3302)
						)
						(arc
							(start 0.4318 -0.3302)
							(mid 0.402042 -0.402042)
							(end 0.3302 -0.4318)
						)
					)
					(width 0)
					(fill yes)
				)
			)
		)
	)
	(footprint ""
		(layer "F.Cu")
		(at 8.3058 -64.8208)
		(property "Reference" "R25"
			(at 0 0 0)
			(layer "F.SilkS")
			(hide yes)
			(effects
				(font
					(size 1.27 1.27)
				)
			)
		)
		(property "Value" "33R2F-3-GP"
			(at 0.064008 -3.993896 0)
			(unlocked yes)
			(layer "F.Fab")
			(hide yes)
			(effects
				(font
					(size 1.016 1.016)
					(thickness 0.1524)
				)
			)
		)
		(property "Device Type" "R402H16"
			(at 0.064008 -5.517896 0)
			(unlocked yes)
			(layer "F.Fab")
			(hide yes)
			(effects
				(font
					(size 1.016 1.016)
					(thickness 0.1524)
				)
			)
		)
		(duplicate_pad_numbers_are_jumpers no)
		(fp_line
			(start -0.508 -0.9398)
			(end -0.508 0.9398)
			(stroke
				(width 0.1524)
				(type default)
			)
			(layer "F.SilkS")
		)
		(fp_line
			(start 0.508 -0.9398)
			(end -0.508 -0.9398)
			(stroke
				(width 0.1524)
				(type default)
			)
			(layer "F.SilkS")
		)
		(fp_rect
			(start -0.508 0.9398)
			(end 0.508 -0.9398)
			(stroke
				(width 0)
				(type default)
			)
			(fill no)
			(layer "F.CrtYd")
		)
		(fp_rect
			(start -0.508 0.9398)
			(end 0.508 -0.9398)
			(stroke
				(width 0)
				(type default)
			)
			(fill no)
			(layer "F.Fab")
		)
		(pad "1" smd custom
			(at 0 -0.4445)
			(size 0.1397 0.1397)
			(layers "F.Cu" "F.Mask" "F.Paste")
			(net "P3V3")
			(options
				(clearance outline)
				(anchor circle)
			)
			(primitives
				(gr_poly
					(pts
						(arc
							(start -0.1778 -0.2794)
							(mid -0.249642 -0.249642)
							(end -0.2794 -0.1778)
						)
						(arc
							(start -0.2794 0.1778)
							(mid -0.249642 0.249642)
							(end -0.1778 0.2794)
						)
						(arc
							(start 0.1778 0.2794)
							(mid 0.249642 0.249642)
							(end 0.2794 0.1778)
						)
						(arc
							(start 0.2794 -0.1778)
							(mid 0.249642 -0.249642)
							(end 0.1778 -0.2794)
						)
					)
					(width 0)
					(fill yes)
				)
			)
		)
		(pad "2" smd custom
			(at 0 0.4445)
			(size 0.1397 0.1397)
			(layers "F.Cu" "F.Mask" "F.Paste")
			(net "LED_DR_LED5_BLUE")
			(options
				(clearance outline)
				(anchor circle)
			)
			(primitives
				(gr_poly
					(pts
						(arc
							(start -0.1778 -0.2794)
							(mid -0.249642 -0.249642)
							(end -0.2794 -0.1778)
						)
						(arc
							(start -0.2794 0.1778)
							(mid -0.249642 0.249642)
							(end -0.1778 0.2794)
						)
						(arc
							(start 0.1778 0.2794)
							(mid 0.249642 0.249642)
							(end 0.2794 0.1778)
						)
						(arc
							(start 0.2794 -0.1778)
							(mid 0.249642 -0.249642)
							(end 0.1778 -0.2794)
						)
					)
					(width 0)
					(fill yes)
				)
			)
		)
	)
	(footprint ""
		(layer "F.Cu")
		(at 8.733028 -67.111118 -90)
		(property "Reference" "R111"
			(at 0 0 270)
			(layer "F.SilkS")
			(hide yes)
			(effects
				(font
					(size 1.27 1.27)
				)
			)
		)
		(property "Value" "2KR2F-3-GP"
			(at 0.064008 -3.993896 270)
			(unlocked yes)
			(layer "F.Fab")
			(hide yes)
			(effects
				(font
					(size 1.016 1.016)
					(thickness 0.1524)
				)
			)
		)
		(property "Device Type" "R402H16"
			(at 0.064008 -5.517896 270)
			(unlocked yes)
			(layer "F.Fab")
			(hide yes)
			(effects
				(font
					(size 1.016 1.016)
					(thickness 0.1524)
				)
			)
		)
		(duplicate_pad_numbers_are_jumpers no)
		(fp_line
			(start -0.508 -0.9398)
			(end -0.508 0.9398)
			(stroke
				(width 0.1524)
				(type default)
			)
			(layer "F.SilkS")
		)
		(fp_line
			(start 0.508 -0.9398)
			(end -0.508 -0.9398)
			(stroke
				(width 0.1524)
				(type default)
			)
			(layer "F.SilkS")
		)
		(fp_rect
			(start -0.508 0.9398)
			(end 0.508 -0.9398)
			(stroke
				(width 0)
				(type default)
			)
			(fill no)
			(layer "F.CrtYd")
		)
		(fp_rect
			(start -0.508 0.9398)
			(end 0.508 -0.9398)
			(stroke
				(width 0)
				(type default)
			)
			(fill no)
			(layer "F.Fab")
		)
		(pad "1" smd custom
			(at 0 -0.4445 270)
			(size 0.1397 0.1397)
			(layers "F.Cu" "F.Mask" "F.Paste")
			(net "LED_DR_LED5")
			(options
				(clearance outline)
				(anchor circle)
			)
			(primitives
				(gr_poly
					(pts
						(arc
							(start -0.1778 -0.2794)
							(mid -0.249642 -0.249642)
							(end -0.2794 -0.1778)
						)
						(arc
							(start -0.2794 0.1778)
							(mid -0.249642 0.249642)
							(end -0.1778 0.2794)
						)
						(arc
							(start 0.1778 0.2794)
							(mid 0.249642 0.249642)
							(end 0.2794 0.1778)
						)
						(arc
							(start 0.2794 -0.1778)
							(mid 0.249642 -0.249642)
							(end 0.1778 -0.2794)
						)
					)
					(width 0)
					(fill yes)
				)
			)
		)
		(pad "2" smd custom
			(at 0 0.4445 270)
			(size 0.1397 0.1397)
			(layers "F.Cu" "F.Mask" "F.Paste")
			(net "LED_DR_LED5_B")
			(options
				(clearance outline)
				(anchor circle)
			)
			(primitives
				(gr_poly
					(pts
						(arc
							(start -0.1778 -0.2794)
							(mid -0.249642 -0.249642)
							(end -0.2794 -0.1778)
						)
						(arc
							(start -0.2794 0.1778)
							(mid -0.249642 0.249642)
							(end -0.1778 0.2794)
						)
						(arc
							(start 0.1778 0.2794)
							(mid 0.249642 0.249642)
							(end 0.2794 0.1778)
						)
						(arc
							(start 0.2794 -0.1778)
							(mid 0.249642 -0.249642)
							(end 0.1778 -0.2794)
						)
					)
					(width 0)
					(fill yes)
				)
			)
		)
	)
	(footprint ""
		(layer "F.Cu")
		(at 21.209 -371.729)
		(property "Reference" "PR33"
			(at 0 0 0)
			(layer "F.SilkS")
			(hide yes)
			(effects
				(font
					(size 1.27 1.27)
				)
			)
		)
		(property "Value" "51KR2F-L-GP"
			(at 0.064008 -3.993896 0)
			(unlocked yes)
			(layer "F.Fab")
			(hide yes)
			(effects
				(font
					(size 1.016 1.016)
					(thickness 0.1524)
				)
			)
		)
		(property "Device Type" "R402H16"
			(at 0.064008 -5.517896 0)
			(unlocked yes)
			(layer "F.Fab")
			(hide yes)
			(effects
				(font
					(size 1.016 1.016)
					(thickness 0.1524)
				)
			)
		)
		(duplicate_pad_numbers_are_jumpers no)
		(fp_line
			(start -0.508 -0.9398)
			(end -0.508 0.9398)
			(stroke
				(width 0.1524)
				(type default)
			)
			(layer "F.SilkS")
		)
		(fp_line
			(start 0.508 -0.9398)
			(end -0.508 -0.9398)
			(stroke
				(width 0.1524)
				(type default)
			)
			(layer "F.SilkS")
		)
		(fp_rect
			(start -0.508 0.9398)
			(end 0.508 -0.9398)
			(stroke
				(width 0)
				(type default)
			)
			(fill no)
			(layer "F.CrtYd")
		)
		(fp_rect
			(start -0.508 0.9398)
			(end 0.508 -0.9398)
			(stroke
				(width 0)
				(type default)
			)
			(fill no)
			(layer "F.Fab")
		)
		(pad "1" smd custom
			(at 0 -0.4445)
			(size 0.1397 0.1397)
			(layers "F.Cu" "F.Mask" "F.Paste")
			(net "P12V_AUX")
			(options
				(clearance outline)
				(anchor circle)
			)
			(primitives
				(gr_poly
					(pts
						(arc
							(start -0.1778 -0.2794)
							(mid -0.249642 -0.249642)
							(end -0.2794 -0.1778)
						)
						(arc
							(start -0.2794 0.1778)
							(mid -0.249642 0.249642)
							(end -0.1778 0.2794)
						)
						(arc
							(start 0.1778 0.2794)
							(mid 0.249642 0.249642)
							(end 0.2794 0.1778)
						)
						(arc
							(start 0.2794 -0.1778)
							(mid 0.249642 -0.249642)
							(end 0.1778 -0.2794)
						)
					)
					(width 0)
					(fill yes)
				)
			)
		)
		(pad "2" smd custom
			(at 0 0.4445)
			(size 0.1397 0.1397)
			(layers "F.Cu" "F.Mask" "F.Paste")
			(net "ADM1276_OV")
			(options
				(clearance outline)
				(anchor circle)
			)
			(primitives
				(gr_poly
					(pts
						(arc
							(start -0.1778 -0.2794)
							(mid -0.249642 -0.249642)
							(end -0.2794 -0.1778)
						)
						(arc
							(start -0.2794 0.1778)
							(mid -0.249642 0.249642)
							(end -0.1778 0.2794)
						)
						(arc
							(start 0.1778 0.2794)
							(mid 0.249642 0.249642)
							(end 0.2794 0.1778)
						)
						(arc
							(start 0.2794 -0.1778)
							(mid 0.249642 -0.249642)
							(end 0.1778 -0.2794)
						)
					)
					(width 0)
					(fill yes)
				)
			)
		)
	)
	(footprint ""
		(layer "F.Cu")
		(at 47.0154 -418.592 90)
		(property "Reference" "C25"
			(at 0 0 90)
			(layer "F.SilkS")
			(hide yes)
			(effects
				(font
					(size 1.27 1.27)
				)
			)
		)
		(property "Value" "SCD1U50V3KX-GP"
			(at 0 -2.8194 90)
			(unlocked yes)
			(layer "F.Fab")
			(hide yes)
			(effects
				(font
					(size 1.016 1.016)
					(thickness 0.1524)
				)
			)
		)
		(property "Device Type" "C603H36"
			(at 0 -4.3434 90)
			(unlocked yes)
			(layer "F.Fab")
			(hide yes)
			(effects
				(font
					(size 1.016 1.016)
					(thickness 0.1524)
				)
			)
		)
		(duplicate_pad_numbers_are_jumpers no)
		(fp_line
			(start 0.508 0)
			(end -0.508 0)
			(stroke
				(width 0.2032)
				(type default)
			)
			(layer "F.SilkS")
		)
		(fp_rect
			(start -0.5842 1.3335)
			(end 0.5842 -1.3335)
			(stroke
				(width 0)
				(type default)
			)
			(fill no)
			(layer "F.CrtYd")
		)
		(fp_rect
			(start -0.5842 1.3335)
			(end 0.5842 -1.3335)
			(stroke
				(width 0)
				(type default)
			)
			(fill no)
			(layer "F.Fab")
		)
		(pad "1" smd custom
			(at 0 -0.762 90)
			(size 0.2159 0.2159)
			(layers "F.Cu" "F.Mask" "F.Paste")
			(net "P12V_AUX")
			(options
				(clearance outline)
				(anchor circle)
			)
			(primitives
				(gr_poly
					(pts
						(arc
							(start -0.3302 -0.4318)
							(mid -0.402042 -0.402042)
							(end -0.4318 -0.3302)
						)
						(arc
							(start -0.4318 0.3302)
							(mid -0.402042 0.402042)
							(end -0.3302 0.4318)
						)
						(arc
							(start 0.3302 0.4318)
							(mid 0.402042 0.402042)
							(end 0.4318 0.3302)
						)
						(arc
							(start 0.4318 -0.3302)
							(mid 0.402042 -0.402042)
							(end 0.3302 -0.4318)
						)
					)
					(width 0)
					(fill yes)
				)
			)
		)
		(pad "2" smd custom
			(at 0 0.762 90)
			(size 0.2159 0.2159)
			(layers "F.Cu" "F.Mask" "F.Paste")
			(net "GND")
			(options
				(clearance outline)
				(anchor circle)
			)
			(primitives
				(gr_poly
					(pts
						(arc
							(start -0.3302 -0.4318)
							(mid -0.402042 -0.402042)
							(end -0.4318 -0.3302)
						)
						(arc
							(start -0.4318 0.3302)
							(mid -0.402042 0.402042)
							(end -0.3302 0.4318)
						)
						(arc
							(start 0.3302 0.4318)
							(mid 0.402042 0.402042)
							(end 0.4318 0.3302)
						)
						(arc
							(start 0.4318 -0.3302)
							(mid 0.402042 -0.402042)
							(end 0.3302 -0.4318)
						)
					)
					(width 0)
					(fill yes)
				)
			)
		)
	)
	(footprint ""
		(layer "F.Cu")
		(at 20.381976 -176.43729 -90)
		(property "Reference" "R24"
			(at 0 0 270)
			(layer "F.SilkS")
			(hide yes)
			(effects
				(font
					(size 1.27 1.27)
				)
			)
		)
		(property "Value" "4K7R2F-GP"
			(at 0.064008 -3.993896 270)
			(unlocked yes)
			(layer "F.Fab")
			(hide yes)
			(effects
				(font
					(size 1.016 1.016)
					(thickness 0.1524)
				)
			)
		)
		(property "Device Type" "R402H16"
			(at 0.064008 -5.517896 270)
			(unlocked yes)
			(layer "F.Fab")
			(hide yes)
			(effects
				(font
					(size 1.016 1.016)
					(thickness 0.1524)
				)
			)
		)
		(duplicate_pad_numbers_are_jumpers no)
		(fp_line
			(start -0.508 -0.9398)
			(end -0.508 0.9398)
			(stroke
				(width 0.1524)
				(type default)
			)
			(layer "F.SilkS")
		)
		(fp_line
			(start 0.508 -0.9398)
			(end -0.508 -0.9398)
			(stroke
				(width 0.1524)
				(type default)
			)
			(layer "F.SilkS")
		)
		(fp_rect
			(start -0.508 0.9398)
			(end 0.508 -0.9398)
			(stroke
				(width 0)
				(type default)
			)
			(fill no)
			(layer "F.CrtYd")
		)
		(fp_rect
			(start -0.508 0.9398)
			(end 0.508 -0.9398)
			(stroke
				(width 0)
				(type default)
			)
			(fill no)
			(layer "F.Fab")
		)
		(pad "1" smd custom
			(at 0 -0.4445 270)
			(size 0.1397 0.1397)
			(layers "F.Cu" "F.Mask" "F.Paste")
			(net "NCT7368S_SEL")
			(options
				(clearance outline)
				(anchor circle)
			)
			(primitives
				(gr_poly
					(pts
						(arc
							(start -0.1778 -0.2794)
							(mid -0.249642 -0.249642)
							(end -0.2794 -0.1778)
						)
						(arc
							(start -0.2794 0.1778)
							(mid -0.249642 0.249642)
							(end -0.1778 0.2794)
						)
						(arc
							(start 0.1778 0.2794)
							(mid 0.249642 0.249642)
							(end 0.2794 0.1778)
						)
						(arc
							(start 0.2794 -0.1778)
							(mid 0.249642 -0.249642)
							(end 0.1778 -0.2794)
						)
					)
					(width 0)
					(fill yes)
				)
			)
		)
		(pad "2" smd custom
			(at 0 0.4445 270)
			(size 0.1397 0.1397)
			(layers "F.Cu" "F.Mask" "F.Paste")
			(net "GND")
			(options
				(clearance outline)
				(anchor circle)
			)
			(primitives
				(gr_poly
					(pts
						(arc
							(start -0.1778 -0.2794)
							(mid -0.249642 -0.249642)
							(end -0.2794 -0.1778)
						)
						(arc
							(start -0.2794 0.1778)
							(mid -0.249642 0.249642)
							(end -0.1778 0.2794)
						)
						(arc
							(start 0.1778 0.2794)
							(mid 0.249642 0.249642)
							(end 0.2794 0.1778)
						)
						(arc
							(start 0.2794 -0.1778)
							(mid 0.249642 -0.249642)
							(end 0.1778 -0.2794)
						)
					)
					(width 0)
					(fill yes)
				)
			)
		)
	)
	(footprint ""
		(layer "F.Cu")
		(at 4.499864 -340.000082)
		(property "Reference" "H4"
			(at 0 0 0)
			(layer "F.SilkS")
			(hide yes)
			(effects
				(font
					(size 1.27 1.27)
				)
			)
		)
		(property "Value" "HOLE315R138"
			(at 0 -7.0612 0)
			(unlocked yes)
			(layer "F.Fab")
			(hide yes)
			(effects
				(font
					(size 1.016 1.016)
					(thickness 0.1524)
				)
			)
		)
		(property "Device Type" "HOLE315R138"
			(at 0 -8.5852 0)
			(unlocked yes)
			(layer "F.Fab")
			(hide yes)
			(effects
				(font
					(size 1.016 1.016)
					(thickness 0.1524)
				)
			)
		)
		(duplicate_pad_numbers_are_jumpers no)
		(fp_poly
			(pts
				(xy 0 4.3053) (xy -0.13462 4.30276) (xy -0.27051 4.29641) (xy -0.40513 4.28625) (xy -0.53975 4.27101)
				(xy -0.6731 4.25196) (xy -0.80645 4.2291) (xy -0.9398 4.20116) (xy -1.07061 4.17068) (xy -1.20142 4.13385)
				(xy -1.33096 4.09448) (xy -1.45796 4.0513) (xy -1.58496 4.00304) (xy -1.70942 3.95097) (xy -1.83261 3.89509)
				(xy -1.95453 3.83667) (xy -2.07391 3.77317) (xy -2.19202 3.70586) (xy -2.30632 3.63474) (xy -2.41935 3.56108)
				(xy -2.53111 3.48361) (xy -2.63906 3.40233) (xy -2.74447 3.31724) (xy -2.84734 3.22961) (xy -2.94767 3.13817)
				(xy -3.04419 3.04419) (xy -3.13817 2.94767) (xy -3.22961 2.84734) (xy -3.31724 2.74447) (xy -3.40233 2.63906)
				(xy -3.48361 2.53111) (xy -3.56108 2.41935) (xy -3.63474 2.30632) (xy -3.70586 2.19202) (xy -3.77317 2.07391)
				(xy -3.83667 1.95453) (xy -3.89509 1.83261) (xy -3.95097 1.70942) (xy -4.00304 1.58496) (xy -4.0513 1.45796)
				(xy -4.09448 1.33096) (xy -4.13385 1.20142) (xy -4.17068 1.07061) (xy -4.20116 0.9398) (xy -4.2291 0.80645)
				(xy -4.25196 0.6731) (xy -4.27101 0.53975) (xy -4.28625 0.40513) (xy -4.29641 0.27051) (xy -4.30276 0.13462)
				(xy -4.3053 0) (xy -4.30276 -0.13462) (xy -4.29641 -0.27051) (xy -4.28625 -0.40513) (xy -4.27101 -0.53975)
				(xy -4.25196 -0.6731) (xy -4.2291 -0.80645) (xy -4.20116 -0.9398) (xy -4.17068 -1.07061) (xy -4.13385 -1.20142)
				(xy -4.09448 -1.33096) (xy -4.0513 -1.45796) (xy -4.00304 -1.58496) (xy -3.95097 -1.70942) (xy -3.89509 -1.83261)
				(xy -3.83667 -1.95453) (xy -3.77317 -2.07391) (xy -3.70586 -2.19202) (xy -3.63474 -2.30632) (xy -3.56108 -2.41935)
				(xy -3.48361 -2.53111) (xy -3.40233 -2.63906) (xy -3.31724 -2.74447) (xy -3.22961 -2.84734) (xy -3.13817 -2.94767)
				(xy -3.04419 -3.04419) (xy -2.94767 -3.13817) (xy -2.84734 -3.22961) (xy -2.74447 -3.31724) (xy -2.63906 -3.40233)
				(xy -2.53111 -3.48361) (xy -2.41935 -3.56108) (xy -2.30632 -3.63474) (xy -2.19202 -3.70586) (xy -2.07391 -3.77317)
				(xy -1.95453 -3.83667) (xy -1.83261 -3.89509) (xy -1.70942 -3.95097) (xy -1.58496 -4.00304) (xy -1.45796 -4.0513)
				(xy -1.33096 -4.09448) (xy -1.20142 -4.13385) (xy -1.07061 -4.17068) (xy -0.9398 -4.20116) (xy -0.80645 -4.2291)
				(xy -0.6731 -4.25196) (xy -0.53975 -4.27101) (xy -0.40513 -4.28625) (xy -0.27051 -4.29641) (xy -0.13462 -4.30276)
				(xy 0 -4.3053) (xy 0.13462 -4.30276) (xy 0.27051 -4.29641) (xy 0.40513 -4.28625) (xy 0.53975 -4.27101)
				(xy 0.6731 -4.25196) (xy 0.80645 -4.2291) (xy 0.9398 -4.20116) (xy 1.07061 -4.17068) (xy 1.20142 -4.13385)
				(xy 1.33096 -4.09448) (xy 1.45796 -4.0513) (xy 1.58496 -4.00304) (xy 1.70942 -3.95097) (xy 1.83261 -3.89509)
				(xy 1.95453 -3.83667) (xy 2.07391 -3.77317) (xy 2.19202 -3.70586) (xy 2.30632 -3.63474) (xy 2.41935 -3.56108)
				(xy 2.53111 -3.48361) (xy 2.63906 -3.40233) (xy 2.74447 -3.31724) (xy 2.84734 -3.22961) (xy 2.94767 -3.13817)
				(xy 3.04419 -3.04419) (xy 3.13817 -2.94767) (xy 3.22961 -2.84734) (xy 3.31724 -2.74447) (xy 3.40233 -2.63906)
				(xy 3.48361 -2.53111) (xy 3.56108 -2.41935) (xy 3.63474 -2.30632) (xy 3.70586 -2.19202) (xy 3.77317 -2.07391)
				(xy 3.83667 -1.95453) (xy 3.89509 -1.83261) (xy 3.95097 -1.70942) (xy 4.00304 -1.58496) (xy 4.0513 -1.45796)
				(xy 4.09448 -1.33096) (xy 4.13385 -1.20142) (xy 4.17068 -1.07061) (xy 4.20116 -0.9398) (xy 4.2291 -0.80645)
				(xy 4.25196 -0.6731) (xy 4.27101 -0.53975) (xy 4.28625 -0.40513) (xy 4.29641 -0.27051) (xy 4.30276 -0.13462)
				(xy 4.3053 0) (xy 4.30276 0.13462) (xy 4.29641 0.27051) (xy 4.28625 0.40513) (xy 4.27101 0.53975)
				(xy 4.25196 0.6731) (xy 4.2291 0.80645) (xy 4.20116 0.9398) (xy 4.17068 1.07061) (xy 4.13385 1.20142)
				(xy 4.09448 1.33096) (xy 4.0513 1.45796) (xy 4.00304 1.58496) (xy 3.95097 1.70942) (xy 3.89509 1.83261)
				(xy 3.83667 1.95453) (xy 3.77317 2.07391) (xy 3.70586 2.19202) (xy 3.63474 2.30632) (xy 3.56108 2.41935)
				(xy 3.48361 2.53111) (xy 3.40233 2.63906) (xy 3.31724 2.74447) (xy 3.22961 2.84734) (xy 3.13817 2.94767)
				(xy 3.04419 3.04419) (xy 2.94767 3.13817) (xy 2.84734 3.22961) (xy 2.74447 3.31724) (xy 2.63906 3.40233)
				(xy 2.53111 3.48361) (xy 2.41935 3.56108) (xy 2.30632 3.63474) (xy 2.19202 3.70586) (xy 2.07391 3.77317)
				(xy 1.95453 3.83667) (xy 1.83261 3.89509) (xy 1.70942 3.95097) (xy 1.58496 4.00304) (xy 1.45796 4.0513)
				(xy 1.33096 4.09448) (xy 1.20142 4.13385) (xy 1.07061 4.17068) (xy 0.9398 4.20116) (xy 0.80645 4.2291)
				(xy 0.6731 4.25196) (xy 0.53975 4.27101) (xy 0.40513 4.28625) (xy 0.27051 4.29641) (xy 0.13462 4.30276)
			)
			(stroke
				(width 0)
				(type default)
			)
			(fill no)
			(layer "F.CrtYd")
		)
		(fp_poly
			(pts
				(xy 0 4.3053) (xy -0.13462 4.30276) (xy -0.27051 4.29641) (xy -0.40513 4.28625) (xy -0.53975 4.27101)
				(xy -0.6731 4.25196) (xy -0.80645 4.2291) (xy -0.9398 4.20116) (xy -1.07061 4.17068) (xy -1.20142 4.13385)
				(xy -1.33096 4.09448) (xy -1.45796 4.0513) (xy -1.58496 4.00304) (xy -1.70942 3.95097) (xy -1.83261 3.89509)
				(xy -1.95453 3.83667) (xy -2.07391 3.77317) (xy -2.19202 3.70586) (xy -2.30632 3.63474) (xy -2.41935 3.56108)
				(xy -2.53111 3.48361) (xy -2.63906 3.40233) (xy -2.74447 3.31724) (xy -2.84734 3.22961) (xy -2.94767 3.13817)
				(xy -3.04419 3.04419) (xy -3.13817 2.94767) (xy -3.22961 2.84734) (xy -3.31724 2.74447) (xy -3.40233 2.63906)
				(xy -3.48361 2.53111) (xy -3.56108 2.41935) (xy -3.63474 2.30632) (xy -3.70586 2.19202) (xy -3.77317 2.07391)
				(xy -3.83667 1.95453) (xy -3.89509 1.83261) (xy -3.95097 1.70942) (xy -4.00304 1.58496) (xy -4.0513 1.45796)
				(xy -4.09448 1.33096) (xy -4.13385 1.20142) (xy -4.17068 1.07061) (xy -4.20116 0.9398) (xy -4.2291 0.80645)
				(xy -4.25196 0.6731) (xy -4.27101 0.53975) (xy -4.28625 0.40513) (xy -4.29641 0.27051) (xy -4.30276 0.13462)
				(xy -4.3053 0) (xy -4.30276 -0.13462) (xy -4.29641 -0.27051) (xy -4.28625 -0.40513) (xy -4.27101 -0.53975)
				(xy -4.25196 -0.6731) (xy -4.2291 -0.80645) (xy -4.20116 -0.9398) (xy -4.17068 -1.07061) (xy -4.13385 -1.20142)
				(xy -4.09448 -1.33096) (xy -4.0513 -1.45796) (xy -4.00304 -1.58496) (xy -3.95097 -1.70942) (xy -3.89509 -1.83261)
				(xy -3.83667 -1.95453) (xy -3.77317 -2.07391) (xy -3.70586 -2.19202) (xy -3.63474 -2.30632) (xy -3.56108 -2.41935)
				(xy -3.48361 -2.53111) (xy -3.40233 -2.63906) (xy -3.31724 -2.74447) (xy -3.22961 -2.84734) (xy -3.13817 -2.94767)
				(xy -3.04419 -3.04419) (xy -2.94767 -3.13817) (xy -2.84734 -3.22961) (xy -2.74447 -3.31724) (xy -2.63906 -3.40233)
				(xy -2.53111 -3.48361) (xy -2.41935 -3.56108) (xy -2.30632 -3.63474) (xy -2.19202 -3.70586) (xy -2.07391 -3.77317)
				(xy -1.95453 -3.83667) (xy -1.83261 -3.89509) (xy -1.70942 -3.95097) (xy -1.58496 -4.00304) (xy -1.45796 -4.0513)
				(xy -1.33096 -4.09448) (xy -1.20142 -4.13385) (xy -1.07061 -4.17068) (xy -0.9398 -4.20116) (xy -0.80645 -4.2291)
				(xy -0.6731 -4.25196) (xy -0.53975 -4.27101) (xy -0.40513 -4.28625) (xy -0.27051 -4.29641) (xy -0.13462 -4.30276)
				(xy 0 -4.3053) (xy 0.13462 -4.30276) (xy 0.27051 -4.29641) (xy 0.40513 -4.28625) (xy 0.53975 -4.27101)
				(xy 0.6731 -4.25196) (xy 0.80645 -4.2291) (xy 0.9398 -4.20116) (xy 1.07061 -4.17068) (xy 1.20142 -4.13385)
				(xy 1.33096 -4.09448) (xy 1.45796 -4.0513) (xy 1.58496 -4.00304) (xy 1.70942 -3.95097) (xy 1.83261 -3.89509)
				(xy 1.95453 -3.83667) (xy 2.07391 -3.77317) (xy 2.19202 -3.70586) (xy 2.30632 -3.63474) (xy 2.41935 -3.56108)
				(xy 2.53111 -3.48361) (xy 2.63906 -3.40233) (xy 2.74447 -3.31724) (xy 2.84734 -3.22961) (xy 2.94767 -3.13817)
				(xy 3.04419 -3.04419) (xy 3.13817 -2.94767) (xy 3.22961 -2.84734) (xy 3.31724 -2.74447) (xy 3.40233 -2.63906)
				(xy 3.48361 -2.53111) (xy 3.56108 -2.41935) (xy 3.63474 -2.30632) (xy 3.70586 -2.19202) (xy 3.77317 -2.07391)
				(xy 3.83667 -1.95453) (xy 3.89509 -1.83261) (xy 3.95097 -1.70942) (xy 4.00304 -1.58496) (xy 4.0513 -1.45796)
				(xy 4.09448 -1.33096) (xy 4.13385 -1.20142) (xy 4.17068 -1.07061) (xy 4.20116 -0.9398) (xy 4.2291 -0.80645)
				(xy 4.25196 -0.6731) (xy 4.27101 -0.53975) (xy 4.28625 -0.40513) (xy 4.29641 -0.27051) (xy 4.30276 -0.13462)
				(xy 4.3053 0) (xy 4.30276 0.13462) (xy 4.29641 0.27051) (xy 4.28625 0.40513) (xy 4.27101 0.53975)
				(xy 4.25196 0.6731) (xy 4.2291 0.80645) (xy 4.20116 0.9398) (xy 4.17068 1.07061) (xy 4.13385 1.20142)
				(xy 4.09448 1.33096) (xy 4.0513 1.45796) (xy 4.00304 1.58496) (xy 3.95097 1.70942) (xy 3.89509 1.83261)
				(xy 3.83667 1.95453) (xy 3.77317 2.07391) (xy 3.70586 2.19202) (xy 3.63474 2.30632) (xy 3.56108 2.41935)
				(xy 3.48361 2.53111) (xy 3.40233 2.63906) (xy 3.31724 2.74447) (xy 3.22961 2.84734) (xy 3.13817 2.94767)
				(xy 3.04419 3.04419) (xy 2.94767 3.13817) (xy 2.84734 3.22961) (xy 2.74447 3.31724) (xy 2.63906 3.40233)
				(xy 2.53111 3.48361) (xy 2.41935 3.56108) (xy 2.30632 3.63474) (xy 2.19202 3.70586) (xy 2.07391 3.77317)
				(xy 1.95453 3.83667) (xy 1.83261 3.89509) (xy 1.70942 3.95097) (xy 1.58496 4.00304) (xy 1.45796 4.0513)
				(xy 1.33096 4.09448) (xy 1.20142 4.13385) (xy 1.07061 4.17068) (xy 0.9398 4.20116) (xy 0.80645 4.2291)
				(xy 0.6731 4.25196) (xy 0.53975 4.27101) (xy 0.40513 4.28625) (xy 0.27051 4.29641) (xy 0.13462 4.30276)
			)
			(stroke
				(width 0)
				(type default)
			)
			(fill no)
			(layer "F.Fab")
		)
		(pad "1" thru_hole circle
			(at 0 0)
			(size 8.001 8.001)
			(drill 3.5052)
			(layers "*.Cu" "*.Mask")
			(remove_unused_layers no)
			(net "GND")
			(clearance -1.7399)
			(thermal_gap 0.3048)
			(padstack
				(mode front_inner_back)
				(layer "Inner"
					(shape circle)
					(size 3.9116 3.9116)
					(clearance 0.3048)
				)
				(layer "B.Cu"
					(shape circle)
					(size 8.001 8.001)
					(clearance -1.7399)
				)
			)
		)
	)
	(footprint ""
		(layer "F.Cu")
		(at 21.489162 -13.843508 90)
		(property "Reference" "D3"
			(at 0 0 90)
			(layer "F.SilkS")
			(hide yes)
			(effects
				(font
					(size 1.27 1.27)
				)
			)
		)
		(property "Value" "BAS16H-GP"
			(at 0 -5.5372 90)
			(unlocked yes)
			(layer "F.Fab")
			(hide yes)
			(effects
				(font
					(size 1.016 1.016)
					(thickness 0.1524)
				)
			)
		)
		(property "Device Type" "SOD123AKH48"
			(at 0 -7.0612 90)
			(unlocked yes)
			(layer "F.Fab")
			(hide yes)
			(effects
				(font
					(size 1.016 1.016)
					(thickness 0.1524)
				)
			)
		)
		(duplicate_pad_numbers_are_jumpers no)
		(fp_line
			(start 1.016 -2.667)
			(end -1.016 -2.667)
			(stroke
				(width 0.1524)
				(type default)
			)
			(layer "F.SilkS")
		)
		(fp_line
			(start -1.016 -2.667)
			(end -1.016 2.667)
			(stroke
				(width 0.1524)
				(type default)
			)
			(layer "F.SilkS")
		)
		(fp_line
			(start 1.016 2.667)
			(end 1.016 -2.667)
			(stroke
				(width 0.1524)
				(type default)
			)
			(layer "F.SilkS")
		)
		(fp_line
			(start -1.016 2.667)
			(end 1.016 2.667)
			(stroke
				(width 0.1524)
				(type default)
			)
			(layer "F.SilkS")
		)
		(fp_line
			(start 0.889 2.921)
			(end -0.889 2.921)
			(stroke
				(width 0.508)
				(type default)
			)
			(layer "F.SilkS")
		)
		(fp_rect
			(start -1.143 3.175)
			(end 1.143 -2.794)
			(stroke
				(width 0)
				(type default)
			)
			(fill no)
			(layer "F.CrtYd")
		)
		(fp_poly
			(pts
				(xy -1.143 -2.794) (xy 1.143 -2.794) (xy 1.143 3.175) (xy -1.143 3.175)
			)
			(stroke
				(width 0)
				(type default)
			)
			(fill no)
			(layer "F.Fab")
		)
		(pad "A" smd rect
			(at 0 -1.6891 90)
			(size 0.889 1.397)
			(layers "F.Cu" "F.Mask" "F.Paste")
			(net "FAN_TACH11")
		)
		(pad "K" smd rect
			(at 0 1.6891 90)
			(size 0.889 1.397)
			(layers "F.Cu" "F.Mask" "F.Paste")
			(net "P12V")
		)
	)
	(footprint ""
		(layer "F.Cu")
		(at 26.6954 -289.433)
		(property "Reference" "R178"
			(at 0 0 0)
			(layer "F.SilkS")
			(hide yes)
			(effects
				(font
					(size 1.27 1.27)
				)
			)
		)
		(property "Value" "0R1206-PAD-1-GP"
			(at 0 -5.0292 0)
			(unlocked yes)
			(layer "F.Fab")
			(hide yes)
			(effects
				(font
					(size 1.016 1.016)
					(thickness 0.1524)
				)
			)
		)
		(property "Device Type" "0R1206-PAD-1"
			(at 0 -6.5532 0)
			(unlocked yes)
			(layer "F.Fab")
			(hide yes)
			(effects
				(font
					(size 1.016 1.016)
					(thickness 0.1524)
				)
			)
		)
		(duplicate_pad_numbers_are_jumpers no)
		(fp_line
			(start -1.016 -2.2352)
			(end -1.016 2.2352)
			(stroke
				(width 0.1524)
				(type default)
			)
			(layer "F.SilkS")
		)
		(fp_line
			(start -1.016 2.2352)
			(end 1.016 2.2352)
			(stroke
				(width 0.1524)
				(type default)
			)
			(layer "F.SilkS")
		)
		(fp_line
			(start 1.016 -2.2352)
			(end -1.016 -2.2352)
			(stroke
				(width 0.1524)
				(type default)
			)
			(layer "F.SilkS")
		)
		(fp_line
			(start 1.016 2.2352)
			(end 1.016 -2.2352)
			(stroke
				(width 0.1524)
				(type default)
			)
			(layer "F.SilkS")
		)
		(fp_rect
			(start -1.0922 2.3114)
			(end 1.0922 -2.3114)
			(stroke
				(width 0)
				(type default)
			)
			(fill no)
			(layer "F.CrtYd")
		)
		(fp_poly
			(pts
				(xy -1.0922 -2.3114) (xy 1.0922 -2.3114) (xy 1.0922 2.3114) (xy -1.0922 2.3114)
			)
			(stroke
				(width 0)
				(type default)
			)
			(fill no)
			(layer "F.Fab")
		)
		(pad "1" smd rect
			(at 0 -1.397)
			(size 1.651 2.0574)
			(drill
				(offset 0 0.3937)
			)
			(layers "F.Cu" "F.Mask" "F.Paste")
			(net "P12V_FAN2")
		)
		(pad "2" smd rect
			(at 0 1.397)
			(size 1.651 2.0574)
			(drill
				(offset 0 -0.3937)
			)
			(layers "F.Cu" "F.Mask" "F.Paste")
			(net "P12V")
		)
	)
	(footprint ""
		(layer "F.Cu")
		(at 12.6746 -225.8822 180)
		(property "Reference" "R124"
			(at 0 0 180)
			(layer "F.SilkS")
			(hide yes)
			(effects
				(font
					(size 1.27 1.27)
				)
			)
		)
		(property "Value" "1K8R6J-GP"
			(at -0.0508 -4.8514 180)
			(unlocked yes)
			(layer "F.Fab")
			(hide yes)
			(effects
				(font
					(size 1.016 1.016)
					(thickness 0.1524)
				)
			)
		)
		(property "Device Type" "R1206H28"
			(at 0 -6.3754 180)
			(unlocked yes)
			(layer "F.Fab")
			(hide yes)
			(effects
				(font
					(size 1.016 1.016)
					(thickness 0.1524)
				)
			)
		)
		(duplicate_pad_numbers_are_jumpers no)
		(fp_line
			(start 1.016 2.2352)
			(end -1.016 2.2352)
			(stroke
				(width 0.1524)
				(type default)
			)
			(layer "F.SilkS")
		)
		(fp_line
			(start 1.016 -2.2352)
			(end 1.016 2.2352)
			(stroke
				(width 0.1524)
				(type default)
			)
			(layer "F.SilkS")
		)
		(fp_line
			(start -1.016 2.2352)
			(end -1.016 -2.2352)
			(stroke
				(width 0.1524)
				(type default)
			)
			(layer "F.SilkS")
		)
		(fp_line
			(start -1.016 -2.2352)
			(end 1.016 -2.2352)
			(stroke
				(width 0.1524)
				(type default)
			)
			(layer "F.SilkS")
		)
		(fp_rect
			(start -1.0922 2.3114)
			(end 1.0922 -2.3114)
			(stroke
				(width 0)
				(type default)
			)
			(fill no)
			(layer "F.CrtYd")
		)
		(fp_poly
			(pts
				(xy -1.0922 -2.3114) (xy 1.0922 -2.3114) (xy 1.0922 2.3114) (xy -1.0922 2.3114)
			)
			(stroke
				(width 0)
				(type default)
			)
			(fill no)
			(layer "F.Fab")
		)
		(pad "1" smd rect
			(at 0 -1.397 180)
			(size 1.651 1.27)
			(layers "F.Cu" "F.Mask" "F.Paste")
			(net "P12V")
		)
		(pad "2" smd rect
			(at 0 1.397 180)
			(size 1.651 1.27)
			(layers "F.Cu" "F.Mask" "F.Paste")
			(net "LED_DR_LED3_BLUE")
		)
	)
	(footprint ""
		(layer "F.Cu")
		(at 36.957 -174.244)
		(property "Reference" "PQ9"
			(at 0 0 0)
			(layer "F.SilkS")
			(hide yes)
			(effects
				(font
					(size 1.27 1.27)
				)
			)
		)
		(property "Value" "PMBS3904-1-GP"
			(at 0 -9.0932 0)
			(unlocked yes)
			(layer "F.Fab")
			(hide yes)
			(effects
				(font
					(size 1.016 1.016)
					(thickness 0.1524)
				)
			)
		)
		(property "Device Type" "SOT-23-10H44"
			(at 0 -10.6172 0)
			(unlocked yes)
			(layer "F.Fab")
			(hide yes)
			(effects
				(font
					(size 1.016 1.016)
					(thickness 0.1524)
				)
			)
		)
		(duplicate_pad_numbers_are_jumpers no)
		(fp_line
			(start -1.7526 1.8796)
			(end -1.7526 0.9906)
			(stroke
				(width 0.3302)
				(type default)
			)
			(layer "F.SilkS")
		)
		(fp_line
			(start -1.651 -1.778)
			(end -1.651 1.778)
			(stroke
				(width 0.1524)
				(type default)
			)
			(layer "F.SilkS")
		)
		(fp_line
			(start -1.651 1.778)
			(end 1.651 1.778)
			(stroke
				(width 0.1524)
				(type default)
			)
			(layer "F.SilkS")
		)
		(fp_line
			(start -1.279398 2.152142)
			(end -0.9906 1.86309)
			(stroke
				(width 0.0127)
				(type default)
			)
			(layer "F.SilkS")
		)
		(fp_line
			(start -1.279144 2.15265)
			(end -0.701294 2.15265)
			(stroke
				(width 0.0127)
				(type default)
			)
			(layer "F.SilkS")
		)
		(fp_line
			(start -1.260856 2.1336)
			(end -0.720344 2.1336)
			(stroke
				(width 0.0127)
				(type default)
			)
			(layer "F.SilkS")
		)
		(fp_line
			(start -1.251458 2.124202)
			(end -0.729996 2.124202)
			(stroke
				(width 0.0127)
				(type default)
			)
			(layer "F.SilkS")
		)
		(fp_line
			(start -1.241806 2.11455)
			(end -0.739394 2.11455)
			(stroke
				(width 0.0127)
				(type default)
			)
			(layer "F.SilkS")
		)
		(fp_line
			(start -1.232408 2.105152)
			(end -0.749046 2.105152)
			(stroke
				(width 0.0127)
				(type default)
			)
			(layer "F.SilkS")
		)
		(fp_line
			(start -1.222756 2.0955)
			(end -0.758444 2.0955)
			(stroke
				(width 0.0127)
				(type default)
			)
			(layer "F.SilkS")
		)
		(fp_line
			(start -1.213358 2.086102)
			(end -0.768096 2.086102)
			(stroke
				(width 0.0127)
				(type default)
			)
			(layer "F.SilkS")
		)
		(fp_line
			(start -1.203706 2.07645)
			(end -0.777494 2.07645)
			(stroke
				(width 0.0127)
				(type default)
			)
			(layer "F.SilkS")
		)
		(fp_line
			(start -1.194308 2.067052)
			(end -0.787146 2.067052)
			(stroke
				(width 0.0127)
				(type default)
			)
			(layer "F.SilkS")
		)
		(fp_line
			(start -1.184656 2.0574)
			(end -0.796544 2.0574)
			(stroke
				(width 0.0127)
				(type default)
			)
			(layer "F.SilkS")
		)
		(fp_line
			(start -1.175258 2.048002)
			(end -0.806196 2.048002)
			(stroke
				(width 0.0127)
				(type default)
			)
			(layer "F.SilkS")
		)
		(fp_line
			(start -1.165606 2.03835)
			(end -0.815594 2.03835)
			(stroke
				(width 0.0127)
				(type default)
			)
			(layer "F.SilkS")
		)
		(fp_line
			(start -1.156208 2.028952)
			(end -0.825246 2.028952)
			(stroke
				(width 0.0127)
				(type default)
			)
			(layer "F.SilkS")
		)
		(fp_line
			(start -1.146556 2.0193)
			(end -0.834644 2.0193)
			(stroke
				(width 0.0127)
				(type default)
			)
			(layer "F.SilkS")
		)
		(fp_line
			(start -1.137158 2.009902)
			(end -0.844296 2.009902)
			(stroke
				(width 0.0127)
				(type default)
			)
			(layer "F.SilkS")
		)
		(fp_line
			(start -1.127506 2.00025)
			(end -0.853694 2.00025)
			(stroke
				(width 0.0127)
				(type default)
			)
			(layer "F.SilkS")
		)
		(fp_line
			(start -1.118108 1.990852)
			(end -0.863346 1.990852)
			(stroke
				(width 0.0127)
				(type default)
			)
			(layer "F.SilkS")
		)
		(fp_line
			(start -1.108456 1.9812)
			(end -0.872744 1.9812)
			(stroke
				(width 0.0127)
				(type default)
			)
			(layer "F.SilkS")
		)
		(fp_line
			(start -1.099058 1.971802)
			(end -0.882396 1.971802)
			(stroke
				(width 0.0127)
				(type default)
			)
			(layer "F.SilkS")
		)
		(fp_line
			(start -1.089406 1.96215)
			(end -0.891794 1.96215)
			(stroke
				(width 0.0127)
				(type default)
			)
			(layer "F.SilkS")
		)
		(fp_line
			(start -1.080008 1.952752)
			(end -0.901446 1.952752)
			(stroke
				(width 0.0127)
				(type default)
			)
			(layer "F.SilkS")
		)
		(fp_line
			(start -1.070356 1.9431)
			(end -0.910844 1.9431)
			(stroke
				(width 0.0127)
				(type default)
			)
			(layer "F.SilkS")
		)
		(fp_line
			(start -1.060958 1.933702)
			(end -0.920496 1.933702)
			(stroke
				(width 0.0127)
				(type default)
			)
			(layer "F.SilkS")
		)
		(fp_line
			(start -1.051306 1.92405)
			(end -0.929894 1.92405)
			(stroke
				(width 0.0127)
				(type default)
			)
			(layer "F.SilkS")
		)
		(fp_line
			(start -1.041908 1.914652)
			(end -0.939546 1.914652)
			(stroke
				(width 0.0127)
				(type default)
			)
			(layer "F.SilkS")
		)
		(fp_line
			(start -1.032256 1.905)
			(end -0.948944 1.905)
			(stroke
				(width 0.0127)
				(type default)
			)
			(layer "F.SilkS")
		)
		(fp_line
			(start -1.022858 1.895602)
			(end -0.958596 1.895602)
			(stroke
				(width 0.0127)
				(type default)
			)
			(layer "F.SilkS")
		)
		(fp_line
			(start -1.013206 1.88595)
			(end -0.967994 1.88595)
			(stroke
				(width 0.0127)
				(type default)
			)
			(layer "F.SilkS")
		)
		(fp_line
			(start -1.003808 1.876552)
			(end -0.977646 1.876552)
			(stroke
				(width 0.0127)
				(type default)
			)
			(layer "F.SilkS")
		)
		(fp_line
			(start -0.994156 1.8669)
			(end -0.987044 1.8669)
			(stroke
				(width 0.0127)
				(type default)
			)
			(layer "F.SilkS")
		)
		(fp_line
			(start -0.9906 1.86309)
			(end -0.701294 2.15265)
			(stroke
				(width 0.0127)
				(type default)
			)
			(layer "F.SilkS")
		)
		(fp_line
			(start -0.719074 2.145538)
			(end -1.265936 2.14122)
			(stroke
				(width 0.0127)
				(type default)
			)
			(layer "F.SilkS")
		)
		(fp_line
			(start -0.71628 2.15265)
			(end -1.26492 2.15265)
			(stroke
				(width 0.0127)
				(type default)
			)
			(layer "F.SilkS")
		)
		(fp_line
			(start -0.635 1.8796)
			(end -1.7526 1.8796)
			(stroke
				(width 0.3302)
				(type default)
			)
			(layer "F.SilkS")
		)
		(fp_line
			(start 1.651 -1.778)
			(end -1.651 -1.778)
			(stroke
				(width 0.1524)
				(type default)
			)
			(layer "F.SilkS")
		)
		(fp_line
			(start 1.651 1.778)
			(end 1.651 -1.778)
			(stroke
				(width 0.1524)
				(type default)
			)
			(layer "F.SilkS")
		)
		(fp_poly
			(pts
				(xy -1.285748 2.159) (xy -1.285748 1.8796) (xy -1.778 1.8796) (xy -1.778 -1.8796) (xy 1.778 -1.8796)
				(xy 1.778 1.8796) (xy -0.694944 1.8796) (xy -0.694944 2.159)
			)
			(stroke
				(width 0)
				(type default)
			)
			(fill no)
			(layer "F.CrtYd")
		)
		(fp_poly
			(pts
				(xy -1.285748 2.159) (xy -1.285748 1.8796) (xy -1.778 1.8796) (xy -1.778 -1.8796) (xy 1.778 -1.8796)
				(xy 1.778 1.8796) (xy -0.694944 1.8796) (xy -0.694944 2.159)
			)
			(stroke
				(width 0)
				(type default)
			)
			(fill no)
			(layer "F.Fab")
		)
		(pad "1" smd rect
			(at -0.98425 0.9525)
			(size 0.762 1.143)
			(layers "F.Cu" "F.Mask" "F.Paste")
			(net "TEMP_ALM#_IN")
		)
		(pad "2" smd rect
			(at 0.98425 0.9525)
			(size 0.762 1.143)
			(layers "F.Cu" "F.Mask" "F.Paste")
			(net "GND")
		)
		(pad "3" smd rect
			(at 0 -0.9525)
			(size 0.762 1.143)
			(layers "F.Cu" "F.Mask" "F.Paste")
			(net "TEMP_ALM#_IN_D")
		)
	)
	(footprint ""
		(layer "F.Cu")
		(at 26.416 -111.633)
		(property "Reference" "PQ7"
			(at 0 0 0)
			(layer "F.SilkS")
			(hide yes)
			(effects
				(font
					(size 1.27 1.27)
				)
			)
		)
		(property "Value" "PH0925CL-GP"
			(at -4.2799 -0.4572 0)
			(unlocked yes)
			(layer "F.Fab")
			(hide yes)
			(effects
				(font
					(size 1.016 1.016)
					(thickness 0.1524)
				)
			)
		)
		(property "Device Type" "LFPAK-5PH48-U"
			(at -4.2799 -1.9812 0)
			(unlocked yes)
			(layer "F.Fab")
			(hide yes)
			(effects
				(font
					(size 1.016 1.016)
					(thickness 0.1524)
				)
			)
		)
		(duplicate_pad_numbers_are_jumpers no)
		(fp_line
			(start -2.7559 -6.5532)
			(end -2.7559 1.0668)
			(stroke
				(width 0.1524)
				(type default)
			)
			(layer "F.SilkS")
		)
		(fp_line
			(start -2.7559 1.0668)
			(end 2.7559 1.0668)
			(stroke
				(width 0.1524)
				(type default)
			)
			(layer "F.SilkS")
		)
		(fp_line
			(start -1.7272 1.1684)
			(end -2.1082 1.1684)
			(stroke
				(width 0.3302)
				(type default)
			)
			(layer "F.SilkS")
		)
		(fp_line
			(start 2.7559 -6.5532)
			(end -2.7559 -6.5532)
			(stroke
				(width 0.1524)
				(type default)
			)
			(layer "F.SilkS")
		)
		(fp_line
			(start 2.7559 1.0668)
			(end 2.7559 -6.5532)
			(stroke
				(width 0.1524)
				(type default)
			)
			(layer "F.SilkS")
		)
		(fp_poly
			(pts
				(xy -2.3368 1.5748) (xy -1.905 1.143) (xy -1.4732 1.5748)
			)
			(stroke
				(width 0)
				(type default)
			)
			(fill yes)
			(layer "F.SilkS")
		)
		(fp_poly
			(pts
				(xy -2.5019 -4.02971) (xy -0.3302 -4.02971) (xy -0.3302 -6.30301) (xy -2.5019 -6.30301)
			)
			(stroke
				(width 0)
				(type default)
			)
			(fill yes)
			(layer "F.Paste")
		)
		(fp_poly
			(pts
				(xy -2.5019 -1.09601) (xy -0.3302 -1.09601) (xy -0.3302 -3.36931) (xy -2.5019 -3.36931)
			)
			(stroke
				(width 0)
				(type default)
			)
			(fill yes)
			(layer "F.Paste")
		)
		(fp_poly
			(pts
				(xy 0.3302 -4.02971) (xy 2.5019 -4.02971) (xy 2.5019 -6.30301) (xy 0.3302 -6.30301)
			)
			(stroke
				(width 0)
				(type default)
			)
			(fill yes)
			(layer "F.Paste")
		)
		(fp_poly
			(pts
				(xy 0.3302 -1.09601) (xy 2.5019 -1.09601) (xy 2.5019 -3.36931) (xy 0.3302 -3.36931)
			)
			(stroke
				(width 0)
				(type default)
			)
			(fill yes)
			(layer "F.Paste")
		)
		(fp_rect
			(start -2.4511 0.3048)
			(end 2.4511 -5.6896)
			(stroke
				(width 0)
				(type default)
			)
			(fill no)
			(layer "F.CrtYd")
		)
		(fp_poly
			(pts
				(xy -3.0099 1.3208) (xy -3.0099 -6.8072) (xy 3.0099 -6.8072) (xy 3.0099 -1.016) (xy 2.4511 -1.016)
				(xy 2.4511 -5.6896) (xy -2.4511 -5.6896) (xy -2.4511 0.3048) (xy 2.4511 0.3048) (xy 2.4511 -1.0033)
				(xy 3.0099 -1.0033) (xy 3.0099 1.3208)
			)
			(stroke
				(width 0)
				(type default)
			)
			(fill no)
			(layer "F.CrtYd")
		)
		(fp_rect
			(start -3.0099 1.3208)
			(end 3.0099 -6.8072)
			(stroke
				(width 0)
				(type default)
			)
			(fill no)
			(layer "F.Fab")
		)
		(pad "1" smd rect
			(at -1.905 0)
			(size 0.762 1.6256)
			(layers "F.Cu" "F.Mask" "F.Paste")
			(net "P12VU")
		)
		(pad "2" smd rect
			(at -0.635 0)
			(size 0.762 1.6256)
			(layers "F.Cu" "F.Mask" "F.Paste")
			(net "P12VU")
		)
		(pad "3" smd rect
			(at 0.635 0)
			(size 0.762 1.6256)
			(layers "F.Cu" "F.Mask" "F.Paste")
			(net "P12VU")
		)
		(pad "4" smd rect
			(at 1.905 0)
			(size 0.762 1.6256)
			(layers "F.Cu" "F.Mask" "F.Paste")
			(net "P12VU_2490_GATE_DRV")
		)
		(pad "5" smd rect
			(at 0 -3.69951)
			(size 5.0038 5.207)
			(layers "F.Cu" "F.Mask" "F.Paste")
			(net "P12VU_NET")
		)
	)
	(footprint ""
		(layer "F.Cu")
		(at 40.259 -178.054 180)
		(property "Reference" "R260"
			(at 0 0 180)
			(layer "F.SilkS")
			(hide yes)
			(effects
				(font
					(size 1.27 1.27)
				)
			)
		)
		(property "Value" "47KR2J-2-GP"
			(at 0.064008 -3.993896 180)
			(unlocked yes)
			(layer "F.Fab")
			(hide yes)
			(effects
				(font
					(size 1.016 1.016)
					(thickness 0.1524)
				)
			)
		)
		(property "Device Type" "R402H16"
			(at 0.064008 -5.517896 180)
			(unlocked yes)
			(layer "F.Fab")
			(hide yes)
			(effects
				(font
					(size 1.016 1.016)
					(thickness 0.1524)
				)
			)
		)
		(duplicate_pad_numbers_are_jumpers no)
		(fp_line
			(start 0.508 -0.9398)
			(end -0.508 -0.9398)
			(stroke
				(width 0.1524)
				(type default)
			)
			(layer "F.SilkS")
		)
		(fp_line
			(start -0.508 -0.9398)
			(end -0.508 0.9398)
			(stroke
				(width 0.1524)
				(type default)
			)
			(layer "F.SilkS")
		)
		(fp_rect
			(start -0.508 0.9398)
			(end 0.508 -0.9398)
			(stroke
				(width 0)
				(type default)
			)
			(fill no)
			(layer "F.CrtYd")
		)
		(fp_rect
			(start -0.508 0.9398)
			(end 0.508 -0.9398)
			(stroke
				(width 0)
				(type default)
			)
			(fill no)
			(layer "F.Fab")
		)
		(pad "1" smd custom
			(at 0 -0.4445 180)
			(size 0.1397 0.1397)
			(layers "F.Cu" "F.Mask" "F.Paste")
			(net "P3V3_AUX")
			(options
				(clearance outline)
				(anchor circle)
			)
			(primitives
				(gr_poly
					(pts
						(arc
							(start -0.1778 -0.2794)
							(mid -0.249642 -0.249642)
							(end -0.2794 -0.1778)
						)
						(arc
							(start -0.2794 0.1778)
							(mid -0.249642 0.249642)
							(end -0.1778 0.2794)
						)
						(arc
							(start 0.1778 0.2794)
							(mid 0.249642 0.249642)
							(end 0.2794 0.1778)
						)
						(arc
							(start 0.2794 -0.1778)
							(mid 0.249642 -0.249642)
							(end 0.1778 -0.2794)
						)
					)
					(width 0)
					(fill yes)
				)
			)
		)
		(pad "2" smd custom
			(at 0 0.4445 180)
			(size 0.1397 0.1397)
			(layers "F.Cu" "F.Mask" "F.Paste")
			(net "D_LATCH_PRE#")
			(options
				(clearance outline)
				(anchor circle)
			)
			(primitives
				(gr_poly
					(pts
						(arc
							(start -0.1778 -0.2794)
							(mid -0.249642 -0.249642)
							(end -0.2794 -0.1778)
						)
						(arc
							(start -0.2794 0.1778)
							(mid -0.249642 0.249642)
							(end -0.1778 0.2794)
						)
						(arc
							(start 0.1778 0.2794)
							(mid 0.249642 0.249642)
							(end 0.2794 0.1778)
						)
						(arc
							(start 0.2794 -0.1778)
							(mid 0.249642 -0.249642)
							(end 0.1778 -0.2794)
						)
					)
					(width 0)
					(fill yes)
				)
			)
		)
	)
	(footprint ""
		(layer "F.Cu")
		(at 19.558508 -288.594038)
		(property "Reference" "R103"
			(at 0 0 0)
			(layer "F.SilkS")
			(hide yes)
			(effects
				(font
					(size 1.27 1.27)
				)
			)
		)
		(property "Value" "10KR2F-2-GP"
			(at 0.064008 -3.993896 0)
			(unlocked yes)
			(layer "F.Fab")
			(hide yes)
			(effects
				(font
					(size 1.016 1.016)
					(thickness 0.1524)
				)
			)
		)
		(property "Device Type" "R402H16"
			(at 0.064008 -5.517896 0)
			(unlocked yes)
			(layer "F.Fab")
			(hide yes)
			(effects
				(font
					(size 1.016 1.016)
					(thickness 0.1524)
				)
			)
		)
		(duplicate_pad_numbers_are_jumpers no)
		(fp_line
			(start -0.508 -0.9398)
			(end -0.508 0.9398)
			(stroke
				(width 0.1524)
				(type default)
			)
			(layer "F.SilkS")
		)
		(fp_line
			(start 0.508 -0.9398)
			(end -0.508 -0.9398)
			(stroke
				(width 0.1524)
				(type default)
			)
			(layer "F.SilkS")
		)
		(fp_rect
			(start -0.508 0.9398)
			(end 0.508 -0.9398)
			(stroke
				(width 0)
				(type default)
			)
			(fill no)
			(layer "F.CrtYd")
		)
		(fp_rect
			(start -0.508 0.9398)
			(end 0.508 -0.9398)
			(stroke
				(width 0)
				(type default)
			)
			(fill no)
			(layer "F.Fab")
		)
		(pad "1" smd custom
			(at 0 -0.4445)
			(size 0.1397 0.1397)
			(layers "F.Cu" "F.Mask" "F.Paste")
			(net "FANIN_4")
			(options
				(clearance outline)
				(anchor circle)
			)
			(primitives
				(gr_poly
					(pts
						(arc
							(start -0.1778 -0.2794)
							(mid -0.249642 -0.249642)
							(end -0.2794 -0.1778)
						)
						(arc
							(start -0.2794 0.1778)
							(mid -0.249642 0.249642)
							(end -0.1778 0.2794)
						)
						(arc
							(start 0.1778 0.2794)
							(mid 0.249642 0.249642)
							(end 0.2794 0.1778)
						)
						(arc
							(start 0.2794 -0.1778)
							(mid 0.249642 -0.249642)
							(end 0.1778 -0.2794)
						)
					)
					(width 0)
					(fill yes)
				)
			)
		)
		(pad "2" smd custom
			(at 0 0.4445)
			(size 0.1397 0.1397)
			(layers "F.Cu" "F.Mask" "F.Paste")
			(net "GND")
			(options
				(clearance outline)
				(anchor circle)
			)
			(primitives
				(gr_poly
					(pts
						(arc
							(start -0.1778 -0.2794)
							(mid -0.249642 -0.249642)
							(end -0.2794 -0.1778)
						)
						(arc
							(start -0.2794 0.1778)
							(mid -0.249642 0.249642)
							(end -0.1778 0.2794)
						)
						(arc
							(start 0.1778 0.2794)
							(mid 0.249642 0.249642)
							(end 0.2794 0.1778)
						)
						(arc
							(start 0.2794 -0.1778)
							(mid 0.249642 -0.249642)
							(end 0.1778 -0.2794)
						)
					)
					(width 0)
					(fill yes)
				)
			)
		)
	)
	(footprint ""
		(layer "F.Cu")
		(at 26.67 -361.188)
		(property "Reference" "PR116"
			(at 0 0 0)
			(layer "F.SilkS")
			(hide yes)
			(effects
				(font
					(size 1.27 1.27)
				)
			)
		)
		(property "Value" "0R2J-2-GP"
			(at 0.064008 -3.993896 0)
			(unlocked yes)
			(layer "F.Fab")
			(hide yes)
			(effects
				(font
					(size 1.016 1.016)
					(thickness 0.1524)
				)
			)
		)
		(property "Device Type" "R402H16"
			(at 0.064008 -5.517896 0)
			(unlocked yes)
			(layer "F.Fab")
			(hide yes)
			(effects
				(font
					(size 1.016 1.016)
					(thickness 0.1524)
				)
			)
		)
		(duplicate_pad_numbers_are_jumpers no)
		(fp_line
			(start -0.508 -0.9398)
			(end -0.508 0.9398)
			(stroke
				(width 0.1524)
				(type default)
			)
			(layer "F.SilkS")
		)
		(fp_line
			(start 0.508 -0.9398)
			(end -0.508 -0.9398)
			(stroke
				(width 0.1524)
				(type default)
			)
			(layer "F.SilkS")
		)
		(fp_rect
			(start -0.508 0.9398)
			(end 0.508 -0.9398)
			(stroke
				(width 0)
				(type default)
			)
			(fill no)
			(layer "F.CrtYd")
		)
		(fp_rect
			(start -0.508 0.9398)
			(end 0.508 -0.9398)
			(stroke
				(width 0)
				(type default)
			)
			(fill no)
			(layer "F.Fab")
		)
		(pad "1" smd custom
			(at 0 -0.4445)
			(size 0.1397 0.1397)
			(layers "F.Cu" "F.Mask" "F.Paste")
			(net "ADM1276_LATCH#")
			(options
				(clearance outline)
				(anchor circle)
			)
			(primitives
				(gr_poly
					(pts
						(arc
							(start -0.1778 -0.2794)
							(mid -0.249642 -0.249642)
							(end -0.2794 -0.1778)
						)
						(arc
							(start -0.2794 0.1778)
							(mid -0.249642 0.249642)
							(end -0.1778 0.2794)
						)
						(arc
							(start 0.1778 0.2794)
							(mid 0.249642 0.249642)
							(end 0.2794 0.1778)
						)
						(arc
							(start 0.2794 -0.1778)
							(mid 0.249642 -0.249642)
							(end 0.1778 -0.2794)
						)
					)
					(width 0)
					(fill yes)
				)
			)
		)
		(pad "2" smd custom
			(at 0 0.4445)
			(size 0.1397 0.1397)
			(layers "F.Cu" "F.Mask" "F.Paste")
			(net "P3V3")
			(options
				(clearance outline)
				(anchor circle)
			)
			(primitives
				(gr_poly
					(pts
						(arc
							(start -0.1778 -0.2794)
							(mid -0.249642 -0.249642)
							(end -0.2794 -0.1778)
						)
						(arc
							(start -0.2794 0.1778)
							(mid -0.249642 0.249642)
							(end -0.1778 0.2794)
						)
						(arc
							(start 0.1778 0.2794)
							(mid 0.249642 0.249642)
							(end 0.2794 0.1778)
						)
						(arc
							(start 0.2794 -0.1778)
							(mid 0.249642 -0.249642)
							(end 0.1778 -0.2794)
						)
					)
					(width 0)
					(fill yes)
				)
			)
		)
	)
	(footprint ""
		(layer "F.Cu")
		(at 37.2618 -121.793)
		(property "Reference" "C257"
			(at 0 0 0)
			(layer "F.SilkS")
			(hide yes)
			(effects
				(font
					(size 1.27 1.27)
				)
			)
		)
		(property "Value" "SC1U25V3KX-1-GP"
			(at 0 -2.8194 0)
			(unlocked yes)
			(layer "F.Fab")
			(hide yes)
			(effects
				(font
					(size 1.016 1.016)
					(thickness 0.1524)
				)
			)
		)
		(property "Device Type" "C603H36"
			(at 0 -4.3434 0)
			(unlocked yes)
			(layer "F.Fab")
			(hide yes)
			(effects
				(font
					(size 1.016 1.016)
					(thickness 0.1524)
				)
			)
		)
		(duplicate_pad_numbers_are_jumpers no)
		(fp_line
			(start 0.508 0)
			(end -0.508 0)
			(stroke
				(width 0.2032)
				(type default)
			)
			(layer "F.SilkS")
		)
		(fp_rect
			(start -0.5842 1.3335)
			(end 0.5842 -1.3335)
			(stroke
				(width 0)
				(type default)
			)
			(fill no)
			(layer "F.CrtYd")
		)
		(fp_rect
			(start -0.5842 1.3335)
			(end 0.5842 -1.3335)
			(stroke
				(width 0)
				(type default)
			)
			(fill no)
			(layer "F.Fab")
		)
		(pad "1" smd custom
			(at 0 -0.762)
			(size 0.2159 0.2159)
			(layers "F.Cu" "F.Mask" "F.Paste")
			(net "P12V")
			(options
				(clearance outline)
				(anchor circle)
			)
			(primitives
				(gr_poly
					(pts
						(arc
							(start -0.3302 -0.4318)
							(mid -0.402042 -0.402042)
							(end -0.4318 -0.3302)
						)
						(arc
							(start -0.4318 0.3302)
							(mid -0.402042 0.402042)
							(end -0.3302 0.4318)
						)
						(arc
							(start 0.3302 0.4318)
							(mid 0.402042 0.402042)
							(end 0.4318 0.3302)
						)
						(arc
							(start 0.4318 -0.3302)
							(mid 0.402042 -0.402042)
							(end 0.3302 -0.4318)
						)
					)
					(width 0)
					(fill yes)
				)
			)
		)
		(pad "2" smd custom
			(at 0 0.762)
			(size 0.2159 0.2159)
			(layers "F.Cu" "F.Mask" "F.Paste")
			(net "GND")
			(options
				(clearance outline)
				(anchor circle)
			)
			(primitives
				(gr_poly
					(pts
						(arc
							(start -0.3302 -0.4318)
							(mid -0.402042 -0.402042)
							(end -0.4318 -0.3302)
						)
						(arc
							(start -0.4318 0.3302)
							(mid -0.402042 0.402042)
							(end -0.3302 0.4318)
						)
						(arc
							(start 0.3302 0.4318)
							(mid 0.402042 0.402042)
							(end 0.4318 0.3302)
						)
						(arc
							(start 0.4318 -0.3302)
							(mid 0.402042 -0.402042)
							(end 0.3302 -0.4318)
						)
					)
					(width 0)
					(fill yes)
				)
			)
		)
	)
	(footprint ""
		(layer "F.Cu")
		(at 14.8844 -44.5262 90)
		(property "Reference" "R171"
			(at 0 0 90)
			(layer "F.SilkS")
			(hide yes)
			(effects
				(font
					(size 1.27 1.27)
				)
			)
		)
		(property "Value" "0R2J-2-GP"
			(at 0.064008 -3.993896 90)
			(unlocked yes)
			(layer "F.Fab")
			(hide yes)
			(effects
				(font
					(size 1.016 1.016)
					(thickness 0.1524)
				)
			)
		)
		(property "Device Type" "R402H16"
			(at 0.064008 -5.517896 90)
			(unlocked yes)
			(layer "F.Fab")
			(hide yes)
			(effects
				(font
					(size 1.016 1.016)
					(thickness 0.1524)
				)
			)
		)
		(duplicate_pad_numbers_are_jumpers no)
		(fp_line
			(start 0.508 -0.9398)
			(end -0.508 -0.9398)
			(stroke
				(width 0.1524)
				(type default)
			)
			(layer "F.SilkS")
		)
		(fp_line
			(start -0.508 -0.9398)
			(end -0.508 0.9398)
			(stroke
				(width 0.1524)
				(type default)
			)
			(layer "F.SilkS")
		)
		(fp_rect
			(start -0.508 0.9398)
			(end 0.508 -0.9398)
			(stroke
				(width 0)
				(type default)
			)
			(fill no)
			(layer "F.CrtYd")
		)
		(fp_rect
			(start -0.508 0.9398)
			(end 0.508 -0.9398)
			(stroke
				(width 0)
				(type default)
			)
			(fill no)
			(layer "F.Fab")
		)
		(pad "1" smd custom
			(at 0 -0.4445 90)
			(size 0.1397 0.1397)
			(layers "F.Cu" "F.Mask" "F.Paste")
			(net "SELF_1A_HB")
			(options
				(clearance outline)
				(anchor circle)
			)
			(primitives
				(gr_poly
					(pts
						(arc
							(start -0.1778 -0.2794)
							(mid -0.249642 -0.249642)
							(end -0.2794 -0.1778)
						)
						(arc
							(start -0.2794 0.1778)
							(mid -0.249642 0.249642)
							(end -0.1778 0.2794)
						)
						(arc
							(start 0.1778 0.2794)
							(mid 0.249642 0.249642)
							(end 0.2794 0.1778)
						)
						(arc
							(start 0.2794 -0.1778)
							(mid 0.249642 -0.249642)
							(end 0.1778 -0.2794)
						)
					)
					(width 0)
					(fill yes)
				)
			)
		)
		(pad "2" smd custom
			(at 0 0.4445 90)
			(size 0.1397 0.1397)
			(layers "F.Cu" "F.Mask" "F.Paste")
			(net "SEB_PEER_2A_HB")
			(options
				(clearance outline)
				(anchor circle)
			)
			(primitives
				(gr_poly
					(pts
						(arc
							(start -0.1778 -0.2794)
							(mid -0.249642 -0.249642)
							(end -0.2794 -0.1778)
						)
						(arc
							(start -0.2794 0.1778)
							(mid -0.249642 0.249642)
							(end -0.1778 0.2794)
						)
						(arc
							(start 0.1778 0.2794)
							(mid 0.249642 0.249642)
							(end 0.2794 0.1778)
						)
						(arc
							(start 0.2794 -0.1778)
							(mid 0.249642 -0.249642)
							(end 0.1778 -0.2794)
						)
					)
					(width 0)
					(fill yes)
				)
			)
		)
	)
	(footprint ""
		(layer "F.Cu")
		(at 23.614634 -156.80309 -90)
		(property "Reference" "TP16"
			(at 0 0 270)
			(layer "F.SilkS")
			(hide yes)
			(effects
				(font
					(size 1.27 1.27)
				)
			)
		)
		(property "Value" "TPAD32-GP"
			(at 0 -3.166364 270)
			(unlocked yes)
			(layer "F.Fab")
			(hide yes)
			(effects
				(font
					(size 1.016 1.016)
					(thickness 0.1524)
				)
			)
		)
		(property "Device Type" "TPAD32"
			(at 0 -4.690618 270)
			(unlocked yes)
			(layer "F.Fab")
			(hide yes)
			(effects
				(font
					(size 1.016 1.016)
					(thickness 0.1524)
				)
			)
		)
		(duplicate_pad_numbers_are_jumpers no)
		(fp_poly
			(pts
				(arc
					(start 0.7112 0)
					(mid -0.7112 0)
					(end 0.7112 0)
				)
			)
			(stroke
				(width 0)
				(type default)
			)
			(fill no)
			(layer "F.CrtYd")
		)
		(fp_poly
			(pts
				(arc
					(start 0.7112 0)
					(mid -0.7112 0)
					(end 0.7112 0)
				)
			)
			(stroke
				(width 0)
				(type default)
			)
			(fill no)
			(layer "F.Fab")
		)
		(pad "1" smd circle
			(at 0 0 270)
			(size 0.8128 0.8128)
			(layers "F.Cu" "F.Mask" "F.Paste")
			(net "NCT7904_LED")
		)
	)
	(footprint ""
		(layer "F.Cu")
		(at 40.132 -122.428)
		(property "Reference" "PR63"
			(at 0 0 0)
			(layer "F.SilkS")
			(hide yes)
			(effects
				(font
					(size 1.27 1.27)
				)
			)
		)
		(property "Value" "D002R2512F-GP"
			(at -3.228594 -1.194054 0)
			(unlocked yes)
			(layer "F.Fab")
			(hide yes)
			(effects
				(font
					(size 1.016 1.016)
					(thickness 0.1524)
				)
			)
		)
		(property "Device Type" "R2512-2H32"
			(at -3.228594 -2.718054 0)
			(unlocked yes)
			(layer "F.Fab")
			(hide yes)
			(effects
				(font
					(size 1.016 1.016)
					(thickness 0.1524)
				)
			)
		)
		(duplicate_pad_numbers_are_jumpers no)
		(fp_line
			(start -1.9685 -3.81)
			(end 1.9685 -3.81)
			(stroke
				(width 0.1524)
				(type default)
			)
			(layer "F.SilkS")
		)
		(fp_line
			(start -1.9685 3.81)
			(end -1.9685 -3.81)
			(stroke
				(width 0.1524)
				(type default)
			)
			(layer "F.SilkS")
		)
		(fp_line
			(start 1.9685 -3.81)
			(end 1.9685 3.81)
			(stroke
				(width 0.1524)
				(type default)
			)
			(layer "F.SilkS")
		)
		(fp_line
			(start 1.9685 3.81)
			(end -1.9685 3.81)
			(stroke
				(width 0.1524)
				(type default)
			)
			(layer "F.SilkS")
		)
		(fp_rect
			(start -1.5875 3.175)
			(end 1.5875 -3.175)
			(stroke
				(width 0)
				(type default)
			)
			(fill no)
			(layer "F.CrtYd")
		)
		(fp_poly
			(pts
				(xy -2.2225 3.8862) (xy -2.2225 0.00254) (xy -1.5875 0.00254) (xy -1.5875 3.175) (xy 1.5875 3.175)
				(xy 1.5875 -3.175) (xy -1.5875 -3.175) (xy -1.5875 -0.00254) (xy -2.2225 -0.00254) (xy -2.2225 -3.8862)
				(xy 2.2225 -3.8862) (xy 2.2225 3.8862)
			)
			(stroke
				(width 0)
				(type default)
			)
			(fill no)
			(layer "F.CrtYd")
		)
		(fp_rect
			(start -2.2225 3.8862)
			(end 2.2225 -3.8862)
			(stroke
				(width 0)
				(type default)
			)
			(fill no)
			(layer "F.Fab")
		)
		(pad "1" smd rect
			(at 0 -2.273808)
			(size 3.429 2.5654)
			(layers "F.Cu" "F.Mask" "F.Paste")
			(net "P12V")
		)
		(pad "2" smd rect
			(at 0 2.273808)
			(size 3.429 2.5654)
			(layers "F.Cu" "F.Mask" "F.Paste")
			(net "P12VL_NET")
		)
	)
	(footprint ""
		(layer "F.Cu")
		(at 23.4442 -222.416116 180)
		(property "Reference" "C15"
			(at 0 0 180)
			(layer "F.SilkS")
			(hide yes)
			(effects
				(font
					(size 1.27 1.27)
				)
			)
		)
		(property "Value" "SC1U16V3KX-5GP"
			(at 0 -2.8194 180)
			(unlocked yes)
			(layer "F.Fab")
			(hide yes)
			(effects
				(font
					(size 1.016 1.016)
					(thickness 0.1524)
				)
			)
		)
		(property "Device Type" "C603H36"
			(at 0 -4.3434 180)
			(unlocked yes)
			(layer "F.Fab")
			(hide yes)
			(effects
				(font
					(size 1.016 1.016)
					(thickness 0.1524)
				)
			)
		)
		(duplicate_pad_numbers_are_jumpers no)
		(fp_line
			(start 0.508 0)
			(end -0.508 0)
			(stroke
				(width 0.2032)
				(type default)
			)
			(layer "F.SilkS")
		)
		(fp_rect
			(start -0.5842 1.3335)
			(end 0.5842 -1.3335)
			(stroke
				(width 0)
				(type default)
			)
			(fill no)
			(layer "F.CrtYd")
		)
		(fp_rect
			(start -0.5842 1.3335)
			(end 0.5842 -1.3335)
			(stroke
				(width 0)
				(type default)
			)
			(fill no)
			(layer "F.Fab")
		)
		(pad "1" smd custom
			(at 0 -0.762 180)
			(size 0.2159 0.2159)
			(layers "F.Cu" "F.Mask" "F.Paste")
			(net "P3V3")
			(options
				(clearance outline)
				(anchor circle)
			)
			(primitives
				(gr_poly
					(pts
						(arc
							(start -0.3302 -0.4318)
							(mid -0.402042 -0.402042)
							(end -0.4318 -0.3302)
						)
						(arc
							(start -0.4318 0.3302)
							(mid -0.402042 0.402042)
							(end -0.3302 0.4318)
						)
						(arc
							(start 0.3302 0.4318)
							(mid 0.402042 0.402042)
							(end 0.4318 0.3302)
						)
						(arc
							(start 0.4318 -0.3302)
							(mid 0.402042 -0.402042)
							(end 0.3302 -0.4318)
						)
					)
					(width 0)
					(fill yes)
				)
			)
		)
		(pad "2" smd custom
			(at 0 0.762 180)
			(size 0.2159 0.2159)
			(layers "F.Cu" "F.Mask" "F.Paste")
			(net "GND")
			(options
				(clearance outline)
				(anchor circle)
			)
			(primitives
				(gr_poly
					(pts
						(arc
							(start -0.3302 -0.4318)
							(mid -0.402042 -0.402042)
							(end -0.4318 -0.3302)
						)
						(arc
							(start -0.4318 0.3302)
							(mid -0.402042 0.402042)
							(end -0.3302 0.4318)
						)
						(arc
							(start 0.3302 0.4318)
							(mid 0.402042 0.402042)
							(end 0.4318 0.3302)
						)
						(arc
							(start 0.4318 -0.3302)
							(mid 0.402042 -0.402042)
							(end 0.3302 -0.4318)
						)
					)
					(width 0)
					(fill yes)
				)
			)
		)
	)
	(footprint ""
		(layer "F.Cu")
		(at 11.4554 -147.3454)
		(property "Reference" "R70"
			(at 0 0 0)
			(layer "F.SilkS")
			(hide yes)
			(effects
				(font
					(size 1.27 1.27)
				)
			)
		)
		(property "Value" "27KR3F-GP"
			(at -0.0254 -2.5146 0)
			(unlocked yes)
			(layer "F.Fab")
			(hide yes)
			(effects
				(font
					(size 1.016 1.016)
					(thickness 0.1524)
				)
			)
		)
		(property "Device Type" "R603H22"
			(at -0.0254 -4.0386 0)
			(unlocked yes)
			(layer "F.Fab")
			(hide yes)
			(effects
				(font
					(size 1.016 1.016)
					(thickness 0.1524)
				)
			)
		)
		(duplicate_pad_numbers_are_jumpers no)
		(fp_line
			(start -0.4826 0)
			(end -0.2032 0)
			(stroke
				(width 0.2032)
				(type default)
			)
			(layer "F.SilkS")
		)
		(fp_line
			(start 0.2032 0)
			(end 0.4826 0)
			(stroke
				(width 0.2032)
				(type default)
			)
			(layer "F.SilkS")
		)
		(fp_rect
			(start -0.5842 1.3335)
			(end 0.5842 -1.3335)
			(stroke
				(width 0)
				(type default)
			)
			(fill no)
			(layer "F.CrtYd")
		)
		(fp_rect
			(start -0.5842 1.3335)
			(end 0.5842 -1.3335)
			(stroke
				(width 0)
				(type default)
			)
			(fill no)
			(layer "F.Fab")
		)
		(pad "1" smd custom
			(at 0 -0.762)
			(size 0.2159 0.2159)
			(layers "F.Cu" "F.Mask" "F.Paste")
			(net "FAN_TACH10")
			(options
				(clearance outline)
				(anchor circle)
			)
			(primitives
				(gr_poly
					(pts
						(arc
							(start -0.3302 -0.4318)
							(mid -0.402042 -0.402042)
							(end -0.4318 -0.3302)
						)
						(arc
							(start -0.4318 0.3302)
							(mid -0.402042 0.402042)
							(end -0.3302 0.4318)
						)
						(arc
							(start 0.3302 0.4318)
							(mid 0.402042 0.402042)
							(end 0.4318 0.3302)
						)
						(arc
							(start 0.4318 -0.3302)
							(mid 0.402042 -0.402042)
							(end 0.3302 -0.4318)
						)
					)
					(width 0)
					(fill yes)
				)
			)
		)
		(pad "2" smd custom
			(at 0 0.762)
			(size 0.2159 0.2159)
			(layers "F.Cu" "F.Mask" "F.Paste")
			(net "FANIN_10")
			(options
				(clearance outline)
				(anchor circle)
			)
			(primitives
				(gr_poly
					(pts
						(arc
							(start -0.3302 -0.4318)
							(mid -0.402042 -0.402042)
							(end -0.4318 -0.3302)
						)
						(arc
							(start -0.4318 0.3302)
							(mid -0.402042 0.402042)
							(end -0.3302 0.4318)
						)
						(arc
							(start 0.3302 0.4318)
							(mid 0.402042 0.402042)
							(end 0.4318 0.3302)
						)
						(arc
							(start 0.4318 -0.3302)
							(mid 0.402042 -0.402042)
							(end 0.3302 -0.4318)
						)
					)
					(width 0)
					(fill yes)
				)
			)
		)
	)
	(footprint ""
		(layer "F.Cu")
		(at 23.622 -368.554 90)
		(property "Reference" "PR35"
			(at 0 0 90)
			(layer "F.SilkS")
			(hide yes)
			(effects
				(font
					(size 1.27 1.27)
				)
			)
		)
		(property "Value" "4K7R2J-2-GP"
			(at 0.064008 -3.993896 90)
			(unlocked yes)
			(layer "F.Fab")
			(hide yes)
			(effects
				(font
					(size 1.016 1.016)
					(thickness 0.1524)
				)
			)
		)
		(property "Device Type" "R402H16"
			(at 0.064008 -5.517896 90)
			(unlocked yes)
			(layer "F.Fab")
			(hide yes)
			(effects
				(font
					(size 1.016 1.016)
					(thickness 0.1524)
				)
			)
		)
		(duplicate_pad_numbers_are_jumpers no)
		(fp_line
			(start 0.508 -0.9398)
			(end -0.508 -0.9398)
			(stroke
				(width 0.1524)
				(type default)
			)
			(layer "F.SilkS")
		)
		(fp_line
			(start -0.508 -0.9398)
			(end -0.508 0.9398)
			(stroke
				(width 0.1524)
				(type default)
			)
			(layer "F.SilkS")
		)
		(fp_rect
			(start -0.508 0.9398)
			(end 0.508 -0.9398)
			(stroke
				(width 0)
				(type default)
			)
			(fill no)
			(layer "F.CrtYd")
		)
		(fp_rect
			(start -0.508 0.9398)
			(end 0.508 -0.9398)
			(stroke
				(width 0)
				(type default)
			)
			(fill no)
			(layer "F.Fab")
		)
		(pad "1" smd custom
			(at 0 -0.4445 90)
			(size 0.1397 0.1397)
			(layers "F.Cu" "F.Mask" "F.Paste")
			(net "ADM1276_UV")
			(options
				(clearance outline)
				(anchor circle)
			)
			(primitives
				(gr_poly
					(pts
						(arc
							(start -0.1778 -0.2794)
							(mid -0.249642 -0.249642)
							(end -0.2794 -0.1778)
						)
						(arc
							(start -0.2794 0.1778)
							(mid -0.249642 0.249642)
							(end -0.1778 0.2794)
						)
						(arc
							(start 0.1778 0.2794)
							(mid 0.249642 0.249642)
							(end 0.2794 0.1778)
						)
						(arc
							(start 0.2794 -0.1778)
							(mid 0.249642 -0.249642)
							(end 0.1778 -0.2794)
						)
					)
					(width 0)
					(fill yes)
				)
			)
		)
		(pad "2" smd custom
			(at 0 0.4445 90)
			(size 0.1397 0.1397)
			(layers "F.Cu" "F.Mask" "F.Paste")
			(net "ADM1276_VCAP")
			(options
				(clearance outline)
				(anchor circle)
			)
			(primitives
				(gr_poly
					(pts
						(arc
							(start -0.1778 -0.2794)
							(mid -0.249642 -0.249642)
							(end -0.2794 -0.1778)
						)
						(arc
							(start -0.2794 0.1778)
							(mid -0.249642 0.249642)
							(end -0.1778 0.2794)
						)
						(arc
							(start 0.1778 0.2794)
							(mid 0.249642 0.249642)
							(end 0.2794 0.1778)
						)
						(arc
							(start 0.2794 -0.1778)
							(mid 0.249642 -0.249642)
							(end 0.1778 -0.2794)
						)
					)
					(width 0)
					(fill yes)
				)
			)
		)
	)
	(footprint ""
		(layer "F.Cu")
		(at 18.3388 -179.8828 180)
		(property "Reference" "C55"
			(at 0 0 180)
			(layer "F.SilkS")
			(hide yes)
			(effects
				(font
					(size 1.27 1.27)
				)
			)
		)
		(property "Value" "SC1U16V3KX-5GP"
			(at 0 -2.8194 180)
			(unlocked yes)
			(layer "F.Fab")
			(hide yes)
			(effects
				(font
					(size 1.016 1.016)
					(thickness 0.1524)
				)
			)
		)
		(property "Device Type" "C603H36"
			(at 0 -4.3434 180)
			(unlocked yes)
			(layer "F.Fab")
			(hide yes)
			(effects
				(font
					(size 1.016 1.016)
					(thickness 0.1524)
				)
			)
		)
		(duplicate_pad_numbers_are_jumpers no)
		(fp_line
			(start 0.508 0)
			(end -0.508 0)
			(stroke
				(width 0.2032)
				(type default)
			)
			(layer "F.SilkS")
		)
		(fp_rect
			(start -0.5842 1.3335)
			(end 0.5842 -1.3335)
			(stroke
				(width 0)
				(type default)
			)
			(fill no)
			(layer "F.CrtYd")
		)
		(fp_rect
			(start -0.5842 1.3335)
			(end 0.5842 -1.3335)
			(stroke
				(width 0)
				(type default)
			)
			(fill no)
			(layer "F.Fab")
		)
		(pad "1" smd custom
			(at 0 -0.762 180)
			(size 0.2159 0.2159)
			(layers "F.Cu" "F.Mask" "F.Paste")
			(net "P3V3")
			(options
				(clearance outline)
				(anchor circle)
			)
			(primitives
				(gr_poly
					(pts
						(arc
							(start -0.3302 -0.4318)
							(mid -0.402042 -0.402042)
							(end -0.4318 -0.3302)
						)
						(arc
							(start -0.4318 0.3302)
							(mid -0.402042 0.402042)
							(end -0.3302 0.4318)
						)
						(arc
							(start 0.3302 0.4318)
							(mid 0.402042 0.402042)
							(end 0.4318 0.3302)
						)
						(arc
							(start 0.4318 -0.3302)
							(mid 0.402042 -0.402042)
							(end 0.3302 -0.4318)
						)
					)
					(width 0)
					(fill yes)
				)
			)
		)
		(pad "2" smd custom
			(at 0 0.762 180)
			(size 0.2159 0.2159)
			(layers "F.Cu" "F.Mask" "F.Paste")
			(net "GND")
			(options
				(clearance outline)
				(anchor circle)
			)
			(primitives
				(gr_poly
					(pts
						(arc
							(start -0.3302 -0.4318)
							(mid -0.402042 -0.402042)
							(end -0.4318 -0.3302)
						)
						(arc
							(start -0.4318 0.3302)
							(mid -0.402042 0.402042)
							(end -0.3302 0.4318)
						)
						(arc
							(start 0.3302 0.4318)
							(mid 0.402042 0.402042)
							(end 0.4318 0.3302)
						)
						(arc
							(start 0.4318 -0.3302)
							(mid 0.402042 -0.402042)
							(end 0.3302 -0.4318)
						)
					)
					(width 0)
					(fill yes)
				)
			)
		)
	)
	(footprint ""
		(layer "F.Cu")
		(at 8.4836 -62.7126 -90)
		(property "Reference" "R122"
			(at 0 0 270)
			(layer "F.SilkS")
			(hide yes)
			(effects
				(font
					(size 1.27 1.27)
				)
			)
		)
		(property "Value" "1K8R6J-GP"
			(at -0.0508 -4.8514 270)
			(unlocked yes)
			(layer "F.Fab")
			(hide yes)
			(effects
				(font
					(size 1.016 1.016)
					(thickness 0.1524)
				)
			)
		)
		(property "Device Type" "R1206H28"
			(at 0 -6.3754 270)
			(unlocked yes)
			(layer "F.Fab")
			(hide yes)
			(effects
				(font
					(size 1.016 1.016)
					(thickness 0.1524)
				)
			)
		)
		(duplicate_pad_numbers_are_jumpers no)
		(fp_line
			(start -1.016 2.2352)
			(end -1.016 -2.2352)
			(stroke
				(width 0.1524)
				(type default)
			)
			(layer "F.SilkS")
		)
		(fp_line
			(start 1.016 2.2352)
			(end -1.016 2.2352)
			(stroke
				(width 0.1524)
				(type default)
			)
			(layer "F.SilkS")
		)
		(fp_line
			(start -1.016 -2.2352)
			(end 1.016 -2.2352)
			(stroke
				(width 0.1524)
				(type default)
			)
			(layer "F.SilkS")
		)
		(fp_line
			(start 1.016 -2.2352)
			(end 1.016 2.2352)
			(stroke
				(width 0.1524)
				(type default)
			)
			(layer "F.SilkS")
		)
		(fp_rect
			(start -1.0922 2.3114)
			(end 1.0922 -2.3114)
			(stroke
				(width 0)
				(type default)
			)
			(fill no)
			(layer "F.CrtYd")
		)
		(fp_poly
			(pts
				(xy -1.0922 -2.3114) (xy 1.0922 -2.3114) (xy 1.0922 2.3114) (xy -1.0922 2.3114)
			)
			(stroke
				(width 0)
				(type default)
			)
			(fill no)
			(layer "F.Fab")
		)
		(pad "1" smd rect
			(at 0 -1.397 270)
			(size 1.651 1.27)
			(layers "F.Cu" "F.Mask" "F.Paste")
			(net "P12V")
		)
		(pad "2" smd rect
			(at 0 1.397 270)
			(size 1.651 1.27)
			(layers "F.Cu" "F.Mask" "F.Paste")
			(net "LED_DR_LED5_BLUE")
		)
	)
	(footprint ""
		(layer "F.Cu")
		(at 23.63851 -151.325834)
		(property "Reference" "R12"
			(at 0 0 0)
			(layer "F.SilkS")
			(hide yes)
			(effects
				(font
					(size 1.27 1.27)
				)
			)
		)
		(property "Value" "4K7R2F-GP"
			(at 0.064008 -3.993896 0)
			(unlocked yes)
			(layer "F.Fab")
			(hide yes)
			(effects
				(font
					(size 1.016 1.016)
					(thickness 0.1524)
				)
			)
		)
		(property "Device Type" "R402H16"
			(at 0.064008 -5.517896 0)
			(unlocked yes)
			(layer "F.Fab")
			(hide yes)
			(effects
				(font
					(size 1.016 1.016)
					(thickness 0.1524)
				)
			)
		)
		(duplicate_pad_numbers_are_jumpers no)
		(fp_line
			(start -0.508 -0.9398)
			(end -0.508 0.9398)
			(stroke
				(width 0.1524)
				(type default)
			)
			(layer "F.SilkS")
		)
		(fp_line
			(start 0.508 -0.9398)
			(end -0.508 -0.9398)
			(stroke
				(width 0.1524)
				(type default)
			)
			(layer "F.SilkS")
		)
		(fp_rect
			(start -0.508 0.9398)
			(end 0.508 -0.9398)
			(stroke
				(width 0)
				(type default)
			)
			(fill no)
			(layer "F.CrtYd")
		)
		(fp_rect
			(start -0.508 0.9398)
			(end 0.508 -0.9398)
			(stroke
				(width 0)
				(type default)
			)
			(fill no)
			(layer "F.Fab")
		)
		(pad "1" smd custom
			(at 0 -0.4445)
			(size 0.1397 0.1397)
			(layers "F.Cu" "F.Mask" "F.Paste")
			(net "NCT7904_RESET")
			(options
				(clearance outline)
				(anchor circle)
			)
			(primitives
				(gr_poly
					(pts
						(arc
							(start -0.1778 -0.2794)
							(mid -0.249642 -0.249642)
							(end -0.2794 -0.1778)
						)
						(arc
							(start -0.2794 0.1778)
							(mid -0.249642 0.249642)
							(end -0.1778 0.2794)
						)
						(arc
							(start 0.1778 0.2794)
							(mid 0.249642 0.249642)
							(end 0.2794 0.1778)
						)
						(arc
							(start 0.2794 -0.1778)
							(mid 0.249642 -0.249642)
							(end 0.1778 -0.2794)
						)
					)
					(width 0)
					(fill yes)
				)
			)
		)
		(pad "2" smd custom
			(at 0 0.4445)
			(size 0.1397 0.1397)
			(layers "F.Cu" "F.Mask" "F.Paste")
			(net "P3V3")
			(options
				(clearance outline)
				(anchor circle)
			)
			(primitives
				(gr_poly
					(pts
						(arc
							(start -0.1778 -0.2794)
							(mid -0.249642 -0.249642)
							(end -0.2794 -0.1778)
						)
						(arc
							(start -0.2794 0.1778)
							(mid -0.249642 0.249642)
							(end -0.1778 0.2794)
						)
						(arc
							(start 0.1778 0.2794)
							(mid 0.249642 0.249642)
							(end 0.2794 0.1778)
						)
						(arc
							(start 0.2794 -0.1778)
							(mid 0.249642 -0.249642)
							(end 0.1778 -0.2794)
						)
					)
					(width 0)
					(fill yes)
				)
			)
		)
	)
	(footprint ""
		(layer "F.Cu")
		(at 27.7876 -150.7998 90)
		(property "Reference" "C7"
			(at 0 0 90)
			(layer "F.SilkS")
			(hide yes)
			(effects
				(font
					(size 1.27 1.27)
				)
			)
		)
		(property "Value" "SC2200P50V2KX-2GP"
			(at 1.1811 -2.7051 90)
			(unlocked yes)
			(layer "F.Fab")
			(hide yes)
			(effects
				(font
					(size 1.016 1.016)
					(thickness 0.1524)
				)
			)
		)
		(property "Device Type" "C402H22"
			(at 1.1811 -4.2291 90)
			(unlocked yes)
			(layer "F.Fab")
			(hide yes)
			(effects
				(font
					(size 1.016 1.016)
					(thickness 0.1524)
				)
			)
		)
		(duplicate_pad_numbers_are_jumpers no)
		(fp_rect
			(start -0.4318 0.9525)
			(end 0.4318 -0.9525)
			(stroke
				(width 0)
				(type default)
			)
			(fill no)
			(layer "F.CrtYd")
		)
		(fp_rect
			(start -0.4318 0.9525)
			(end 0.4318 -0.9525)
			(stroke
				(width 0)
				(type default)
			)
			(fill no)
			(layer "F.Fab")
		)
		(pad "1" smd custom
			(at 0 -0.4445 90)
			(size 0.1524 0.1524)
			(layers "F.Cu" "F.Mask" "F.Paste")
			(net "NCT7904_D1+")
			(options
				(clearance outline)
				(anchor circle)
			)
			(primitives
				(gr_poly
					(pts
						(arc
							(start 0.3048 -0.2032)
							(mid 0.275042 -0.275042)
							(end 0.2032 -0.3048)
						)
						(arc
							(start -0.2032 -0.3048)
							(mid -0.275042 -0.275042)
							(end -0.3048 -0.2032)
						)
						(arc
							(start -0.3048 0.2032)
							(mid -0.275042 0.275042)
							(end -0.2032 0.3048)
						)
						(arc
							(start 0.2032 0.3048)
							(mid 0.275042 0.275042)
							(end 0.3048 0.2032)
						)
					)
					(width 0)
					(fill yes)
				)
			)
		)
		(pad "2" smd custom
			(at 0 0.4445 90)
			(size 0.1524 0.1524)
			(layers "F.Cu" "F.Mask" "F.Paste")
			(net "NCT7904_D1-")
			(options
				(clearance outline)
				(anchor circle)
			)
			(primitives
				(gr_poly
					(pts
						(arc
							(start 0.3048 -0.2032)
							(mid 0.275042 -0.275042)
							(end 0.2032 -0.3048)
						)
						(arc
							(start -0.2032 -0.3048)
							(mid -0.275042 -0.275042)
							(end -0.3048 -0.2032)
						)
						(arc
							(start -0.3048 0.2032)
							(mid -0.275042 0.275042)
							(end -0.2032 0.3048)
						)
						(arc
							(start 0.2032 0.3048)
							(mid 0.275042 0.275042)
							(end 0.3048 0.2032)
						)
					)
					(width 0)
					(fill yes)
				)
			)
		)
	)
	(footprint ""
		(layer "F.Cu")
		(at 34.29 -254.381 180)
		(property "Reference" "R106"
			(at 0 0 180)
			(layer "F.SilkS")
			(hide yes)
			(effects
				(font
					(size 1.27 1.27)
				)
			)
		)
		(property "Value" "0R2J-2-GP"
			(at 0.064008 -3.993896 180)
			(unlocked yes)
			(layer "F.Fab")
			(hide yes)
			(effects
				(font
					(size 1.016 1.016)
					(thickness 0.1524)
				)
			)
		)
		(property "Device Type" "R402H16"
			(at 0.064008 -5.517896 180)
			(unlocked yes)
			(layer "F.Fab")
			(hide yes)
			(effects
				(font
					(size 1.016 1.016)
					(thickness 0.1524)
				)
			)
		)
		(duplicate_pad_numbers_are_jumpers no)
		(fp_line
			(start 0.508 -0.9398)
			(end -0.508 -0.9398)
			(stroke
				(width 0.1524)
				(type default)
			)
			(layer "F.SilkS")
		)
		(fp_line
			(start -0.508 -0.9398)
			(end -0.508 0.9398)
			(stroke
				(width 0.1524)
				(type default)
			)
			(layer "F.SilkS")
		)
		(fp_rect
			(start -0.508 0.9398)
			(end 0.508 -0.9398)
			(stroke
				(width 0)
				(type default)
			)
			(fill no)
			(layer "F.CrtYd")
		)
		(fp_rect
			(start -0.508 0.9398)
			(end 0.508 -0.9398)
			(stroke
				(width 0)
				(type default)
			)
			(fill no)
			(layer "F.Fab")
		)
		(pad "1" smd custom
			(at 0 -0.4445 180)
			(size 0.1397 0.1397)
			(layers "F.Cu" "F.Mask" "F.Paste")
			(net "I2C_C_SDA_LEDDRV")
			(options
				(clearance outline)
				(anchor circle)
			)
			(primitives
				(gr_poly
					(pts
						(arc
							(start -0.1778 -0.2794)
							(mid -0.249642 -0.249642)
							(end -0.2794 -0.1778)
						)
						(arc
							(start -0.2794 0.1778)
							(mid -0.249642 0.249642)
							(end -0.1778 0.2794)
						)
						(arc
							(start 0.1778 0.2794)
							(mid 0.249642 0.249642)
							(end 0.2794 0.1778)
						)
						(arc
							(start 0.2794 -0.1778)
							(mid 0.249642 -0.249642)
							(end 0.1778 -0.2794)
						)
					)
					(width 0)
					(fill yes)
				)
			)
		)
		(pad "2" smd custom
			(at 0 0.4445 180)
			(size 0.1397 0.1397)
			(layers "F.Cu" "F.Mask" "F.Paste")
			(net "I2C_C_SDA")
			(options
				(clearance outline)
				(anchor circle)
			)
			(primitives
				(gr_poly
					(pts
						(arc
							(start -0.1778 -0.2794)
							(mid -0.249642 -0.249642)
							(end -0.2794 -0.1778)
						)
						(arc
							(start -0.2794 0.1778)
							(mid -0.249642 0.249642)
							(end -0.1778 0.2794)
						)
						(arc
							(start 0.1778 0.2794)
							(mid 0.249642 0.249642)
							(end 0.2794 0.1778)
						)
						(arc
							(start 0.2794 -0.1778)
							(mid 0.249642 -0.249642)
							(end 0.1778 -0.2794)
						)
					)
					(width 0)
					(fill yes)
				)
			)
		)
	)
	(footprint ""
		(layer "F.Cu")
		(at 29.6672 -149.071584 180)
		(property "Reference" "R16"
			(at 0 0 180)
			(layer "F.SilkS")
			(hide yes)
			(effects
				(font
					(size 1.27 1.27)
				)
			)
		)
		(property "Value" "110KR2F-L-GP"
			(at 0.064008 -3.993896 180)
			(unlocked yes)
			(layer "F.Fab")
			(hide yes)
			(effects
				(font
					(size 1.016 1.016)
					(thickness 0.1524)
				)
			)
		)
		(property "Device Type" "R402H16"
			(at 0.064008 -5.517896 180)
			(unlocked yes)
			(layer "F.Fab")
			(hide yes)
			(effects
				(font
					(size 1.016 1.016)
					(thickness 0.1524)
				)
			)
		)
		(duplicate_pad_numbers_are_jumpers no)
		(fp_line
			(start 0.508 -0.9398)
			(end -0.508 -0.9398)
			(stroke
				(width 0.1524)
				(type default)
			)
			(layer "F.SilkS")
		)
		(fp_line
			(start -0.508 -0.9398)
			(end -0.508 0.9398)
			(stroke
				(width 0.1524)
				(type default)
			)
			(layer "F.SilkS")
		)
		(fp_rect
			(start -0.508 0.9398)
			(end 0.508 -0.9398)
			(stroke
				(width 0)
				(type default)
			)
			(fill no)
			(layer "F.CrtYd")
		)
		(fp_rect
			(start -0.508 0.9398)
			(end 0.508 -0.9398)
			(stroke
				(width 0)
				(type default)
			)
			(fill no)
			(layer "F.Fab")
		)
		(pad "1" smd custom
			(at 0 -0.4445 180)
			(size 0.1397 0.1397)
			(layers "F.Cu" "F.Mask" "F.Paste")
			(net "P12VL")
			(options
				(clearance outline)
				(anchor circle)
			)
			(primitives
				(gr_poly
					(pts
						(arc
							(start -0.1778 -0.2794)
							(mid -0.249642 -0.249642)
							(end -0.2794 -0.1778)
						)
						(arc
							(start -0.2794 0.1778)
							(mid -0.249642 0.249642)
							(end -0.1778 0.2794)
						)
						(arc
							(start 0.1778 0.2794)
							(mid 0.249642 0.249642)
							(end 0.2794 0.1778)
						)
						(arc
							(start 0.2794 -0.1778)
							(mid 0.249642 -0.249642)
							(end 0.1778 -0.2794)
						)
					)
					(width 0)
					(fill yes)
				)
			)
		)
		(pad "2" smd custom
			(at 0 0.4445 180)
			(size 0.1397 0.1397)
			(layers "F.Cu" "F.Mask" "F.Paste")
			(net "NCT7904_VSEN6")
			(options
				(clearance outline)
				(anchor circle)
			)
			(primitives
				(gr_poly
					(pts
						(arc
							(start -0.1778 -0.2794)
							(mid -0.249642 -0.249642)
							(end -0.2794 -0.1778)
						)
						(arc
							(start -0.2794 0.1778)
							(mid -0.249642 0.249642)
							(end -0.1778 0.2794)
						)
						(arc
							(start 0.1778 0.2794)
							(mid 0.249642 0.249642)
							(end 0.2794 0.1778)
						)
						(arc
							(start 0.2794 -0.1778)
							(mid 0.249642 -0.249642)
							(end 0.1778 -0.2794)
						)
					)
					(width 0)
					(fill yes)
				)
			)
		)
	)
	(footprint ""
		(layer "F.Cu")
		(at 7.3406 -174.7774 180)
		(property "Reference" "C52"
			(at 0 0 180)
			(layer "F.SilkS")
			(hide yes)
			(effects
				(font
					(size 1.27 1.27)
				)
			)
		)
		(property "Value" "SCD1U50V3KX-GP"
			(at 0 -2.8194 180)
			(unlocked yes)
			(layer "F.Fab")
			(hide yes)
			(effects
				(font
					(size 1.016 1.016)
					(thickness 0.1524)
				)
			)
		)
		(property "Device Type" "C603H36"
			(at 0 -4.3434 180)
			(unlocked yes)
			(layer "F.Fab")
			(hide yes)
			(effects
				(font
					(size 1.016 1.016)
					(thickness 0.1524)
				)
			)
		)
		(duplicate_pad_numbers_are_jumpers no)
		(fp_line
			(start 0.508 0)
			(end -0.508 0)
			(stroke
				(width 0.2032)
				(type default)
			)
			(layer "F.SilkS")
		)
		(fp_rect
			(start -0.5842 1.3335)
			(end 0.5842 -1.3335)
			(stroke
				(width 0)
				(type default)
			)
			(fill no)
			(layer "F.CrtYd")
		)
		(fp_rect
			(start -0.5842 1.3335)
			(end 0.5842 -1.3335)
			(stroke
				(width 0)
				(type default)
			)
			(fill no)
			(layer "F.Fab")
		)
		(pad "1" smd custom
			(at 0 -0.762 180)
			(size 0.2159 0.2159)
			(layers "F.Cu" "F.Mask" "F.Paste")
			(net "P3V3")
			(options
				(clearance outline)
				(anchor circle)
			)
			(primitives
				(gr_poly
					(pts
						(arc
							(start -0.3302 -0.4318)
							(mid -0.402042 -0.402042)
							(end -0.4318 -0.3302)
						)
						(arc
							(start -0.4318 0.3302)
							(mid -0.402042 0.402042)
							(end -0.3302 0.4318)
						)
						(arc
							(start 0.3302 0.4318)
							(mid 0.402042 0.402042)
							(end 0.4318 0.3302)
						)
						(arc
							(start 0.4318 -0.3302)
							(mid 0.402042 -0.402042)
							(end 0.3302 -0.4318)
						)
					)
					(width 0)
					(fill yes)
				)
			)
		)
		(pad "2" smd custom
			(at 0 0.762 180)
			(size 0.2159 0.2159)
			(layers "F.Cu" "F.Mask" "F.Paste")
			(net "GND")
			(options
				(clearance outline)
				(anchor circle)
			)
			(primitives
				(gr_poly
					(pts
						(arc
							(start -0.3302 -0.4318)
							(mid -0.402042 -0.402042)
							(end -0.4318 -0.3302)
						)
						(arc
							(start -0.4318 0.3302)
							(mid -0.402042 0.402042)
							(end -0.3302 0.4318)
						)
						(arc
							(start 0.3302 0.4318)
							(mid 0.402042 0.402042)
							(end 0.4318 0.3302)
						)
						(arc
							(start 0.4318 -0.3302)
							(mid 0.402042 -0.402042)
							(end 0.3302 -0.4318)
						)
					)
					(width 0)
					(fill yes)
				)
			)
		)
	)
	(footprint ""
		(layer "F.Cu")
		(at 26.289 -248.158 180)
		(property "Reference" "PC42"
			(at 0 0 180)
			(layer "F.SilkS")
			(hide yes)
			(effects
				(font
					(size 1.27 1.27)
				)
			)
		)
		(property "Value" "SC22P50V3JN-DLGP"
			(at 0 -2.8194 180)
			(unlocked yes)
			(layer "F.Fab")
			(hide yes)
			(effects
				(font
					(size 1.016 1.016)
					(thickness 0.1524)
				)
			)
		)
		(property "Device Type" "C603H36"
			(at 0 -4.3434 180)
			(unlocked yes)
			(layer "F.Fab")
			(hide yes)
			(effects
				(font
					(size 1.016 1.016)
					(thickness 0.1524)
				)
			)
		)
		(duplicate_pad_numbers_are_jumpers no)
		(fp_line
			(start 0.508 0)
			(end -0.508 0)
			(stroke
				(width 0.2032)
				(type default)
			)
			(layer "F.SilkS")
		)
		(fp_rect
			(start -0.5842 1.3335)
			(end 0.5842 -1.3335)
			(stroke
				(width 0)
				(type default)
			)
			(fill no)
			(layer "F.CrtYd")
		)
		(fp_rect
			(start -0.5842 1.3335)
			(end 0.5842 -1.3335)
			(stroke
				(width 0)
				(type default)
			)
			(fill no)
			(layer "F.Fab")
		)
		(pad "1" smd custom
			(at 0 -0.762 180)
			(size 0.2159 0.2159)
			(layers "F.Cu" "F.Mask" "F.Paste")
			(net "P3V3_LX_COPPER")
			(options
				(clearance outline)
				(anchor circle)
			)
			(primitives
				(gr_poly
					(pts
						(arc
							(start -0.3302 -0.4318)
							(mid -0.402042 -0.402042)
							(end -0.4318 -0.3302)
						)
						(arc
							(start -0.4318 0.3302)
							(mid -0.402042 0.402042)
							(end -0.3302 0.4318)
						)
						(arc
							(start 0.3302 0.4318)
							(mid 0.402042 0.402042)
							(end 0.4318 0.3302)
						)
						(arc
							(start 0.4318 -0.3302)
							(mid 0.402042 -0.402042)
							(end 0.3302 -0.4318)
						)
					)
					(width 0)
					(fill yes)
				)
			)
		)
		(pad "2" smd custom
			(at 0 0.762 180)
			(size 0.2159 0.2159)
			(layers "F.Cu" "F.Mask" "F.Paste")
			(net "P3V3_FB")
			(options
				(clearance outline)
				(anchor circle)
			)
			(primitives
				(gr_poly
					(pts
						(arc
							(start -0.3302 -0.4318)
							(mid -0.402042 -0.402042)
							(end -0.4318 -0.3302)
						)
						(arc
							(start -0.4318 0.3302)
							(mid -0.402042 0.402042)
							(end -0.3302 0.4318)
						)
						(arc
							(start 0.3302 0.4318)
							(mid 0.402042 0.402042)
							(end 0.4318 0.3302)
						)
						(arc
							(start 0.4318 -0.3302)
							(mid 0.402042 -0.402042)
							(end 0.3302 -0.4318)
						)
					)
					(width 0)
					(fill yes)
				)
			)
		)
	)
	(footprint ""
		(layer "F.Cu")
		(at 44.704 -122.428)
		(property "Reference" "PR62"
			(at 0 0 0)
			(layer "F.SilkS")
			(hide yes)
			(effects
				(font
					(size 1.27 1.27)
				)
			)
		)
		(property "Value" "D002R2512F-GP"
			(at -3.228594 -1.194054 0)
			(unlocked yes)
			(layer "F.Fab")
			(hide yes)
			(effects
				(font
					(size 1.016 1.016)
					(thickness 0.1524)
				)
			)
		)
		(property "Device Type" "R2512-2H32"
			(at -3.228594 -2.718054 0)
			(unlocked yes)
			(layer "F.Fab")
			(hide yes)
			(effects
				(font
					(size 1.016 1.016)
					(thickness 0.1524)
				)
			)
		)
		(duplicate_pad_numbers_are_jumpers no)
		(fp_line
			(start -1.9685 -3.81)
			(end 1.9685 -3.81)
			(stroke
				(width 0.1524)
				(type default)
			)
			(layer "F.SilkS")
		)
		(fp_line
			(start -1.9685 3.81)
			(end -1.9685 -3.81)
			(stroke
				(width 0.1524)
				(type default)
			)
			(layer "F.SilkS")
		)
		(fp_line
			(start 1.9685 -3.81)
			(end 1.9685 3.81)
			(stroke
				(width 0.1524)
				(type default)
			)
			(layer "F.SilkS")
		)
		(fp_line
			(start 1.9685 3.81)
			(end -1.9685 3.81)
			(stroke
				(width 0.1524)
				(type default)
			)
			(layer "F.SilkS")
		)
		(fp_rect
			(start -1.5875 3.175)
			(end 1.5875 -3.175)
			(stroke
				(width 0)
				(type default)
			)
			(fill no)
			(layer "F.CrtYd")
		)
		(fp_poly
			(pts
				(xy -2.2225 3.8862) (xy -2.2225 0.00254) (xy -1.5875 0.00254) (xy -1.5875 3.175) (xy 1.5875 3.175)
				(xy 1.5875 -3.175) (xy -1.5875 -3.175) (xy -1.5875 -0.00254) (xy -2.2225 -0.00254) (xy -2.2225 -3.8862)
				(xy 2.2225 -3.8862) (xy 2.2225 3.8862)
			)
			(stroke
				(width 0)
				(type default)
			)
			(fill no)
			(layer "F.CrtYd")
		)
		(fp_rect
			(start -2.2225 3.8862)
			(end 2.2225 -3.8862)
			(stroke
				(width 0)
				(type default)
			)
			(fill no)
			(layer "F.Fab")
		)
		(pad "1" smd rect
			(at 0 -2.273808)
			(size 3.429 2.5654)
			(layers "F.Cu" "F.Mask" "F.Paste")
			(net "P12V")
		)
		(pad "2" smd rect
			(at 0 2.273808)
			(size 3.429 2.5654)
			(layers "F.Cu" "F.Mask" "F.Paste")
			(net "P12VL_NET")
		)
	)
	(footprint ""
		(layer "F.Cu")
		(at 25.5016 -139.5984 -90)
		(property "Reference" "PR99"
			(at 0 0 270)
			(layer "F.SilkS")
			(hide yes)
			(effects
				(font
					(size 1.27 1.27)
				)
			)
		)
		(property "Value" "100R2F-L1-GP-U"
			(at 0.064008 -3.993896 270)
			(unlocked yes)
			(layer "F.Fab")
			(hide yes)
			(effects
				(font
					(size 1.016 1.016)
					(thickness 0.1524)
				)
			)
		)
		(property "Device Type" "R402H14"
			(at 0.064008 -5.517896 270)
			(unlocked yes)
			(layer "F.Fab")
			(hide yes)
			(effects
				(font
					(size 1.016 1.016)
					(thickness 0.1524)
				)
			)
		)
		(duplicate_pad_numbers_are_jumpers no)
		(fp_line
			(start -0.508 -0.9398)
			(end -0.508 0.9398)
			(stroke
				(width 0.1524)
				(type default)
			)
			(layer "F.SilkS")
		)
		(fp_line
			(start 0.508 -0.9398)
			(end -0.508 -0.9398)
			(stroke
				(width 0.1524)
				(type default)
			)
			(layer "F.SilkS")
		)
		(fp_rect
			(start -0.508 0.9398)
			(end 0.508 -0.9398)
			(stroke
				(width 0)
				(type default)
			)
			(fill no)
			(layer "F.CrtYd")
		)
		(fp_rect
			(start -0.508 0.9398)
			(end 0.508 -0.9398)
			(stroke
				(width 0)
				(type default)
			)
			(fill no)
			(layer "F.Fab")
		)
		(pad "1" smd custom
			(at 0 -0.4445 270)
			(size 0.1397 0.1397)
			(layers "F.Cu" "F.Mask" "F.Paste")
			(net "P12VU_2490_GATE")
			(options
				(clearance outline)
				(anchor circle)
			)
			(primitives
				(gr_poly
					(pts
						(arc
							(start -0.1778 -0.2794)
							(mid -0.249642 -0.249642)
							(end -0.2794 -0.1778)
						)
						(arc
							(start -0.2794 0.1778)
							(mid -0.249642 0.249642)
							(end -0.1778 0.2794)
						)
						(arc
							(start 0.1778 0.2794)
							(mid 0.249642 0.249642)
							(end 0.2794 0.1778)
						)
						(arc
							(start 0.2794 -0.1778)
							(mid 0.249642 -0.249642)
							(end 0.1778 -0.2794)
						)
					)
					(width 0)
					(fill yes)
				)
			)
		)
		(pad "2" smd custom
			(at 0 0.4445 270)
			(size 0.1397 0.1397)
			(layers "F.Cu" "F.Mask" "F.Paste")
			(net "P12VU_2490_RC")
			(options
				(clearance outline)
				(anchor circle)
			)
			(primitives
				(gr_poly
					(pts
						(arc
							(start -0.1778 -0.2794)
							(mid -0.249642 -0.249642)
							(end -0.2794 -0.1778)
						)
						(arc
							(start -0.2794 0.1778)
							(mid -0.249642 0.249642)
							(end -0.1778 0.2794)
						)
						(arc
							(start 0.1778 0.2794)
							(mid 0.249642 0.249642)
							(end 0.2794 0.1778)
						)
						(arc
							(start 0.2794 -0.1778)
							(mid 0.249642 -0.249642)
							(end 0.1778 -0.2794)
						)
					)
					(width 0)
					(fill yes)
				)
			)
		)
	)
	(footprint ""
		(layer "F.Cu")
		(at 14.8844 -39.4462 90)
		(property "Reference" "R120"
			(at 0 0 90)
			(layer "F.SilkS")
			(hide yes)
			(effects
				(font
					(size 1.27 1.27)
				)
			)
		)
		(property "Value" "470R2F-GP"
			(at 0.064008 -3.993896 90)
			(unlocked yes)
			(layer "F.Fab")
			(hide yes)
			(effects
				(font
					(size 1.016 1.016)
					(thickness 0.1524)
				)
			)
		)
		(property "Device Type" "R402H16"
			(at 0.064008 -5.517896 90)
			(unlocked yes)
			(layer "F.Fab")
			(hide yes)
			(effects
				(font
					(size 1.016 1.016)
					(thickness 0.1524)
				)
			)
		)
		(duplicate_pad_numbers_are_jumpers no)
		(fp_line
			(start 0.508 -0.9398)
			(end -0.508 -0.9398)
			(stroke
				(width 0.1524)
				(type default)
			)
			(layer "F.SilkS")
		)
		(fp_line
			(start -0.508 -0.9398)
			(end -0.508 0.9398)
			(stroke
				(width 0.1524)
				(type default)
			)
			(layer "F.SilkS")
		)
		(fp_rect
			(start -0.508 0.9398)
			(end 0.508 -0.9398)
			(stroke
				(width 0)
				(type default)
			)
			(fill no)
			(layer "F.CrtYd")
		)
		(fp_rect
			(start -0.508 0.9398)
			(end 0.508 -0.9398)
			(stroke
				(width 0)
				(type default)
			)
			(fill no)
			(layer "F.Fab")
		)
		(pad "1" smd custom
			(at 0 -0.4445 90)
			(size 0.1397 0.1397)
			(layers "F.Cu" "F.Mask" "F.Paste")
			(net "SEB_PEER_2B_HB")
			(options
				(clearance outline)
				(anchor circle)
			)
			(primitives
				(gr_poly
					(pts
						(arc
							(start -0.1778 -0.2794)
							(mid -0.249642 -0.249642)
							(end -0.2794 -0.1778)
						)
						(arc
							(start -0.2794 0.1778)
							(mid -0.249642 0.249642)
							(end -0.1778 0.2794)
						)
						(arc
							(start 0.1778 0.2794)
							(mid 0.249642 0.249642)
							(end 0.2794 0.1778)
						)
						(arc
							(start 0.2794 -0.1778)
							(mid 0.249642 -0.249642)
							(end 0.1778 -0.2794)
						)
					)
					(width 0)
					(fill yes)
				)
			)
		)
		(pad "2" smd custom
			(at 0 0.4445 90)
			(size 0.1397 0.1397)
			(layers "F.Cu" "F.Mask" "F.Paste")
			(net "GND")
			(options
				(clearance outline)
				(anchor circle)
			)
			(primitives
				(gr_poly
					(pts
						(arc
							(start -0.1778 -0.2794)
							(mid -0.249642 -0.249642)
							(end -0.2794 -0.1778)
						)
						(arc
							(start -0.2794 0.1778)
							(mid -0.249642 0.249642)
							(end -0.1778 0.2794)
						)
						(arc
							(start 0.1778 0.2794)
							(mid 0.249642 0.249642)
							(end 0.2794 0.1778)
						)
						(arc
							(start 0.2794 -0.1778)
							(mid 0.249642 -0.249642)
							(end 0.1778 -0.2794)
						)
					)
					(width 0)
					(fill yes)
				)
			)
		)
	)
	(footprint ""
		(layer "F.Cu")
		(at 22.537166 -135.554466 -90)
		(property "Reference" "PR98"
			(at 0 0 270)
			(layer "F.SilkS")
			(hide yes)
			(effects
				(font
					(size 1.27 1.27)
				)
			)
		)
		(property "Value" "1MR3J-L-GP"
			(at -0.0254 -2.5146 270)
			(unlocked yes)
			(layer "F.Fab")
			(hide yes)
			(effects
				(font
					(size 1.016 1.016)
					(thickness 0.1524)
				)
			)
		)
		(property "Device Type" "R603H22"
			(at -0.0254 -4.0386 270)
			(unlocked yes)
			(layer "F.Fab")
			(hide yes)
			(effects
				(font
					(size 1.016 1.016)
					(thickness 0.1524)
				)
			)
		)
		(duplicate_pad_numbers_are_jumpers no)
		(fp_line
			(start -0.4826 0)
			(end -0.2032 0)
			(stroke
				(width 0.2032)
				(type default)
			)
			(layer "F.SilkS")
		)
		(fp_line
			(start 0.2032 0)
			(end 0.4826 0)
			(stroke
				(width 0.2032)
				(type default)
			)
			(layer "F.SilkS")
		)
		(fp_rect
			(start -0.5842 1.3335)
			(end 0.5842 -1.3335)
			(stroke
				(width 0)
				(type default)
			)
			(fill no)
			(layer "F.CrtYd")
		)
		(fp_rect
			(start -0.5842 1.3335)
			(end 0.5842 -1.3335)
			(stroke
				(width 0)
				(type default)
			)
			(fill no)
			(layer "F.Fab")
		)
		(pad "1" smd custom
			(at 0 -0.762 270)
			(size 0.2159 0.2159)
			(layers "F.Cu" "F.Mask" "F.Paste")
			(net "P12VU_2490_VCC")
			(options
				(clearance outline)
				(anchor circle)
			)
			(primitives
				(gr_poly
					(pts
						(arc
							(start -0.3302 -0.4318)
							(mid -0.402042 -0.402042)
							(end -0.4318 -0.3302)
						)
						(arc
							(start -0.4318 0.3302)
							(mid -0.402042 0.402042)
							(end -0.3302 0.4318)
						)
						(arc
							(start 0.3302 0.4318)
							(mid 0.402042 0.402042)
							(end 0.4318 0.3302)
						)
						(arc
							(start 0.4318 -0.3302)
							(mid 0.402042 -0.402042)
							(end 0.3302 -0.4318)
						)
					)
					(width 0)
					(fill yes)
				)
			)
		)
		(pad "2" smd custom
			(at 0 0.762 270)
			(size 0.2159 0.2159)
			(layers "F.Cu" "F.Mask" "F.Paste")
			(net "P12VU_2490_SENSE")
			(options
				(clearance outline)
				(anchor circle)
			)
			(primitives
				(gr_poly
					(pts
						(arc
							(start -0.3302 -0.4318)
							(mid -0.402042 -0.402042)
							(end -0.4318 -0.3302)
						)
						(arc
							(start -0.4318 0.3302)
							(mid -0.402042 0.402042)
							(end -0.3302 0.4318)
						)
						(arc
							(start 0.3302 0.4318)
							(mid 0.402042 0.402042)
							(end 0.4318 0.3302)
						)
						(arc
							(start 0.4318 -0.3302)
							(mid 0.402042 -0.402042)
							(end 0.3302 -0.4318)
						)
					)
					(width 0)
					(fill yes)
				)
			)
		)
	)
	(footprint ""
		(layer "F.Cu")
		(at 45.500036 -480.000056)
		(property "Reference" "H3"
			(at 0 0 0)
			(layer "F.SilkS")
			(hide yes)
			(effects
				(font
					(size 1.27 1.27)
				)
			)
		)
		(property "Value" "HOLE315R158"
			(at -5.08 -0.4572 0)
			(unlocked yes)
			(layer "F.Fab")
			(hide yes)
			(effects
				(font
					(size 1.016 1.016)
					(thickness 0.1524)
				)
			)
		)
		(property "Device Type" "HOLE315R158"
			(at -5.08 -1.9812 0)
			(unlocked yes)
			(layer "F.Fab")
			(hide yes)
			(effects
				(font
					(size 1.016 1.016)
					(thickness 0.1524)
				)
			)
		)
		(duplicate_pad_numbers_are_jumpers no)
		(fp_poly
			(pts
				(arc
					(start -4.3053 0)
					(mid 4.3053 0)
					(end -4.3053 0)
				)
			)
			(stroke
				(width 0)
				(type default)
			)
			(fill no)
			(layer "B.CrtYd")
		)
		(fp_poly
			(pts
				(arc
					(start -4.3053 0)
					(mid 4.3053 0)
					(end -4.3053 0)
				)
			)
			(stroke
				(width 0)
				(type default)
			)
			(fill no)
			(layer "F.CrtYd")
		)
		(fp_poly
			(pts
				(arc
					(start -4.3053 0)
					(mid 4.3053 0)
					(end -4.3053 0)
				)
			)
			(stroke
				(width 0)
				(type default)
			)
			(fill no)
			(layer "B.Fab")
		)
		(fp_poly
			(pts
				(arc
					(start -4.3053 0)
					(mid 4.3053 0)
					(end -4.3053 0)
				)
			)
			(stroke
				(width 0)
				(type default)
			)
			(fill no)
			(layer "F.Fab")
		)
		(pad "1" thru_hole circle
			(at 0 0)
			(size 8.001 8.001)
			(drill 4.0132)
			(layers "*.Cu" "*.Mask")
			(remove_unused_layers no)
			(net "GND")
			(clearance -1.4859)
			(thermal_gap 0.3048)
			(padstack
				(mode front_inner_back)
				(layer "Inner"
					(shape circle)
					(size 4.4196 4.4196)
					(clearance 0.3048)
				)
				(layer "B.Cu"
					(shape circle)
					(size 8.001 8.001)
					(clearance -1.4859)
				)
			)
		)
	)
	(footprint ""
		(layer "F.Cu")
		(at 7.949946 -267.865098 -90)
		(property "Reference" "LED3"
			(at 0 0 270)
			(layer "F.SilkS")
			(hide yes)
			(effects
				(font
					(size 1.27 1.27)
				)
			)
		)
		(property "Value" "LED-RB-6-GP"
			(at -4.6736 3.8354 270)
			(unlocked yes)
			(layer "F.Fab")
			(hide yes)
			(effects
				(font
					(size 1.016 1.016)
					(thickness 0.1524)
				)
			)
		)
		(property "Device Type" "LED-100-3P-067106H325"
			(at -4.6736 2.3114 270)
			(unlocked yes)
			(layer "F.Fab")
			(hide yes)
			(effects
				(font
					(size 1.016 1.016)
					(thickness 0.1524)
				)
			)
		)
		(duplicate_pad_numbers_are_jumpers no)
		(fp_line
			(start -1.7526 10.414)
			(end -1.7526 6.6548)
			(stroke
				(width 0.1524)
				(type default)
			)
			(layer "F.SilkS")
		)
		(fp_line
			(start 1.7526 10.414)
			(end -1.7526 10.414)
			(stroke
				(width 0.1524)
				(type default)
			)
			(layer "F.SilkS")
		)
		(fp_line
			(start -3.6068 6.6548)
			(end -3.6068 -0.889)
			(stroke
				(width 0.1524)
				(type default)
			)
			(layer "F.SilkS")
		)
		(fp_line
			(start -1.7526 6.6548)
			(end -3.6068 6.6548)
			(stroke
				(width 0.1524)
				(type default)
			)
			(layer "F.SilkS")
		)
		(fp_line
			(start 1.7526 6.6548)
			(end 1.7526 10.414)
			(stroke
				(width 0.1524)
				(type default)
			)
			(layer "F.SilkS")
		)
		(fp_line
			(start 3.6068 6.6548)
			(end 1.7526 6.6548)
			(stroke
				(width 0.1524)
				(type default)
			)
			(layer "F.SilkS")
		)
		(fp_line
			(start -3.6068 -0.889)
			(end 3.6068 -0.889)
			(stroke
				(width 0.1524)
				(type default)
			)
			(layer "F.SilkS")
		)
		(fp_line
			(start 3.6068 -0.889)
			(end 3.6068 6.6548)
			(stroke
				(width 0.1524)
				(type default)
			)
			(layer "F.SilkS")
		)
		(fp_circle
			(center -2.54 0)
			(end -2.54 -0.9906)
			(stroke
				(width 0.3048)
				(type default)
			)
			(fill no)
			(layer "F.SilkS")
		)
		(fp_circle
			(center 0 0)
			(end 0 -0.9906)
			(stroke
				(width 0.3048)
				(type default)
			)
			(fill no)
			(layer "F.SilkS")
		)
		(fp_circle
			(center 2.54 0)
			(end 2.54 -0.9906)
			(stroke
				(width 0.3048)
				(type default)
			)
			(fill no)
			(layer "F.SilkS")
		)
		(fp_poly
			(pts
				(xy -1.4986 10.1473) (xy -1.4986 6.4008) (xy -3.3528 6.4008) (xy -3.3528 -0.3937) (xy 3.3528 -0.3937)
				(xy 3.3528 6.4008) (xy 1.4986 6.4008) (xy 1.4986 10.1473)
			)
			(stroke
				(width 0)
				(type default)
			)
			(fill no)
			(layer "F.CrtYd")
		)
		(fp_poly
			(pts
				(xy -2.0066 10.668) (xy 2.0066 10.668) (xy 2.0066 6.9088) (xy 3.8608 6.9088) (xy 3.8608 2.2098)
				(xy 3.3528 2.2098) (xy 3.3528 6.4008) (xy 1.4986 6.4008) (xy 1.4986 10.1473) (xy -1.4986 10.1473)
				(xy -1.4986 6.4008) (xy -3.3528 6.4008) (xy -3.3528 -0.3937) (xy 3.3528 -0.3937) (xy 3.3528 2.1971)
				(xy 3.8608 2.1971) (xy 3.8608 -1.143) (xy -3.8608 -1.143) (xy -3.8608 6.9088) (xy -2.0066 6.9088)
			)
			(stroke
				(width 0)
				(type default)
			)
			(fill no)
			(layer "F.CrtYd")
		)
		(fp_poly
			(pts
				(xy -2.0066 10.668) (xy -2.0066 6.9088) (xy -3.8608 6.9088) (xy -3.8608 -1.143) (xy 3.8608 -1.143)
				(xy 3.8608 6.9088) (xy 2.0066 6.9088) (xy 2.0066 10.668)
			)
			(stroke
				(width 0)
				(type default)
			)
			(fill no)
			(layer "F.Fab")
		)
		(pad "1" thru_hole circle
			(at 2.54 0 270)
			(size 1.27 1.27)
			(drill 0.889)
			(layers "*.Cu" "*.Mask")
			(remove_unused_layers no)
			(net "LED_DR_LED2_BLUE")
			(clearance 0.1651)
			(thermal_gap 0.1651)
		)
		(pad "2" thru_hole circle
			(at 0 0 270)
			(size 1.27 1.27)
			(drill 0.889)
			(layers "*.Cu" "*.Mask")
			(remove_unused_layers no)
			(net "LED_DR_LED2_K")
			(clearance 0.1651)
			(thermal_gap 0.1651)
		)
		(pad "3" thru_hole circle
			(at -2.54 0 270)
			(size 1.27 1.27)
			(drill 0.889)
			(layers "*.Cu" "*.Mask")
			(remove_unused_layers no)
			(net "LED_DR_LED2")
			(clearance 0.1651)
			(thermal_gap 0.1651)
		)
	)
	(footprint ""
		(layer "F.Cu")
		(at 21.6916 -144.7546 -90)
		(property "Reference" "PR110"
			(at 0 0 270)
			(layer "F.SilkS")
			(hide yes)
			(effects
				(font
					(size 1.27 1.27)
				)
			)
		)
		(property "Value" "178KR2F-GP"
			(at 0.064008 -3.993896 270)
			(unlocked yes)
			(layer "F.Fab")
			(hide yes)
			(effects
				(font
					(size 1.016 1.016)
					(thickness 0.1524)
				)
			)
		)
		(property "Device Type" "R402H16"
			(at 0.064008 -5.517896 270)
			(unlocked yes)
			(layer "F.Fab")
			(hide yes)
			(effects
				(font
					(size 1.016 1.016)
					(thickness 0.1524)
				)
			)
		)
		(duplicate_pad_numbers_are_jumpers no)
		(fp_line
			(start -0.508 -0.9398)
			(end -0.508 0.9398)
			(stroke
				(width 0.1524)
				(type default)
			)
			(layer "F.SilkS")
		)
		(fp_line
			(start 0.508 -0.9398)
			(end -0.508 -0.9398)
			(stroke
				(width 0.1524)
				(type default)
			)
			(layer "F.SilkS")
		)
		(fp_rect
			(start -0.508 0.9398)
			(end 0.508 -0.9398)
			(stroke
				(width 0)
				(type default)
			)
			(fill no)
			(layer "F.CrtYd")
		)
		(fp_rect
			(start -0.508 0.9398)
			(end 0.508 -0.9398)
			(stroke
				(width 0)
				(type default)
			)
			(fill no)
			(layer "F.Fab")
		)
		(pad "1" smd custom
			(at 0 -0.4445 270)
			(size 0.1397 0.1397)
			(layers "F.Cu" "F.Mask" "F.Paste")
			(net "P12VU_2490_VREF")
			(options
				(clearance outline)
				(anchor circle)
			)
			(primitives
				(gr_poly
					(pts
						(arc
							(start -0.1778 -0.2794)
							(mid -0.249642 -0.249642)
							(end -0.2794 -0.1778)
						)
						(arc
							(start -0.2794 0.1778)
							(mid -0.249642 0.249642)
							(end -0.1778 0.2794)
						)
						(arc
							(start 0.1778 0.2794)
							(mid 0.249642 0.249642)
							(end 0.2794 0.1778)
						)
						(arc
							(start 0.2794 -0.1778)
							(mid 0.249642 -0.249642)
							(end 0.1778 -0.2794)
						)
					)
					(width 0)
					(fill yes)
				)
			)
		)
		(pad "2" smd custom
			(at 0 0.4445 270)
			(size 0.1397 0.1397)
			(layers "F.Cu" "F.Mask" "F.Paste")
			(net "P12VU_2490_PROG")
			(options
				(clearance outline)
				(anchor circle)
			)
			(primitives
				(gr_poly
					(pts
						(arc
							(start -0.1778 -0.2794)
							(mid -0.249642 -0.249642)
							(end -0.2794 -0.1778)
						)
						(arc
							(start -0.2794 0.1778)
							(mid -0.249642 0.249642)
							(end -0.1778 0.2794)
						)
						(arc
							(start 0.1778 0.2794)
							(mid 0.249642 0.249642)
							(end 0.2794 0.1778)
						)
						(arc
							(start 0.2794 -0.1778)
							(mid 0.249642 -0.249642)
							(end 0.1778 -0.2794)
						)
					)
					(width 0)
					(fill yes)
				)
			)
		)
	)
	(footprint ""
		(layer "F.Cu")
		(at 23.622 -170.434 -90)
		(property "Reference" "R21"
			(at 0 0 270)
			(layer "F.SilkS")
			(hide yes)
			(effects
				(font
					(size 1.27 1.27)
				)
			)
		)
		(property "Value" "100KR2F-L1-GP"
			(at 0.064008 -3.993896 270)
			(unlocked yes)
			(layer "F.Fab")
			(hide yes)
			(effects
				(font
					(size 1.016 1.016)
					(thickness 0.1524)
				)
			)
		)
		(property "Device Type" "R402H16"
			(at 0.064008 -5.517896 270)
			(unlocked yes)
			(layer "F.Fab")
			(hide yes)
			(effects
				(font
					(size 1.016 1.016)
					(thickness 0.1524)
				)
			)
		)
		(duplicate_pad_numbers_are_jumpers no)
		(fp_line
			(start -0.508 -0.9398)
			(end -0.508 0.9398)
			(stroke
				(width 0.1524)
				(type default)
			)
			(layer "F.SilkS")
		)
		(fp_line
			(start 0.508 -0.9398)
			(end -0.508 -0.9398)
			(stroke
				(width 0.1524)
				(type default)
			)
			(layer "F.SilkS")
		)
		(fp_rect
			(start -0.508 0.9398)
			(end 0.508 -0.9398)
			(stroke
				(width 0)
				(type default)
			)
			(fill no)
			(layer "F.CrtYd")
		)
		(fp_rect
			(start -0.508 0.9398)
			(end 0.508 -0.9398)
			(stroke
				(width 0)
				(type default)
			)
			(fill no)
			(layer "F.Fab")
		)
		(pad "1" smd custom
			(at 0 -0.4445 270)
			(size 0.1397 0.1397)
			(layers "F.Cu" "F.Mask" "F.Paste")
			(net "PWM_EXP_2B")
			(options
				(clearance outline)
				(anchor circle)
			)
			(primitives
				(gr_poly
					(pts
						(arc
							(start -0.1778 -0.2794)
							(mid -0.249642 -0.249642)
							(end -0.2794 -0.1778)
						)
						(arc
							(start -0.2794 0.1778)
							(mid -0.249642 0.249642)
							(end -0.1778 0.2794)
						)
						(arc
							(start 0.1778 0.2794)
							(mid 0.249642 0.249642)
							(end 0.2794 0.1778)
						)
						(arc
							(start 0.2794 -0.1778)
							(mid 0.249642 -0.249642)
							(end 0.1778 -0.2794)
						)
					)
					(width 0)
					(fill yes)
				)
			)
		)
		(pad "2" smd custom
			(at 0 0.4445 270)
			(size 0.1397 0.1397)
			(layers "F.Cu" "F.Mask" "F.Paste")
			(net "GND")
			(options
				(clearance outline)
				(anchor circle)
			)
			(primitives
				(gr_poly
					(pts
						(arc
							(start -0.1778 -0.2794)
							(mid -0.249642 -0.249642)
							(end -0.2794 -0.1778)
						)
						(arc
							(start -0.2794 0.1778)
							(mid -0.249642 0.249642)
							(end -0.1778 0.2794)
						)
						(arc
							(start 0.1778 0.2794)
							(mid 0.249642 0.249642)
							(end 0.2794 0.1778)
						)
						(arc
							(start 0.2794 -0.1778)
							(mid 0.249642 -0.249642)
							(end 0.1778 -0.2794)
						)
					)
					(width 0)
					(fill yes)
				)
			)
		)
	)
	(footprint ""
		(layer "F.Cu")
		(at 36.068 -252.603 -90)
		(property "Reference" "TP18"
			(at 0 0 270)
			(layer "F.SilkS")
			(hide yes)
			(effects
				(font
					(size 1.27 1.27)
				)
			)
		)
		(property "Value" "TPAD32-GP"
			(at 0 -3.166364 270)
			(unlocked yes)
			(layer "F.Fab")
			(hide yes)
			(effects
				(font
					(size 1.016 1.016)
					(thickness 0.1524)
				)
			)
		)
		(property "Device Type" "TPAD32"
			(at 0 -4.690618 270)
			(unlocked yes)
			(layer "F.Fab")
			(hide yes)
			(effects
				(font
					(size 1.016 1.016)
					(thickness 0.1524)
				)
			)
		)
		(duplicate_pad_numbers_are_jumpers no)
		(fp_poly
			(pts
				(arc
					(start 0.7112 0)
					(mid -0.7112 0)
					(end 0.7112 0)
				)
			)
			(stroke
				(width 0)
				(type default)
			)
			(fill no)
			(layer "F.CrtYd")
		)
		(fp_poly
			(pts
				(arc
					(start 0.7112 0)
					(mid -0.7112 0)
					(end 0.7112 0)
				)
			)
			(stroke
				(width 0)
				(type default)
			)
			(fill no)
			(layer "F.Fab")
		)
		(pad "1" smd circle
			(at 0 0 270)
			(size 0.8128 0.8128)
			(layers "F.Cu" "F.Mask" "F.Paste")
			(net "LED_DRV_RST")
		)
	)
	(footprint ""
		(layer "F.Cu")
		(at 39.878 -240.665 180)
		(property "Reference" "R155"
			(at 0 0 180)
			(layer "F.SilkS")
			(hide yes)
			(effects
				(font
					(size 1.27 1.27)
				)
			)
		)
		(property "Value" "330R2J-3-GP"
			(at 0.064008 -3.993896 180)
			(unlocked yes)
			(layer "F.Fab")
			(hide yes)
			(effects
				(font
					(size 1.016 1.016)
					(thickness 0.1524)
				)
			)
		)
		(property "Device Type" "R402H16"
			(at 0.064008 -5.517896 180)
			(unlocked yes)
			(layer "F.Fab")
			(hide yes)
			(effects
				(font
					(size 1.016 1.016)
					(thickness 0.1524)
				)
			)
		)
		(duplicate_pad_numbers_are_jumpers no)
		(fp_line
			(start 0.508 -0.9398)
			(end -0.508 -0.9398)
			(stroke
				(width 0.1524)
				(type default)
			)
			(layer "F.SilkS")
		)
		(fp_line
			(start -0.508 -0.9398)
			(end -0.508 0.9398)
			(stroke
				(width 0.1524)
				(type default)
			)
			(layer "F.SilkS")
		)
		(fp_rect
			(start -0.508 0.9398)
			(end 0.508 -0.9398)
			(stroke
				(width 0)
				(type default)
			)
			(fill no)
			(layer "F.CrtYd")
		)
		(fp_rect
			(start -0.508 0.9398)
			(end 0.508 -0.9398)
			(stroke
				(width 0)
				(type default)
			)
			(fill no)
			(layer "F.Fab")
		)
		(pad "1" smd custom
			(at 0 -0.4445 180)
			(size 0.1397 0.1397)
			(layers "F.Cu" "F.Mask" "F.Paste")
			(net "P3V3")
			(options
				(clearance outline)
				(anchor circle)
			)
			(primitives
				(gr_poly
					(pts
						(arc
							(start -0.1778 -0.2794)
							(mid -0.249642 -0.249642)
							(end -0.2794 -0.1778)
						)
						(arc
							(start -0.2794 0.1778)
							(mid -0.249642 0.249642)
							(end -0.1778 0.2794)
						)
						(arc
							(start 0.1778 0.2794)
							(mid 0.249642 0.249642)
							(end 0.2794 0.1778)
						)
						(arc
							(start 0.2794 -0.1778)
							(mid 0.249642 -0.249642)
							(end 0.1778 -0.2794)
						)
					)
					(width 0)
					(fill yes)
				)
			)
		)
		(pad "2" smd custom
			(at 0 0.4445 180)
			(size 0.1397 0.1397)
			(layers "F.Cu" "F.Mask" "F.Paste")
			(net "LED_DR_LED3")
			(options
				(clearance outline)
				(anchor circle)
			)
			(primitives
				(gr_poly
					(pts
						(arc
							(start -0.1778 -0.2794)
							(mid -0.249642 -0.249642)
							(end -0.2794 -0.1778)
						)
						(arc
							(start -0.2794 0.1778)
							(mid -0.249642 0.249642)
							(end -0.1778 0.2794)
						)
						(arc
							(start 0.1778 0.2794)
							(mid 0.249642 0.249642)
							(end 0.2794 0.1778)
						)
						(arc
							(start 0.2794 -0.1778)
							(mid 0.249642 -0.249642)
							(end 0.1778 -0.2794)
						)
					)
					(width 0)
					(fill yes)
				)
			)
		)
	)
	(footprint ""
		(layer "F.Cu")
		(at 19.1262 -241.1984 90)
		(property "Reference" "PL7"
			(at 0 0 90)
			(layer "F.SilkS")
			(hide yes)
			(effects
				(font
					(size 1.27 1.27)
				)
			)
		)
		(property "Value" "IND-22UH-169-GP"
			(at -4.7498 0.5588 90)
			(unlocked yes)
			(layer "F.Fab")
			(hide yes)
			(effects
				(font
					(size 1.016 1.016)
					(thickness 0.1524)
				)
			)
		)
		(property "Device Type" "L6362-D620H119"
			(at -4.7498 -0.9652 90)
			(unlocked yes)
			(layer "F.Fab")
			(hide yes)
			(effects
				(font
					(size 1.016 1.016)
					(thickness 0.1524)
				)
			)
		)
		(duplicate_pad_numbers_are_jumpers no)
		(fp_line
			(start 1.667256 -3.8989)
			(end 3.3528 -2.213356)
			(stroke
				(width 0.1524)
				(type default)
			)
			(layer "F.SilkS")
		)
		(fp_line
			(start -1.667256 -3.8989)
			(end 1.667256 -3.8989)
			(stroke
				(width 0.1524)
				(type default)
			)
			(layer "F.SilkS")
		)
		(fp_line
			(start 3.3528 -2.213356)
			(end 3.3528 2.213356)
			(stroke
				(width 0.1524)
				(type default)
			)
			(layer "F.SilkS")
		)
		(fp_line
			(start -3.3528 -2.213356)
			(end -1.667256 -3.8989)
			(stroke
				(width 0.1524)
				(type default)
			)
			(layer "F.SilkS")
		)
		(fp_line
			(start 3.3528 2.213356)
			(end 1.667256 3.8989)
			(stroke
				(width 0.1524)
				(type default)
			)
			(layer "F.SilkS")
		)
		(fp_line
			(start -3.3528 2.213356)
			(end -3.3528 -2.213356)
			(stroke
				(width 0.1524)
				(type default)
			)
			(layer "F.SilkS")
		)
		(fp_line
			(start 1.667256 3.8989)
			(end -1.667256 3.8989)
			(stroke
				(width 0.1524)
				(type default)
			)
			(layer "F.SilkS")
		)
		(fp_line
			(start -1.667256 3.8989)
			(end -3.3528 2.213356)
			(stroke
				(width 0.1524)
				(type default)
			)
			(layer "F.SilkS")
		)
		(fp_poly
			(pts
				(xy 2.0574 3.1496) (xy -2.0574 3.1496) (xy -3.0988 2.1082) (xy -3.0988 -2.1082) (xy -2.0574 -3.1496)
				(xy 2.0574 -3.1496) (xy 3.0988 -2.1082) (xy 3.0988 2.1082)
			)
			(stroke
				(width 0)
				(type default)
			)
			(fill no)
			(layer "F.CrtYd")
		)
		(fp_poly
			(pts
				(xy 3.6068 2.318512) (xy 1.950212 3.9751) (xy -1.950212 3.9751) (xy -3.6068 2.318512) (xy -3.6068 -2.318512)
				(xy -1.950212 -3.9751) (xy 1.950212 -3.9751) (xy 3.6068 -2.318512) (xy 3.6068 -1.9177) (xy 3.0988 -1.9177)
				(xy 3.0988 -2.1082) (xy 2.0574 -3.1496) (xy -2.0574 -3.1496) (xy -3.0988 -2.1082) (xy -3.0988 2.1082)
				(xy -2.0574 3.1496) (xy 2.0574 3.1496) (xy 3.0988 2.1082) (xy 3.0988 -1.905) (xy 3.6068 -1.905)
			)
			(stroke
				(width 0)
				(type default)
			)
			(fill no)
			(layer "F.CrtYd")
		)
		(fp_poly
			(pts
				(xy -1.950212 3.9751) (xy -3.6068 2.318512) (xy -3.6068 -2.318512) (xy -1.950212 -3.9751) (xy 1.950212 -3.9751)
				(xy 3.6068 -2.318512) (xy 3.6068 2.318512) (xy 1.950212 3.9751)
			)
			(stroke
				(width 0)
				(type default)
			)
			(fill no)
			(layer "F.Fab")
		)
		(pad "1" smd rect
			(at 0 -2.895346 90)
			(size 2.2606 1.4986)
			(layers "F.Cu" "F.Mask" "F.Paste")
			(net "P3V3_LX")
		)
		(pad "2" smd rect
			(at 0 2.895346 90)
			(size 2.2606 1.4986)
			(layers "F.Cu" "F.Mask" "F.Paste")
			(net "P3V3_LX_COPPER")
		)
	)
	(footprint ""
		(layer "F.Cu")
		(at 18.288 -271.7038 90)
		(property "Reference" "R179"
			(at 0 0 90)
			(layer "F.SilkS")
			(hide yes)
			(effects
				(font
					(size 1.27 1.27)
				)
			)
		)
		(property "Value" "0R1206-PAD-1-GP"
			(at 0 -5.0292 90)
			(unlocked yes)
			(layer "F.Fab")
			(hide yes)
			(effects
				(font
					(size 1.016 1.016)
					(thickness 0.1524)
				)
			)
		)
		(property "Device Type" "0R1206-PAD-1"
			(at 0 -6.5532 90)
			(unlocked yes)
			(layer "F.Fab")
			(hide yes)
			(effects
				(font
					(size 1.016 1.016)
					(thickness 0.1524)
				)
			)
		)
		(duplicate_pad_numbers_are_jumpers no)
		(fp_line
			(start 1.016 -2.2352)
			(end -1.016 -2.2352)
			(stroke
				(width 0.1524)
				(type default)
			)
			(layer "F.SilkS")
		)
		(fp_line
			(start -1.016 -2.2352)
			(end -1.016 2.2352)
			(stroke
				(width 0.1524)
				(type default)
			)
			(layer "F.SilkS")
		)
		(fp_line
			(start 1.016 2.2352)
			(end 1.016 -2.2352)
			(stroke
				(width 0.1524)
				(type default)
			)
			(layer "F.SilkS")
		)
		(fp_line
			(start -1.016 2.2352)
			(end 1.016 2.2352)
			(stroke
				(width 0.1524)
				(type default)
			)
			(layer "F.SilkS")
		)
		(fp_rect
			(start -1.0922 2.3114)
			(end 1.0922 -2.3114)
			(stroke
				(width 0)
				(type default)
			)
			(fill no)
			(layer "F.CrtYd")
		)
		(fp_poly
			(pts
				(xy -1.0922 -2.3114) (xy 1.0922 -2.3114) (xy 1.0922 2.3114) (xy -1.0922 2.3114)
			)
			(stroke
				(width 0)
				(type default)
			)
			(fill no)
			(layer "F.Fab")
		)
		(pad "1" smd rect
			(at 0 -1.397 90)
			(size 1.651 2.0574)
			(drill
				(offset 0 0.3937)
			)
			(layers "F.Cu" "F.Mask" "F.Paste")
			(net "P12V_FAN3")
		)
		(pad "2" smd rect
			(at 0 1.397 90)
			(size 1.651 2.0574)
			(drill
				(offset 0 -0.3937)
			)
			(layers "F.Cu" "F.Mask" "F.Paste")
			(net "P12V")
		)
	)
	(footprint ""
		(layer "F.Cu")
		(at 32.385 -361.315 180)
		(property "Reference" "R108"
			(at 0 0 180)
			(layer "F.SilkS")
			(hide yes)
			(effects
				(font
					(size 1.27 1.27)
				)
			)
		)
		(property "Value" "0R2J-2-GP"
			(at 0.064008 -3.993896 180)
			(unlocked yes)
			(layer "F.Fab")
			(hide yes)
			(effects
				(font
					(size 1.016 1.016)
					(thickness 0.1524)
				)
			)
		)
		(property "Device Type" "R402H16"
			(at 0.064008 -5.517896 180)
			(unlocked yes)
			(layer "F.Fab")
			(hide yes)
			(effects
				(font
					(size 1.016 1.016)
					(thickness 0.1524)
				)
			)
		)
		(duplicate_pad_numbers_are_jumpers no)
		(fp_line
			(start 0.508 -0.9398)
			(end -0.508 -0.9398)
			(stroke
				(width 0.1524)
				(type default)
			)
			(layer "F.SilkS")
		)
		(fp_line
			(start -0.508 -0.9398)
			(end -0.508 0.9398)
			(stroke
				(width 0.1524)
				(type default)
			)
			(layer "F.SilkS")
		)
		(fp_rect
			(start -0.508 0.9398)
			(end 0.508 -0.9398)
			(stroke
				(width 0)
				(type default)
			)
			(fill no)
			(layer "F.CrtYd")
		)
		(fp_rect
			(start -0.508 0.9398)
			(end 0.508 -0.9398)
			(stroke
				(width 0)
				(type default)
			)
			(fill no)
			(layer "F.Fab")
		)
		(pad "1" smd custom
			(at 0 -0.4445 180)
			(size 0.1397 0.1397)
			(layers "F.Cu" "F.Mask" "F.Paste")
			(net "I2C_C_SCL")
			(options
				(clearance outline)
				(anchor circle)
			)
			(primitives
				(gr_poly
					(pts
						(arc
							(start -0.1778 -0.2794)
							(mid -0.249642 -0.249642)
							(end -0.2794 -0.1778)
						)
						(arc
							(start -0.2794 0.1778)
							(mid -0.249642 0.249642)
							(end -0.1778 0.2794)
						)
						(arc
							(start 0.1778 0.2794)
							(mid 0.249642 0.249642)
							(end 0.2794 0.1778)
						)
						(arc
							(start 0.2794 -0.1778)
							(mid 0.249642 -0.249642)
							(end 0.1778 -0.2794)
						)
					)
					(width 0)
					(fill yes)
				)
			)
		)
		(pad "2" smd custom
			(at 0 0.4445 180)
			(size 0.1397 0.1397)
			(layers "F.Cu" "F.Mask" "F.Paste")
			(net "I2C_C_SCL_ADM1276")
			(options
				(clearance outline)
				(anchor circle)
			)
			(primitives
				(gr_poly
					(pts
						(arc
							(start -0.1778 -0.2794)
							(mid -0.249642 -0.249642)
							(end -0.2794 -0.1778)
						)
						(arc
							(start -0.2794 0.1778)
							(mid -0.249642 0.249642)
							(end -0.1778 0.2794)
						)
						(arc
							(start 0.1778 0.2794)
							(mid 0.249642 0.249642)
							(end 0.2794 0.1778)
						)
						(arc
							(start 0.2794 -0.1778)
							(mid 0.249642 -0.249642)
							(end 0.1778 -0.2794)
						)
					)
					(width 0)
					(fill yes)
				)
			)
		)
	)
	(footprint ""
		(layer "F.Cu")
		(at 33.147 -376.428 90)
		(property "Reference" "PR14"
			(at 0 0 90)
			(layer "F.SilkS")
			(hide yes)
			(effects
				(font
					(size 1.27 1.27)
				)
			)
		)
		(property "Value" "0R2J-2-GP"
			(at 0.064008 -3.993896 90)
			(unlocked yes)
			(layer "F.Fab")
			(hide yes)
			(effects
				(font
					(size 1.016 1.016)
					(thickness 0.1524)
				)
			)
		)
		(property "Device Type" "R402H16"
			(at 0.064008 -5.517896 90)
			(unlocked yes)
			(layer "F.Fab")
			(hide yes)
			(effects
				(font
					(size 1.016 1.016)
					(thickness 0.1524)
				)
			)
		)
		(duplicate_pad_numbers_are_jumpers no)
		(fp_line
			(start 0.508 -0.9398)
			(end -0.508 -0.9398)
			(stroke
				(width 0.1524)
				(type default)
			)
			(layer "F.SilkS")
		)
		(fp_line
			(start -0.508 -0.9398)
			(end -0.508 0.9398)
			(stroke
				(width 0.1524)
				(type default)
			)
			(layer "F.SilkS")
		)
		(fp_rect
			(start -0.508 0.9398)
			(end 0.508 -0.9398)
			(stroke
				(width 0)
				(type default)
			)
			(fill no)
			(layer "F.CrtYd")
		)
		(fp_rect
			(start -0.508 0.9398)
			(end 0.508 -0.9398)
			(stroke
				(width 0)
				(type default)
			)
			(fill no)
			(layer "F.Fab")
		)
		(pad "1" smd custom
			(at 0 -0.4445 90)
			(size 0.1397 0.1397)
			(layers "F.Cu" "F.Mask" "F.Paste")
			(net "ADM1276_GATE")
			(options
				(clearance outline)
				(anchor circle)
			)
			(primitives
				(gr_poly
					(pts
						(arc
							(start -0.1778 -0.2794)
							(mid -0.249642 -0.249642)
							(end -0.2794 -0.1778)
						)
						(arc
							(start -0.2794 0.1778)
							(mid -0.249642 0.249642)
							(end -0.1778 0.2794)
						)
						(arc
							(start 0.1778 0.2794)
							(mid 0.249642 0.249642)
							(end 0.2794 0.1778)
						)
						(arc
							(start 0.2794 -0.1778)
							(mid 0.249642 -0.249642)
							(end 0.1778 -0.2794)
						)
					)
					(width 0)
					(fill yes)
				)
			)
		)
		(pad "2" smd custom
			(at 0 0.4445 90)
			(size 0.1397 0.1397)
			(layers "F.Cu" "F.Mask" "F.Paste")
			(net "ADM1276_GATE_RC")
			(options
				(clearance outline)
				(anchor circle)
			)
			(primitives
				(gr_poly
					(pts
						(arc
							(start -0.1778 -0.2794)
							(mid -0.249642 -0.249642)
							(end -0.2794 -0.1778)
						)
						(arc
							(start -0.2794 0.1778)
							(mid -0.249642 0.249642)
							(end -0.1778 0.2794)
						)
						(arc
							(start 0.1778 0.2794)
							(mid 0.249642 0.249642)
							(end 0.2794 0.1778)
						)
						(arc
							(start 0.2794 -0.1778)
							(mid 0.249642 -0.249642)
							(end 0.1778 -0.2794)
						)
					)
					(width 0)
					(fill yes)
				)
			)
		)
	)
	(footprint ""
		(layer "F.Cu")
		(at 23.749 -106.426 90)
		(property "Reference" "TC3"
			(at 0 0 90)
			(layer "F.SilkS")
			(hide yes)
			(effects
				(font
					(size 1.27 1.27)
				)
			)
		)
		(property "Value" "ST68U16VDM-1-GP"
			(at 0 -9.6012 90)
			(unlocked yes)
			(layer "F.Fab")
			(hide yes)
			(effects
				(font
					(size 1.016 1.016)
					(thickness 0.1524)
				)
			)
		)
		(property "Device Type" "CT7343H79"
			(at 0 -11.1252 90)
			(unlocked yes)
			(layer "F.Fab")
			(hide yes)
			(effects
				(font
					(size 1.016 1.016)
					(thickness 0.1524)
				)
			)
		)
		(duplicate_pad_numbers_are_jumpers no)
		(fp_line
			(start 2.286 -4.8768)
			(end -2.286 -4.8768)
			(stroke
				(width 0.1524)
				(type default)
			)
			(layer "F.SilkS")
		)
		(fp_line
			(start -2.286 -4.8768)
			(end -2.286 -2.032)
			(stroke
				(width 0.1524)
				(type default)
			)
			(layer "F.SilkS")
		)
		(fp_line
			(start 2.1082 -4.699)
			(end -2.1082 -4.699)
			(stroke
				(width 0.508)
				(type default)
			)
			(layer "F.SilkS")
		)
		(fp_line
			(start 2.286 -2.032)
			(end 2.286 -4.8768)
			(stroke
				(width 0.1524)
				(type default)
			)
			(layer "F.SilkS")
		)
		(fp_line
			(start 2.286 2.032)
			(end 2.286 4.8768)
			(stroke
				(width 0.1524)
				(type default)
			)
			(layer "F.SilkS")
		)
		(fp_line
			(start 2.286 4.8768)
			(end -2.286 4.8768)
			(stroke
				(width 0.1524)
				(type default)
			)
			(layer "F.SilkS")
		)
		(fp_line
			(start -2.286 4.8768)
			(end -2.286 2.032)
			(stroke
				(width 0.1524)
				(type default)
			)
			(layer "F.SilkS")
		)
		(fp_rect
			(start -2.1463 3.6449)
			(end 2.1463 -3.6449)
			(stroke
				(width 0)
				(type default)
			)
			(fill no)
			(layer "F.CrtYd")
		)
		(fp_poly
			(pts
				(xy -2.54 4.953) (xy -2.54 4.2926) (xy -3.81 4.2926) (xy -3.81 -4.2926) (xy -2.54 -4.2926) (xy -2.54 -4.953)
				(xy 2.54 -4.953) (xy 2.54 -4.2926) (xy 3.81 -4.2926) (xy 3.81 -1.6256) (xy 2.1463 -1.6256) (xy 2.1463 -3.6449)
				(xy -2.1463 -3.6449) (xy -2.1463 3.6449) (xy 2.1463 3.6449) (xy 2.1463 -1.6129) (xy 3.81 -1.6129)
				(xy 3.81 4.2926) (xy 2.54 4.2926) (xy 2.54 4.953)
			)
			(stroke
				(width 0)
				(type default)
			)
			(fill no)
			(layer "F.CrtYd")
		)
		(fp_rect
			(start 2.54 4.2926)
			(end 3.81 -4.2926)
			(stroke
				(width 0)
				(type default)
			)
			(fill no)
			(layer "F.Fab")
		)
		(fp_rect
			(start -3.81 4.2926)
			(end -2.54 -4.2926)
			(stroke
				(width 0)
				(type default)
			)
			(fill no)
			(layer "F.Fab")
		)
		(fp_rect
			(start -2.54 4.953)
			(end 2.54 -4.953)
			(stroke
				(width 0)
				(type default)
			)
			(fill no)
			(layer "F.Fab")
		)
		(pad "1" smd rect
			(at 0 -3.1496 90)
			(size 2.413 2.286)
			(layers "F.Cu" "F.Mask" "F.Paste")
			(net "P12VU")
		)
		(pad "2" smd rect
			(at 0 3.1496 90)
			(size 2.413 2.286)
			(layers "F.Cu" "F.Mask" "F.Paste")
			(net "GND")
		)
		(zone
			(layer "F.Cu")
			(hatch none 0.5)
			(connect_pads
				(clearance 0)
			)
			(min_thickness 0.25)
			(keepout
				(tracks allowed)
				(vias not_allowed)
				(pads allowed)
				(copperpour not_allowed)
				(footprints allowed)
			)
			(placement
				(enabled no)
				(sheetname "")
			)
			(fill
				(thermal_gap 0.5)
				(thermal_bridge_width 0.5)
				(island_removal_mode 0)
			)
			(polygon
				(pts
					(xy 22.0599 -107.9373) (xy 19.1516 -107.9373) (xy 19.1516 -104.9147) (xy 22.0472 -104.9147) (xy 22.3774 -104.9147)
					(xy 22.3774 -107.9373)
				)
			)
		)
		(zone
			(layer "F.Cu")
			(hatch none 0.5)
			(connect_pads
				(clearance 0)
			)
			(min_thickness 0.25)
			(keepout
				(tracks allowed)
				(vias not_allowed)
				(pads allowed)
				(copperpour not_allowed)
				(footprints allowed)
			)
			(placement
				(enabled no)
				(sheetname "")
			)
			(fill
				(thermal_gap 0.5)
				(thermal_bridge_width 0.5)
				(island_removal_mode 0)
			)
			(polygon
				(pts
					(xy 28.3464 -104.9147) (xy 28.3464 -107.9373) (xy 25.4508 -107.9373) (xy 25.1206 -107.9373) (xy 25.1206 -104.9147)
					(xy 25.4508 -104.9147)
				)
			)
		)
	)
	(footprint ""
		(layer "F.Cu")
		(at 5.4864 -449.4784 -90)
		(property "Reference" "R104"
			(at 0 0 270)
			(layer "F.SilkS")
			(hide yes)
			(effects
				(font
					(size 1.27 1.27)
				)
			)
		)
		(property "Value" "10KR2F-2-GP"
			(at 0.064008 -3.993896 270)
			(unlocked yes)
			(layer "F.Fab")
			(hide yes)
			(effects
				(font
					(size 1.016 1.016)
					(thickness 0.1524)
				)
			)
		)
		(property "Device Type" "R402H16"
			(at 0.064008 -5.517896 270)
			(unlocked yes)
			(layer "F.Fab")
			(hide yes)
			(effects
				(font
					(size 1.016 1.016)
					(thickness 0.1524)
				)
			)
		)
		(duplicate_pad_numbers_are_jumpers no)
		(fp_line
			(start -0.508 -0.9398)
			(end -0.508 0.9398)
			(stroke
				(width 0.1524)
				(type default)
			)
			(layer "F.SilkS")
		)
		(fp_line
			(start 0.508 -0.9398)
			(end -0.508 -0.9398)
			(stroke
				(width 0.1524)
				(type default)
			)
			(layer "F.SilkS")
		)
		(fp_rect
			(start -0.508 0.9398)
			(end 0.508 -0.9398)
			(stroke
				(width 0)
				(type default)
			)
			(fill no)
			(layer "F.CrtYd")
		)
		(fp_rect
			(start -0.508 0.9398)
			(end 0.508 -0.9398)
			(stroke
				(width 0)
				(type default)
			)
			(fill no)
			(layer "F.Fab")
		)
		(pad "1" smd custom
			(at 0 -0.4445 270)
			(size 0.1397 0.1397)
			(layers "F.Cu" "F.Mask" "F.Paste")
			(net "FANIN_1")
			(options
				(clearance outline)
				(anchor circle)
			)
			(primitives
				(gr_poly
					(pts
						(arc
							(start -0.1778 -0.2794)
							(mid -0.249642 -0.249642)
							(end -0.2794 -0.1778)
						)
						(arc
							(start -0.2794 0.1778)
							(mid -0.249642 0.249642)
							(end -0.1778 0.2794)
						)
						(arc
							(start 0.1778 0.2794)
							(mid 0.249642 0.249642)
							(end 0.2794 0.1778)
						)
						(arc
							(start 0.2794 -0.1778)
							(mid 0.249642 -0.249642)
							(end 0.1778 -0.2794)
						)
					)
					(width 0)
					(fill yes)
				)
			)
		)
		(pad "2" smd custom
			(at 0 0.4445 270)
			(size 0.1397 0.1397)
			(layers "F.Cu" "F.Mask" "F.Paste")
			(net "GND")
			(options
				(clearance outline)
				(anchor circle)
			)
			(primitives
				(gr_poly
					(pts
						(arc
							(start -0.1778 -0.2794)
							(mid -0.249642 -0.249642)
							(end -0.2794 -0.1778)
						)
						(arc
							(start -0.2794 0.1778)
							(mid -0.249642 0.249642)
							(end -0.1778 0.2794)
						)
						(arc
							(start 0.1778 0.2794)
							(mid 0.249642 0.249642)
							(end 0.2794 0.1778)
						)
						(arc
							(start 0.2794 -0.1778)
							(mid 0.249642 -0.249642)
							(end 0.1778 -0.2794)
						)
					)
					(width 0)
					(fill yes)
				)
			)
		)
	)
	(footprint ""
		(layer "F.Cu")
		(at 37.973 -147.4216 180)
		(property "Reference" "PC94"
			(at 0 0 180)
			(layer "F.SilkS")
			(hide yes)
			(effects
				(font
					(size 1.27 1.27)
				)
			)
		)
		(property "Value" "SC220P50V2KX-3GP"
			(at 1.1811 -2.7051 180)
			(unlocked yes)
			(layer "F.Fab")
			(hide yes)
			(effects
				(font
					(size 1.016 1.016)
					(thickness 0.1524)
				)
			)
		)
		(property "Device Type" "C402H22"
			(at 1.1811 -4.2291 180)
			(unlocked yes)
			(layer "F.Fab")
			(hide yes)
			(effects
				(font
					(size 1.016 1.016)
					(thickness 0.1524)
				)
			)
		)
		(duplicate_pad_numbers_are_jumpers no)
		(fp_rect
			(start -0.4318 0.9525)
			(end 0.4318 -0.9525)
			(stroke
				(width 0)
				(type default)
			)
			(fill no)
			(layer "F.CrtYd")
		)
		(fp_rect
			(start -0.4318 0.9525)
			(end 0.4318 -0.9525)
			(stroke
				(width 0)
				(type default)
			)
			(fill no)
			(layer "F.Fab")
		)
		(pad "1" smd custom
			(at 0 -0.4445 180)
			(size 0.1524 0.1524)
			(layers "F.Cu" "F.Mask" "F.Paste")
			(net "P12VL_2490_VREF")
			(options
				(clearance outline)
				(anchor circle)
			)
			(primitives
				(gr_poly
					(pts
						(arc
							(start 0.3048 -0.2032)
							(mid 0.275042 -0.275042)
							(end 0.2032 -0.3048)
						)
						(arc
							(start -0.2032 -0.3048)
							(mid -0.275042 -0.275042)
							(end -0.3048 -0.2032)
						)
						(arc
							(start -0.3048 0.2032)
							(mid -0.275042 0.275042)
							(end -0.2032 0.3048)
						)
						(arc
							(start 0.2032 0.3048)
							(mid 0.275042 0.275042)
							(end 0.3048 0.2032)
						)
					)
					(width 0)
					(fill yes)
				)
			)
		)
		(pad "2" smd custom
			(at 0 0.4445 180)
			(size 0.1524 0.1524)
			(layers "F.Cu" "F.Mask" "F.Paste")
			(net "GND")
			(options
				(clearance outline)
				(anchor circle)
			)
			(primitives
				(gr_poly
					(pts
						(arc
							(start 0.3048 -0.2032)
							(mid 0.275042 -0.275042)
							(end 0.2032 -0.3048)
						)
						(arc
							(start -0.2032 -0.3048)
							(mid -0.275042 -0.275042)
							(end -0.3048 -0.2032)
						)
						(arc
							(start -0.3048 0.2032)
							(mid -0.275042 0.275042)
							(end -0.2032 0.3048)
						)
						(arc
							(start 0.2032 0.3048)
							(mid 0.275042 0.275042)
							(end 0.3048 0.2032)
						)
					)
					(width 0)
					(fill yes)
				)
			)
		)
	)
	(footprint ""
		(layer "F.Cu")
		(at 39.243 -149.098 -90)
		(property "Reference" "PR108"
			(at 0 0 270)
			(layer "F.SilkS")
			(hide yes)
			(effects
				(font
					(size 1.27 1.27)
				)
			)
		)
		(property "Value" "6K81R2F-1-GP"
			(at 0.064008 -3.993896 270)
			(unlocked yes)
			(layer "F.Fab")
			(hide yes)
			(effects
				(font
					(size 1.016 1.016)
					(thickness 0.1524)
				)
			)
		)
		(property "Device Type" "R402H16"
			(at 0.064008 -5.517896 270)
			(unlocked yes)
			(layer "F.Fab")
			(hide yes)
			(effects
				(font
					(size 1.016 1.016)
					(thickness 0.1524)
				)
			)
		)
		(duplicate_pad_numbers_are_jumpers no)
		(fp_line
			(start -0.508 -0.9398)
			(end -0.508 0.9398)
			(stroke
				(width 0.1524)
				(type default)
			)
			(layer "F.SilkS")
		)
		(fp_line
			(start 0.508 -0.9398)
			(end -0.508 -0.9398)
			(stroke
				(width 0.1524)
				(type default)
			)
			(layer "F.SilkS")
		)
		(fp_rect
			(start -0.508 0.9398)
			(end 0.508 -0.9398)
			(stroke
				(width 0)
				(type default)
			)
			(fill no)
			(layer "F.CrtYd")
		)
		(fp_rect
			(start -0.508 0.9398)
			(end 0.508 -0.9398)
			(stroke
				(width 0)
				(type default)
			)
			(fill no)
			(layer "F.Fab")
		)
		(pad "1" smd custom
			(at 0 -0.4445 270)
			(size 0.1397 0.1397)
			(layers "F.Cu" "F.Mask" "F.Paste")
			(net "P12V")
			(options
				(clearance outline)
				(anchor circle)
			)
			(primitives
				(gr_poly
					(pts
						(arc
							(start -0.1778 -0.2794)
							(mid -0.249642 -0.249642)
							(end -0.2794 -0.1778)
						)
						(arc
							(start -0.2794 0.1778)
							(mid -0.249642 0.249642)
							(end -0.1778 0.2794)
						)
						(arc
							(start 0.1778 0.2794)
							(mid 0.249642 0.249642)
							(end 0.2794 0.1778)
						)
						(arc
							(start 0.2794 -0.1778)
							(mid 0.249642 -0.249642)
							(end 0.1778 -0.2794)
						)
					)
					(width 0)
					(fill yes)
				)
			)
		)
		(pad "2" smd custom
			(at 0 0.4445 270)
			(size 0.1397 0.1397)
			(layers "F.Cu" "F.Mask" "F.Paste")
			(net "P12VU_2490_EN_1")
			(options
				(clearance outline)
				(anchor circle)
			)
			(primitives
				(gr_poly
					(pts
						(arc
							(start -0.1778 -0.2794)
							(mid -0.249642 -0.249642)
							(end -0.2794 -0.1778)
						)
						(arc
							(start -0.2794 0.1778)
							(mid -0.249642 0.249642)
							(end -0.1778 0.2794)
						)
						(arc
							(start 0.1778 0.2794)
							(mid 0.249642 0.249642)
							(end 0.2794 0.1778)
						)
						(arc
							(start 0.2794 -0.1778)
							(mid 0.249642 -0.249642)
							(end 0.1778 -0.2794)
						)
					)
					(width 0)
					(fill yes)
				)
			)
		)
	)
	(footprint ""
		(layer "F.Cu")
		(at 7.239 -454.1012 -90)
		(property "Reference" "C45"
			(at 0 0 270)
			(layer "F.SilkS")
			(hide yes)
			(effects
				(font
					(size 1.27 1.27)
				)
			)
		)
		(property "Value" "SCD1U16V2KX-3GP"
			(at 1.1811 -2.7051 270)
			(unlocked yes)
			(layer "F.Fab")
			(hide yes)
			(effects
				(font
					(size 1.016 1.016)
					(thickness 0.1524)
				)
			)
		)
		(property "Device Type" "C402H22"
			(at 1.1811 -4.2291 270)
			(unlocked yes)
			(layer "F.Fab")
			(hide yes)
			(effects
				(font
					(size 1.016 1.016)
					(thickness 0.1524)
				)
			)
		)
		(duplicate_pad_numbers_are_jumpers no)
		(fp_rect
			(start -0.4318 0.9525)
			(end 0.4318 -0.9525)
			(stroke
				(width 0)
				(type default)
			)
			(fill no)
			(layer "F.CrtYd")
		)
		(fp_rect
			(start -0.4318 0.9525)
			(end 0.4318 -0.9525)
			(stroke
				(width 0)
				(type default)
			)
			(fill no)
			(layer "F.Fab")
		)
		(pad "1" smd custom
			(at 0 -0.4445 270)
			(size 0.1524 0.1524)
			(layers "F.Cu" "F.Mask" "F.Paste")
			(net "FAN_TACH1")
			(options
				(clearance outline)
				(anchor circle)
			)
			(primitives
				(gr_poly
					(pts
						(arc
							(start 0.3048 -0.2032)
							(mid 0.275042 -0.275042)
							(end 0.2032 -0.3048)
						)
						(arc
							(start -0.2032 -0.3048)
							(mid -0.275042 -0.275042)
							(end -0.3048 -0.2032)
						)
						(arc
							(start -0.3048 0.2032)
							(mid -0.275042 0.275042)
							(end -0.2032 0.3048)
						)
						(arc
							(start 0.2032 0.3048)
							(mid 0.275042 0.275042)
							(end 0.3048 0.2032)
						)
					)
					(width 0)
					(fill yes)
				)
			)
		)
		(pad "2" smd custom
			(at 0 0.4445 270)
			(size 0.1524 0.1524)
			(layers "F.Cu" "F.Mask" "F.Paste")
			(net "GND")
			(options
				(clearance outline)
				(anchor circle)
			)
			(primitives
				(gr_poly
					(pts
						(arc
							(start 0.3048 -0.2032)
							(mid 0.275042 -0.275042)
							(end 0.2032 -0.3048)
						)
						(arc
							(start -0.2032 -0.3048)
							(mid -0.275042 -0.275042)
							(end -0.3048 -0.2032)
						)
						(arc
							(start -0.3048 0.2032)
							(mid -0.275042 0.275042)
							(end -0.2032 0.3048)
						)
						(arc
							(start 0.2032 0.3048)
							(mid 0.275042 0.275042)
							(end 0.3048 0.2032)
						)
					)
					(width 0)
					(fill yes)
				)
			)
		)
	)
	(footprint ""
		(layer "F.Cu")
		(at 17.271492 -13.919962 180)
		(property "Reference" "R69"
			(at 0 0 180)
			(layer "F.SilkS")
			(hide yes)
			(effects
				(font
					(size 1.27 1.27)
				)
			)
		)
		(property "Value" "4K7R2F-GP"
			(at 0.064008 -3.993896 180)
			(unlocked yes)
			(layer "F.Fab")
			(hide yes)
			(effects
				(font
					(size 1.016 1.016)
					(thickness 0.1524)
				)
			)
		)
		(property "Device Type" "R402H16"
			(at 0.064008 -5.517896 180)
			(unlocked yes)
			(layer "F.Fab")
			(hide yes)
			(effects
				(font
					(size 1.016 1.016)
					(thickness 0.1524)
				)
			)
		)
		(duplicate_pad_numbers_are_jumpers no)
		(fp_line
			(start 0.508 -0.9398)
			(end -0.508 -0.9398)
			(stroke
				(width 0.1524)
				(type default)
			)
			(layer "F.SilkS")
		)
		(fp_line
			(start -0.508 -0.9398)
			(end -0.508 0.9398)
			(stroke
				(width 0.1524)
				(type default)
			)
			(layer "F.SilkS")
		)
		(fp_rect
			(start -0.508 0.9398)
			(end 0.508 -0.9398)
			(stroke
				(width 0)
				(type default)
			)
			(fill no)
			(layer "F.CrtYd")
		)
		(fp_rect
			(start -0.508 0.9398)
			(end 0.508 -0.9398)
			(stroke
				(width 0)
				(type default)
			)
			(fill no)
			(layer "F.Fab")
		)
		(pad "1" smd custom
			(at 0 -0.4445 180)
			(size 0.1397 0.1397)
			(layers "F.Cu" "F.Mask" "F.Paste")
			(net "P12V")
			(options
				(clearance outline)
				(anchor circle)
			)
			(primitives
				(gr_poly
					(pts
						(arc
							(start -0.1778 -0.2794)
							(mid -0.249642 -0.249642)
							(end -0.2794 -0.1778)
						)
						(arc
							(start -0.2794 0.1778)
							(mid -0.249642 0.249642)
							(end -0.1778 0.2794)
						)
						(arc
							(start 0.1778 0.2794)
							(mid 0.249642 0.249642)
							(end 0.2794 0.1778)
						)
						(arc
							(start 0.2794 -0.1778)
							(mid 0.249642 -0.249642)
							(end 0.1778 -0.2794)
						)
					)
					(width 0)
					(fill yes)
				)
			)
		)
		(pad "2" smd custom
			(at 0 0.4445 180)
			(size 0.1397 0.1397)
			(layers "F.Cu" "F.Mask" "F.Paste")
			(net "FAN_TACH11")
			(options
				(clearance outline)
				(anchor circle)
			)
			(primitives
				(gr_poly
					(pts
						(arc
							(start -0.1778 -0.2794)
							(mid -0.249642 -0.249642)
							(end -0.2794 -0.1778)
						)
						(arc
							(start -0.2794 0.1778)
							(mid -0.249642 0.249642)
							(end -0.1778 0.2794)
						)
						(arc
							(start 0.1778 0.2794)
							(mid 0.249642 0.249642)
							(end 0.2794 0.1778)
						)
						(arc
							(start 0.2794 -0.1778)
							(mid 0.249642 -0.249642)
							(end 0.1778 -0.2794)
						)
					)
					(width 0)
					(fill yes)
				)
			)
		)
	)
	(footprint ""
		(layer "F.Cu")
		(at 34.798 -381 180)
		(property "Reference" "PR24"
			(at 0 0 180)
			(layer "F.SilkS")
			(hide yes)
			(effects
				(font
					(size 1.27 1.27)
				)
			)
		)
		(property "Value" "10R2F-L-GP"
			(at 0.064008 -3.993896 180)
			(unlocked yes)
			(layer "F.Fab")
			(hide yes)
			(effects
				(font
					(size 1.016 1.016)
					(thickness 0.1524)
				)
			)
		)
		(property "Device Type" "R402H14"
			(at 0.064008 -5.517896 180)
			(unlocked yes)
			(layer "F.Fab")
			(hide yes)
			(effects
				(font
					(size 1.016 1.016)
					(thickness 0.1524)
				)
			)
		)
		(duplicate_pad_numbers_are_jumpers no)
		(fp_line
			(start 0.508 -0.9398)
			(end -0.508 -0.9398)
			(stroke
				(width 0.1524)
				(type default)
			)
			(layer "F.SilkS")
		)
		(fp_line
			(start -0.508 -0.9398)
			(end -0.508 0.9398)
			(stroke
				(width 0.1524)
				(type default)
			)
			(layer "F.SilkS")
		)
		(fp_rect
			(start -0.508 0.9398)
			(end 0.508 -0.9398)
			(stroke
				(width 0)
				(type default)
			)
			(fill no)
			(layer "F.CrtYd")
		)
		(fp_rect
			(start -0.508 0.9398)
			(end 0.508 -0.9398)
			(stroke
				(width 0)
				(type default)
			)
			(fill no)
			(layer "F.Fab")
		)
		(pad "1" smd custom
			(at 0 -0.4445 180)
			(size 0.1397 0.1397)
			(layers "F.Cu" "F.Mask" "F.Paste")
			(net "ADM1276_SENSE-")
			(options
				(clearance outline)
				(anchor circle)
			)
			(primitives
				(gr_poly
					(pts
						(arc
							(start -0.1778 -0.2794)
							(mid -0.249642 -0.249642)
							(end -0.2794 -0.1778)
						)
						(arc
							(start -0.2794 0.1778)
							(mid -0.249642 0.249642)
							(end -0.1778 0.2794)
						)
						(arc
							(start 0.1778 0.2794)
							(mid 0.249642 0.249642)
							(end 0.2794 0.1778)
						)
						(arc
							(start 0.2794 -0.1778)
							(mid 0.249642 -0.249642)
							(end 0.1778 -0.2794)
						)
					)
					(width 0)
					(fill yes)
				)
			)
		)
		(pad "2" smd custom
			(at 0 0.4445 180)
			(size 0.1397 0.1397)
			(layers "F.Cu" "F.Mask" "F.Paste")
			(net "SENSE-_R4")
			(options
				(clearance outline)
				(anchor circle)
			)
			(primitives
				(gr_poly
					(pts
						(arc
							(start -0.1778 -0.2794)
							(mid -0.249642 -0.249642)
							(end -0.2794 -0.1778)
						)
						(arc
							(start -0.2794 0.1778)
							(mid -0.249642 0.249642)
							(end -0.1778 0.2794)
						)
						(arc
							(start 0.1778 0.2794)
							(mid 0.249642 0.249642)
							(end 0.2794 0.1778)
						)
						(arc
							(start 0.2794 -0.1778)
							(mid 0.249642 -0.249642)
							(end 0.1778 -0.2794)
						)
					)
					(width 0)
					(fill yes)
				)
			)
		)
	)
	(footprint ""
		(layer "F.Cu")
		(at 25.146 -248.412 180)
		(property "Reference" "PR55"
			(at 0 0 180)
			(layer "F.SilkS")
			(hide yes)
			(effects
				(font
					(size 1.27 1.27)
				)
			)
		)
		(property "Value" "100KR2F-L1-GP"
			(at 0.064008 -3.993896 180)
			(unlocked yes)
			(layer "F.Fab")
			(hide yes)
			(effects
				(font
					(size 1.016 1.016)
					(thickness 0.1524)
				)
			)
		)
		(property "Device Type" "R402H16"
			(at 0.064008 -5.517896 180)
			(unlocked yes)
			(layer "F.Fab")
			(hide yes)
			(effects
				(font
					(size 1.016 1.016)
					(thickness 0.1524)
				)
			)
		)
		(duplicate_pad_numbers_are_jumpers no)
		(fp_line
			(start 0.508 -0.9398)
			(end -0.508 -0.9398)
			(stroke
				(width 0.1524)
				(type default)
			)
			(layer "F.SilkS")
		)
		(fp_line
			(start -0.508 -0.9398)
			(end -0.508 0.9398)
			(stroke
				(width 0.1524)
				(type default)
			)
			(layer "F.SilkS")
		)
		(fp_rect
			(start -0.508 0.9398)
			(end 0.508 -0.9398)
			(stroke
				(width 0)
				(type default)
			)
			(fill no)
			(layer "F.CrtYd")
		)
		(fp_rect
			(start -0.508 0.9398)
			(end 0.508 -0.9398)
			(stroke
				(width 0)
				(type default)
			)
			(fill no)
			(layer "F.Fab")
		)
		(pad "1" smd custom
			(at 0 -0.4445 180)
			(size 0.1397 0.1397)
			(layers "F.Cu" "F.Mask" "F.Paste")
			(net "P3V3_LX_REV")
			(options
				(clearance outline)
				(anchor circle)
			)
			(primitives
				(gr_poly
					(pts
						(arc
							(start -0.1778 -0.2794)
							(mid -0.249642 -0.249642)
							(end -0.2794 -0.1778)
						)
						(arc
							(start -0.2794 0.1778)
							(mid -0.249642 0.249642)
							(end -0.1778 0.2794)
						)
						(arc
							(start 0.1778 0.2794)
							(mid 0.249642 0.249642)
							(end 0.2794 0.1778)
						)
						(arc
							(start 0.2794 -0.1778)
							(mid 0.249642 -0.249642)
							(end 0.1778 -0.2794)
						)
					)
					(width 0)
					(fill yes)
				)
			)
		)
		(pad "2" smd custom
			(at 0 0.4445 180)
			(size 0.1397 0.1397)
			(layers "F.Cu" "F.Mask" "F.Paste")
			(net "P3V3_FB")
			(options
				(clearance outline)
				(anchor circle)
			)
			(primitives
				(gr_poly
					(pts
						(arc
							(start -0.1778 -0.2794)
							(mid -0.249642 -0.249642)
							(end -0.2794 -0.1778)
						)
						(arc
							(start -0.2794 0.1778)
							(mid -0.249642 0.249642)
							(end -0.1778 0.2794)
						)
						(arc
							(start 0.1778 0.2794)
							(mid 0.249642 0.249642)
							(end 0.2794 0.1778)
						)
						(arc
							(start 0.2794 -0.1778)
							(mid 0.249642 -0.249642)
							(end 0.1778 -0.2794)
						)
					)
					(width 0)
					(fill yes)
				)
			)
		)
	)
	(footprint ""
		(layer "F.Cu")
		(at 19.6088 -178.8668 180)
		(property "Reference" "R91"
			(at 0 0 180)
			(layer "F.SilkS")
			(hide yes)
			(effects
				(font
					(size 1.27 1.27)
				)
			)
		)
		(property "Value" "10KR2F-2-GP"
			(at 0.064008 -3.993896 180)
			(unlocked yes)
			(layer "F.Fab")
			(hide yes)
			(effects
				(font
					(size 1.016 1.016)
					(thickness 0.1524)
				)
			)
		)
		(property "Device Type" "R402H16"
			(at 0.064008 -5.517896 180)
			(unlocked yes)
			(layer "F.Fab")
			(hide yes)
			(effects
				(font
					(size 1.016 1.016)
					(thickness 0.1524)
				)
			)
		)
		(duplicate_pad_numbers_are_jumpers no)
		(fp_line
			(start 0.508 -0.9398)
			(end -0.508 -0.9398)
			(stroke
				(width 0.1524)
				(type default)
			)
			(layer "F.SilkS")
		)
		(fp_line
			(start -0.508 -0.9398)
			(end -0.508 0.9398)
			(stroke
				(width 0.1524)
				(type default)
			)
			(layer "F.SilkS")
		)
		(fp_rect
			(start -0.508 0.9398)
			(end 0.508 -0.9398)
			(stroke
				(width 0)
				(type default)
			)
			(fill no)
			(layer "F.CrtYd")
		)
		(fp_rect
			(start -0.508 0.9398)
			(end 0.508 -0.9398)
			(stroke
				(width 0)
				(type default)
			)
			(fill no)
			(layer "F.Fab")
		)
		(pad "1" smd custom
			(at 0 -0.4445 180)
			(size 0.1397 0.1397)
			(layers "F.Cu" "F.Mask" "F.Paste")
			(net "FANIN_7")
			(options
				(clearance outline)
				(anchor circle)
			)
			(primitives
				(gr_poly
					(pts
						(arc
							(start -0.1778 -0.2794)
							(mid -0.249642 -0.249642)
							(end -0.2794 -0.1778)
						)
						(arc
							(start -0.2794 0.1778)
							(mid -0.249642 0.249642)
							(end -0.1778 0.2794)
						)
						(arc
							(start 0.1778 0.2794)
							(mid 0.249642 0.249642)
							(end 0.2794 0.1778)
						)
						(arc
							(start 0.2794 -0.1778)
							(mid 0.249642 -0.249642)
							(end 0.1778 -0.2794)
						)
					)
					(width 0)
					(fill yes)
				)
			)
		)
		(pad "2" smd custom
			(at 0 0.4445 180)
			(size 0.1397 0.1397)
			(layers "F.Cu" "F.Mask" "F.Paste")
			(net "GND")
			(options
				(clearance outline)
				(anchor circle)
			)
			(primitives
				(gr_poly
					(pts
						(arc
							(start -0.1778 -0.2794)
							(mid -0.249642 -0.249642)
							(end -0.2794 -0.1778)
						)
						(arc
							(start -0.2794 0.1778)
							(mid -0.249642 0.249642)
							(end -0.1778 0.2794)
						)
						(arc
							(start 0.1778 0.2794)
							(mid 0.249642 0.249642)
							(end 0.2794 0.1778)
						)
						(arc
							(start 0.2794 -0.1778)
							(mid 0.249642 -0.249642)
							(end 0.1778 -0.2794)
						)
					)
					(width 0)
					(fill yes)
				)
			)
		)
	)
	(footprint ""
		(layer "F.Cu")
		(at 20.0406 -383.8194)
		(property "Reference" "TC11"
			(at 0 0 0)
			(layer "F.SilkS")
			(hide yes)
			(effects
				(font
					(size 1.27 1.27)
				)
			)
		)
		(property "Value" "ST68U16VDM-1-GP"
			(at 0 -9.6012 0)
			(unlocked yes)
			(layer "F.Fab")
			(hide yes)
			(effects
				(font
					(size 1.016 1.016)
					(thickness 0.1524)
				)
			)
		)
		(property "Device Type" "CT7343H79"
			(at 0 -11.1252 0)
			(unlocked yes)
			(layer "F.Fab")
			(hide yes)
			(effects
				(font
					(size 1.016 1.016)
					(thickness 0.1524)
				)
			)
		)
		(duplicate_pad_numbers_are_jumpers no)
		(fp_line
			(start -2.286 -4.8768)
			(end -2.286 -2.032)
			(stroke
				(width 0.1524)
				(type default)
			)
			(layer "F.SilkS")
		)
		(fp_line
			(start -2.286 4.8768)
			(end -2.286 2.032)
			(stroke
				(width 0.1524)
				(type default)
			)
			(layer "F.SilkS")
		)
		(fp_line
			(start 2.1082 -4.699)
			(end -2.1082 -4.699)
			(stroke
				(width 0.508)
				(type default)
			)
			(layer "F.SilkS")
		)
		(fp_line
			(start 2.286 -4.8768)
			(end -2.286 -4.8768)
			(stroke
				(width 0.1524)
				(type default)
			)
			(layer "F.SilkS")
		)
		(fp_line
			(start 2.286 -2.032)
			(end 2.286 -4.8768)
			(stroke
				(width 0.1524)
				(type default)
			)
			(layer "F.SilkS")
		)
		(fp_line
			(start 2.286 2.032)
			(end 2.286 4.8768)
			(stroke
				(width 0.1524)
				(type default)
			)
			(layer "F.SilkS")
		)
		(fp_line
			(start 2.286 4.8768)
			(end -2.286 4.8768)
			(stroke
				(width 0.1524)
				(type default)
			)
			(layer "F.SilkS")
		)
		(fp_rect
			(start -2.1463 3.6449)
			(end 2.1463 -3.6449)
			(stroke
				(width 0)
				(type default)
			)
			(fill no)
			(layer "F.CrtYd")
		)
		(fp_poly
			(pts
				(xy -2.54 4.953) (xy -2.54 4.2926) (xy -3.81 4.2926) (xy -3.81 -4.2926) (xy -2.54 -4.2926) (xy -2.54 -4.953)
				(xy 2.54 -4.953) (xy 2.54 -4.2926) (xy 3.81 -4.2926) (xy 3.81 -1.6256) (xy 2.1463 -1.6256) (xy 2.1463 -3.6449)
				(xy -2.1463 -3.6449) (xy -2.1463 3.6449) (xy 2.1463 3.6449) (xy 2.1463 -1.6129) (xy 3.81 -1.6129)
				(xy 3.81 4.2926) (xy 2.54 4.2926) (xy 2.54 4.953)
			)
			(stroke
				(width 0)
				(type default)
			)
			(fill no)
			(layer "F.CrtYd")
		)
		(fp_rect
			(start -3.81 4.2926)
			(end -2.54 -4.2926)
			(stroke
				(width 0)
				(type default)
			)
			(fill no)
			(layer "F.Fab")
		)
		(fp_rect
			(start -2.54 4.953)
			(end 2.54 -4.953)
			(stroke
				(width 0)
				(type default)
			)
			(fill no)
			(layer "F.Fab")
		)
		(fp_rect
			(start 2.54 4.2926)
			(end 3.81 -4.2926)
			(stroke
				(width 0)
				(type default)
			)
			(fill no)
			(layer "F.Fab")
		)
		(pad "1" smd rect
			(at 0 -3.1496)
			(size 2.413 2.286)
			(layers "F.Cu" "F.Mask" "F.Paste")
			(net "P12V")
		)
		(pad "2" smd rect
			(at 0 3.1496)
			(size 2.413 2.286)
			(layers "F.Cu" "F.Mask" "F.Paste")
			(net "GND")
		)
		(zone
			(layer "F.Cu")
			(hatch none 0.5)
			(connect_pads
				(clearance 0)
			)
			(min_thickness 0.25)
			(keepout
				(tracks allowed)
				(vias not_allowed)
				(pads allowed)
				(copperpour not_allowed)
				(footprints allowed)
			)
			(placement
				(enabled no)
				(sheetname "")
			)
			(fill
				(thermal_gap 0.5)
				(thermal_bridge_width 0.5)
				(island_removal_mode 0)
			)
			(polygon
				(pts
					(xy 18.5293 -379.222) (xy 21.5519 -379.222) (xy 21.5519 -382.1176) (xy 21.5519 -382.4478) (xy 18.5293 -382.4478)
					(xy 18.5293 -382.1176)
				)
			)
		)
		(zone
			(layer "F.Cu")
			(hatch none 0.5)
			(connect_pads
				(clearance 0)
			)
			(min_thickness 0.25)
			(keepout
				(tracks allowed)
				(vias not_allowed)
				(pads allowed)
				(copperpour not_allowed)
				(footprints allowed)
			)
			(placement
				(enabled no)
				(sheetname "")
			)
			(fill
				(thermal_gap 0.5)
				(thermal_bridge_width 0.5)
				(island_removal_mode 0)
			)
			(polygon
				(pts
					(xy 21.5519 -385.5085) (xy 21.5519 -388.4168) (xy 18.5293 -388.4168) (xy 18.5293 -385.5212) (xy 18.5293 -385.191)
					(xy 21.5519 -385.191)
				)
			)
		)
	)
	(footprint ""
		(layer "F.Cu")
		(at 5.993384 -65.735962 180)
		(property "Reference" "Q3"
			(at 0 0 180)
			(layer "F.SilkS")
			(hide yes)
			(effects
				(font
					(size 1.27 1.27)
				)
			)
		)
		(property "Value" "PMBS3904-1-GP"
			(at 0 -9.0932 180)
			(unlocked yes)
			(layer "F.Fab")
			(hide yes)
			(effects
				(font
					(size 1.016 1.016)
					(thickness 0.1524)
				)
			)
		)
		(property "Device Type" "SOT-23-10H44"
			(at 0 -10.6172 180)
			(unlocked yes)
			(layer "F.Fab")
			(hide yes)
			(effects
				(font
					(size 1.016 1.016)
					(thickness 0.1524)
				)
			)
		)
		(duplicate_pad_numbers_are_jumpers no)
		(fp_line
			(start 1.651 1.778)
			(end 1.651 -1.778)
			(stroke
				(width 0.1524)
				(type default)
			)
			(layer "F.SilkS")
		)
		(fp_line
			(start 1.651 -1.778)
			(end -1.651 -1.778)
			(stroke
				(width 0.1524)
				(type default)
			)
			(layer "F.SilkS")
		)
		(fp_line
			(start -0.635 1.8796)
			(end -1.7526 1.8796)
			(stroke
				(width 0.3302)
				(type default)
			)
			(layer "F.SilkS")
		)
		(fp_line
			(start -0.71628 2.15265)
			(end -1.26492 2.15265)
			(stroke
				(width 0.0127)
				(type default)
			)
			(layer "F.SilkS")
		)
		(fp_line
			(start -0.719074 2.145538)
			(end -1.265936 2.14122)
			(stroke
				(width 0.0127)
				(type default)
			)
			(layer "F.SilkS")
		)
		(fp_line
			(start -0.9906 1.86309)
			(end -0.701294 2.15265)
			(stroke
				(width 0.0127)
				(type default)
			)
			(layer "F.SilkS")
		)
		(fp_line
			(start -0.994156 1.8669)
			(end -0.987044 1.8669)
			(stroke
				(width 0.0127)
				(type default)
			)
			(layer "F.SilkS")
		)
		(fp_line
			(start -1.003808 1.876552)
			(end -0.977646 1.876552)
			(stroke
				(width 0.0127)
				(type default)
			)
			(layer "F.SilkS")
		)
		(fp_line
			(start -1.013206 1.88595)
			(end -0.967994 1.88595)
			(stroke
				(width 0.0127)
				(type default)
			)
			(layer "F.SilkS")
		)
		(fp_line
			(start -1.022858 1.895602)
			(end -0.958596 1.895602)
			(stroke
				(width 0.0127)
				(type default)
			)
			(layer "F.SilkS")
		)
		(fp_line
			(start -1.032256 1.905)
			(end -0.948944 1.905)
			(stroke
				(width 0.0127)
				(type default)
			)
			(layer "F.SilkS")
		)
		(fp_line
			(start -1.041908 1.914652)
			(end -0.939546 1.914652)
			(stroke
				(width 0.0127)
				(type default)
			)
			(layer "F.SilkS")
		)
		(fp_line
			(start -1.051306 1.92405)
			(end -0.929894 1.92405)
			(stroke
				(width 0.0127)
				(type default)
			)
			(layer "F.SilkS")
		)
		(fp_line
			(start -1.060958 1.933702)
			(end -0.920496 1.933702)
			(stroke
				(width 0.0127)
				(type default)
			)
			(layer "F.SilkS")
		)
		(fp_line
			(start -1.070356 1.9431)
			(end -0.910844 1.9431)
			(stroke
				(width 0.0127)
				(type default)
			)
			(layer "F.SilkS")
		)
		(fp_line
			(start -1.080008 1.952752)
			(end -0.901446 1.952752)
			(stroke
				(width 0.0127)
				(type default)
			)
			(layer "F.SilkS")
		)
		(fp_line
			(start -1.089406 1.96215)
			(end -0.891794 1.96215)
			(stroke
				(width 0.0127)
				(type default)
			)
			(layer "F.SilkS")
		)
		(fp_line
			(start -1.099058 1.971802)
			(end -0.882396 1.971802)
			(stroke
				(width 0.0127)
				(type default)
			)
			(layer "F.SilkS")
		)
		(fp_line
			(start -1.108456 1.9812)
			(end -0.872744 1.9812)
			(stroke
				(width 0.0127)
				(type default)
			)
			(layer "F.SilkS")
		)
		(fp_line
			(start -1.118108 1.990852)
			(end -0.863346 1.990852)
			(stroke
				(width 0.0127)
				(type default)
			)
			(layer "F.SilkS")
		)
		(fp_line
			(start -1.127506 2.00025)
			(end -0.853694 2.00025)
			(stroke
				(width 0.0127)
				(type default)
			)
			(layer "F.SilkS")
		)
		(fp_line
			(start -1.137158 2.009902)
			(end -0.844296 2.009902)
			(stroke
				(width 0.0127)
				(type default)
			)
			(layer "F.SilkS")
		)
		(fp_line
			(start -1.146556 2.0193)
			(end -0.834644 2.0193)
			(stroke
				(width 0.0127)
				(type default)
			)
			(layer "F.SilkS")
		)
		(fp_line
			(start -1.156208 2.028952)
			(end -0.825246 2.028952)
			(stroke
				(width 0.0127)
				(type default)
			)
			(layer "F.SilkS")
		)
		(fp_line
			(start -1.165606 2.03835)
			(end -0.815594 2.03835)
			(stroke
				(width 0.0127)
				(type default)
			)
			(layer "F.SilkS")
		)
		(fp_line
			(start -1.175258 2.048002)
			(end -0.806196 2.048002)
			(stroke
				(width 0.0127)
				(type default)
			)
			(layer "F.SilkS")
		)
		(fp_line
			(start -1.184656 2.0574)
			(end -0.796544 2.0574)
			(stroke
				(width 0.0127)
				(type default)
			)
			(layer "F.SilkS")
		)
		(fp_line
			(start -1.194308 2.067052)
			(end -0.787146 2.067052)
			(stroke
				(width 0.0127)
				(type default)
			)
			(layer "F.SilkS")
		)
		(fp_line
			(start -1.203706 2.07645)
			(end -0.777494 2.07645)
			(stroke
				(width 0.0127)
				(type default)
			)
			(layer "F.SilkS")
		)
		(fp_line
			(start -1.213358 2.086102)
			(end -0.768096 2.086102)
			(stroke
				(width 0.0127)
				(type default)
			)
			(layer "F.SilkS")
		)
		(fp_line
			(start -1.222756 2.0955)
			(end -0.758444 2.0955)
			(stroke
				(width 0.0127)
				(type default)
			)
			(layer "F.SilkS")
		)
		(fp_line
			(start -1.232408 2.105152)
			(end -0.749046 2.105152)
			(stroke
				(width 0.0127)
				(type default)
			)
			(layer "F.SilkS")
		)
		(fp_line
			(start -1.241806 2.11455)
			(end -0.739394 2.11455)
			(stroke
				(width 0.0127)
				(type default)
			)
			(layer "F.SilkS")
		)
		(fp_line
			(start -1.251458 2.124202)
			(end -0.729996 2.124202)
			(stroke
				(width 0.0127)
				(type default)
			)
			(layer "F.SilkS")
		)
		(fp_line
			(start -1.260856 2.1336)
			(end -0.720344 2.1336)
			(stroke
				(width 0.0127)
				(type default)
			)
			(layer "F.SilkS")
		)
		(fp_line
			(start -1.279144 2.15265)
			(end -0.701294 2.15265)
			(stroke
				(width 0.0127)
				(type default)
			)
			(layer "F.SilkS")
		)
		(fp_line
			(start -1.279398 2.152142)
			(end -0.9906 1.86309)
			(stroke
				(width 0.0127)
				(type default)
			)
			(layer "F.SilkS")
		)
		(fp_line
			(start -1.651 1.778)
			(end 1.651 1.778)
			(stroke
				(width 0.1524)
				(type default)
			)
			(layer "F.SilkS")
		)
		(fp_line
			(start -1.651 -1.778)
			(end -1.651 1.778)
			(stroke
				(width 0.1524)
				(type default)
			)
			(layer "F.SilkS")
		)
		(fp_line
			(start -1.7526 1.8796)
			(end -1.7526 0.9906)
			(stroke
				(width 0.3302)
				(type default)
			)
			(layer "F.SilkS")
		)
		(fp_poly
			(pts
				(xy -1.285748 2.159) (xy -1.285748 1.8796) (xy -1.778 1.8796) (xy -1.778 -1.8796) (xy 1.778 -1.8796)
				(xy 1.778 1.8796) (xy -0.694944 1.8796) (xy -0.694944 2.159)
			)
			(stroke
				(width 0)
				(type default)
			)
			(fill no)
			(layer "F.CrtYd")
		)
		(fp_poly
			(pts
				(xy -1.285748 2.159) (xy -1.285748 1.8796) (xy -1.778 1.8796) (xy -1.778 -1.8796) (xy 1.778 -1.8796)
				(xy 1.778 1.8796) (xy -0.694944 1.8796) (xy -0.694944 2.159)
			)
			(stroke
				(width 0)
				(type default)
			)
			(fill no)
			(layer "F.Fab")
		)
		(pad "1" smd rect
			(at -0.98425 0.9525 180)
			(size 0.762 1.143)
			(layers "F.Cu" "F.Mask" "F.Paste")
			(net "LED_DR_LED5_B")
		)
		(pad "2" smd rect
			(at 0.98425 0.9525 180)
			(size 0.762 1.143)
			(layers "F.Cu" "F.Mask" "F.Paste")
			(net "GND")
		)
		(pad "3" smd rect
			(at 0 -0.9525 180)
			(size 0.762 1.143)
			(layers "F.Cu" "F.Mask" "F.Paste")
			(net "LED_DR_LED5_BLUE")
		)
	)
	(footprint ""
		(layer "F.Cu")
		(at 43.9166 -101.0666 90)
		(property "Reference" "TC8"
			(at 0 0 90)
			(layer "F.SilkS")
			(hide yes)
			(effects
				(font
					(size 1.27 1.27)
				)
			)
		)
		(property "Value" "ST15U25VDM-1-GP"
			(at 0 -9.6012 90)
			(unlocked yes)
			(layer "F.Fab")
			(hide yes)
			(effects
				(font
					(size 1.016 1.016)
					(thickness 0.1524)
				)
			)
		)
		(property "Device Type" "CT7343H79"
			(at 0 -11.1252 90)
			(unlocked yes)
			(layer "F.Fab")
			(hide yes)
			(effects
				(font
					(size 1.016 1.016)
					(thickness 0.1524)
				)
			)
		)
		(duplicate_pad_numbers_are_jumpers no)
		(fp_line
			(start 2.286 -4.8768)
			(end -2.286 -4.8768)
			(stroke
				(width 0.1524)
				(type default)
			)
			(layer "F.SilkS")
		)
		(fp_line
			(start -2.286 -4.8768)
			(end -2.286 -2.032)
			(stroke
				(width 0.1524)
				(type default)
			)
			(layer "F.SilkS")
		)
		(fp_line
			(start 2.1082 -4.699)
			(end -2.1082 -4.699)
			(stroke
				(width 0.508)
				(type default)
			)
			(layer "F.SilkS")
		)
		(fp_line
			(start 2.286 -2.032)
			(end 2.286 -4.8768)
			(stroke
				(width 0.1524)
				(type default)
			)
			(layer "F.SilkS")
		)
		(fp_line
			(start 2.286 2.032)
			(end 2.286 4.8768)
			(stroke
				(width 0.1524)
				(type default)
			)
			(layer "F.SilkS")
		)
		(fp_line
			(start 2.286 4.8768)
			(end -2.286 4.8768)
			(stroke
				(width 0.1524)
				(type default)
			)
			(layer "F.SilkS")
		)
		(fp_line
			(start -2.286 4.8768)
			(end -2.286 2.032)
			(stroke
				(width 0.1524)
				(type default)
			)
			(layer "F.SilkS")
		)
		(fp_rect
			(start -2.1463 3.6449)
			(end 2.1463 -3.6449)
			(stroke
				(width 0)
				(type default)
			)
			(fill no)
			(layer "F.CrtYd")
		)
		(fp_poly
			(pts
				(xy -2.54 4.953) (xy -2.54 4.2926) (xy -3.81 4.2926) (xy -3.81 -4.2926) (xy -2.54 -4.2926) (xy -2.54 -4.953)
				(xy 2.54 -4.953) (xy 2.54 -4.2926) (xy 3.81 -4.2926) (xy 3.81 -1.6256) (xy 2.1463 -1.6256) (xy 2.1463 -3.6449)
				(xy -2.1463 -3.6449) (xy -2.1463 3.6449) (xy 2.1463 3.6449) (xy 2.1463 -1.6129) (xy 3.81 -1.6129)
				(xy 3.81 4.2926) (xy 2.54 4.2926) (xy 2.54 4.953)
			)
			(stroke
				(width 0)
				(type default)
			)
			(fill no)
			(layer "F.CrtYd")
		)
		(fp_rect
			(start 2.54 4.2926)
			(end 3.81 -4.2926)
			(stroke
				(width 0)
				(type default)
			)
			(fill no)
			(layer "F.Fab")
		)
		(fp_rect
			(start -3.81 4.2926)
			(end -2.54 -4.2926)
			(stroke
				(width 0)
				(type default)
			)
			(fill no)
			(layer "F.Fab")
		)
		(fp_rect
			(start -2.54 4.953)
			(end 2.54 -4.953)
			(stroke
				(width 0)
				(type default)
			)
			(fill no)
			(layer "F.Fab")
		)
		(pad "1" smd rect
			(at 0 -3.1496 90)
			(size 2.413 2.286)
			(layers "F.Cu" "F.Mask" "F.Paste")
			(net "P12VL")
		)
		(pad "2" smd rect
			(at 0 3.1496 90)
			(size 2.413 2.286)
			(layers "F.Cu" "F.Mask" "F.Paste")
			(net "GND")
		)
		(zone
			(layer "F.Cu")
			(hatch none 0.5)
			(connect_pads
				(clearance 0)
			)
			(min_thickness 0.25)
			(keepout
				(tracks allowed)
				(vias not_allowed)
				(pads allowed)
				(copperpour not_allowed)
				(footprints allowed)
			)
			(placement
				(enabled no)
				(sheetname "")
			)
			(fill
				(thermal_gap 0.5)
				(thermal_bridge_width 0.5)
				(island_removal_mode 0)
			)
			(polygon
				(pts
					(xy 42.2275 -102.5779) (xy 39.3192 -102.5779) (xy 39.3192 -99.5553) (xy 42.2148 -99.5553) (xy 42.545 -99.5553)
					(xy 42.545 -102.5779)
				)
			)
		)
		(zone
			(layer "F.Cu")
			(hatch none 0.5)
			(connect_pads
				(clearance 0)
			)
			(min_thickness 0.25)
			(keepout
				(tracks allowed)
				(vias not_allowed)
				(pads allowed)
				(copperpour not_allowed)
				(footprints allowed)
			)
			(placement
				(enabled no)
				(sheetname "")
			)
			(fill
				(thermal_gap 0.5)
				(thermal_bridge_width 0.5)
				(island_removal_mode 0)
			)
			(polygon
				(pts
					(xy 48.514 -99.5553) (xy 48.514 -102.5779) (xy 45.6184 -102.5779) (xy 45.2882 -102.5779) (xy 45.2882 -99.5553)
					(xy 45.6184 -99.5553)
				)
			)
		)
	)
	(footprint ""
		(layer "F.Cu")
		(at 19.9644 -145.4912 180)
		(property "Reference" "PR114"
			(at 0 0 180)
			(layer "F.SilkS")
			(hide yes)
			(effects
				(font
					(size 1.27 1.27)
				)
			)
		)
		(property "Value" "20KR2F-L-GP"
			(at 0.064008 -3.993896 180)
			(unlocked yes)
			(layer "F.Fab")
			(hide yes)
			(effects
				(font
					(size 1.016 1.016)
					(thickness 0.1524)
				)
			)
		)
		(property "Device Type" "R402H16"
			(at 0.064008 -5.517896 180)
			(unlocked yes)
			(layer "F.Fab")
			(hide yes)
			(effects
				(font
					(size 1.016 1.016)
					(thickness 0.1524)
				)
			)
		)
		(duplicate_pad_numbers_are_jumpers no)
		(fp_line
			(start 0.508 -0.9398)
			(end -0.508 -0.9398)
			(stroke
				(width 0.1524)
				(type default)
			)
			(layer "F.SilkS")
		)
		(fp_line
			(start -0.508 -0.9398)
			(end -0.508 0.9398)
			(stroke
				(width 0.1524)
				(type default)
			)
			(layer "F.SilkS")
		)
		(fp_rect
			(start -0.508 0.9398)
			(end 0.508 -0.9398)
			(stroke
				(width 0)
				(type default)
			)
			(fill no)
			(layer "F.CrtYd")
		)
		(fp_rect
			(start -0.508 0.9398)
			(end 0.508 -0.9398)
			(stroke
				(width 0)
				(type default)
			)
			(fill no)
			(layer "F.Fab")
		)
		(pad "1" smd custom
			(at 0 -0.4445 180)
			(size 0.1397 0.1397)
			(layers "F.Cu" "F.Mask" "F.Paste")
			(net "P12VU_2490_PROG")
			(options
				(clearance outline)
				(anchor circle)
			)
			(primitives
				(gr_poly
					(pts
						(arc
							(start -0.1778 -0.2794)
							(mid -0.249642 -0.249642)
							(end -0.2794 -0.1778)
						)
						(arc
							(start -0.2794 0.1778)
							(mid -0.249642 0.249642)
							(end -0.1778 0.2794)
						)
						(arc
							(start 0.1778 0.2794)
							(mid 0.249642 0.249642)
							(end 0.2794 0.1778)
						)
						(arc
							(start 0.2794 -0.1778)
							(mid 0.249642 -0.249642)
							(end 0.1778 -0.2794)
						)
					)
					(width 0)
					(fill yes)
				)
			)
		)
		(pad "2" smd custom
			(at 0 0.4445 180)
			(size 0.1397 0.1397)
			(layers "F.Cu" "F.Mask" "F.Paste")
			(net "GND")
			(options
				(clearance outline)
				(anchor circle)
			)
			(primitives
				(gr_poly
					(pts
						(arc
							(start -0.1778 -0.2794)
							(mid -0.249642 -0.249642)
							(end -0.2794 -0.1778)
						)
						(arc
							(start -0.2794 0.1778)
							(mid -0.249642 0.249642)
							(end -0.1778 0.2794)
						)
						(arc
							(start 0.1778 0.2794)
							(mid 0.249642 0.249642)
							(end 0.2794 0.1778)
						)
						(arc
							(start 0.2794 -0.1778)
							(mid 0.249642 -0.249642)
							(end 0.1778 -0.2794)
						)
					)
					(width 0)
					(fill yes)
				)
			)
		)
	)
	(footprint ""
		(layer "F.Cu")
		(at 18.415 -109.5502 90)
		(property "Reference" "PR118"
			(at 0 0 90)
			(layer "F.SilkS")
			(hide yes)
			(effects
				(font
					(size 1.27 1.27)
				)
			)
		)
		(property "Value" "10R2F-L-GP"
			(at 0.064008 -3.993896 90)
			(unlocked yes)
			(layer "F.Fab")
			(hide yes)
			(effects
				(font
					(size 1.016 1.016)
					(thickness 0.1524)
				)
			)
		)
		(property "Device Type" "R402H14"
			(at 0.064008 -5.517896 90)
			(unlocked yes)
			(layer "F.Fab")
			(hide yes)
			(effects
				(font
					(size 1.016 1.016)
					(thickness 0.1524)
				)
			)
		)
		(duplicate_pad_numbers_are_jumpers no)
		(fp_line
			(start 0.508 -0.9398)
			(end -0.508 -0.9398)
			(stroke
				(width 0.1524)
				(type default)
			)
			(layer "F.SilkS")
		)
		(fp_line
			(start -0.508 -0.9398)
			(end -0.508 0.9398)
			(stroke
				(width 0.1524)
				(type default)
			)
			(layer "F.SilkS")
		)
		(fp_rect
			(start -0.508 0.9398)
			(end 0.508 -0.9398)
			(stroke
				(width 0)
				(type default)
			)
			(fill no)
			(layer "F.CrtYd")
		)
		(fp_rect
			(start -0.508 0.9398)
			(end 0.508 -0.9398)
			(stroke
				(width 0)
				(type default)
			)
			(fill no)
			(layer "F.Fab")
		)
		(pad "1" smd custom
			(at 0 -0.4445 90)
			(size 0.1397 0.1397)
			(layers "F.Cu" "F.Mask" "F.Paste")
			(net "P12VU_2490_GATE_DRV_2")
			(options
				(clearance outline)
				(anchor circle)
			)
			(primitives
				(gr_poly
					(pts
						(arc
							(start -0.1778 -0.2794)
							(mid -0.249642 -0.249642)
							(end -0.2794 -0.1778)
						)
						(arc
							(start -0.2794 0.1778)
							(mid -0.249642 0.249642)
							(end -0.1778 0.2794)
						)
						(arc
							(start 0.1778 0.2794)
							(mid 0.249642 0.249642)
							(end 0.2794 0.1778)
						)
						(arc
							(start 0.2794 -0.1778)
							(mid 0.249642 -0.249642)
							(end 0.1778 -0.2794)
						)
					)
					(width 0)
					(fill yes)
				)
			)
		)
		(pad "2" smd custom
			(at 0 0.4445 90)
			(size 0.1397 0.1397)
			(layers "F.Cu" "F.Mask" "F.Paste")
			(net "P12VU_2490_GATE")
			(options
				(clearance outline)
				(anchor circle)
			)
			(primitives
				(gr_poly
					(pts
						(arc
							(start -0.1778 -0.2794)
							(mid -0.249642 -0.249642)
							(end -0.2794 -0.1778)
						)
						(arc
							(start -0.2794 0.1778)
							(mid -0.249642 0.249642)
							(end -0.1778 0.2794)
						)
						(arc
							(start 0.1778 0.2794)
							(mid 0.249642 0.249642)
							(end 0.2794 0.1778)
						)
						(arc
							(start 0.2794 -0.1778)
							(mid 0.249642 -0.249642)
							(end 0.1778 -0.2794)
						)
					)
					(width 0)
					(fill yes)
				)
			)
		)
	)
	(footprint ""
		(layer "F.Cu")
		(at 12.064492 -61.391546)
		(property "Reference" "C32"
			(at 0 0 0)
			(layer "F.SilkS")
			(hide yes)
			(effects
				(font
					(size 1.27 1.27)
				)
			)
		)
		(property "Value" "SC1U25V3KX-1-GP"
			(at 0 -2.8194 0)
			(unlocked yes)
			(layer "F.Fab")
			(hide yes)
			(effects
				(font
					(size 1.016 1.016)
					(thickness 0.1524)
				)
			)
		)
		(property "Device Type" "C603H36"
			(at 0 -4.3434 0)
			(unlocked yes)
			(layer "F.Fab")
			(hide yes)
			(effects
				(font
					(size 1.016 1.016)
					(thickness 0.1524)
				)
			)
		)
		(duplicate_pad_numbers_are_jumpers no)
		(fp_line
			(start 0.508 0)
			(end -0.508 0)
			(stroke
				(width 0.2032)
				(type default)
			)
			(layer "F.SilkS")
		)
		(fp_rect
			(start -0.5842 1.3335)
			(end 0.5842 -1.3335)
			(stroke
				(width 0)
				(type default)
			)
			(fill no)
			(layer "F.CrtYd")
		)
		(fp_rect
			(start -0.5842 1.3335)
			(end 0.5842 -1.3335)
			(stroke
				(width 0)
				(type default)
			)
			(fill no)
			(layer "F.Fab")
		)
		(pad "1" smd custom
			(at 0 -0.762)
			(size 0.2159 0.2159)
			(layers "F.Cu" "F.Mask" "F.Paste")
			(net "P12V")
			(options
				(clearance outline)
				(anchor circle)
			)
			(primitives
				(gr_poly
					(pts
						(arc
							(start -0.3302 -0.4318)
							(mid -0.402042 -0.402042)
							(end -0.4318 -0.3302)
						)
						(arc
							(start -0.4318 0.3302)
							(mid -0.402042 0.402042)
							(end -0.3302 0.4318)
						)
						(arc
							(start 0.3302 0.4318)
							(mid 0.402042 0.402042)
							(end 0.4318 0.3302)
						)
						(arc
							(start 0.4318 -0.3302)
							(mid 0.402042 -0.402042)
							(end 0.3302 -0.4318)
						)
					)
					(width 0)
					(fill yes)
				)
			)
		)
		(pad "2" smd custom
			(at 0 0.762)
			(size 0.2159 0.2159)
			(layers "F.Cu" "F.Mask" "F.Paste")
			(net "GND")
			(options
				(clearance outline)
				(anchor circle)
			)
			(primitives
				(gr_poly
					(pts
						(arc
							(start -0.3302 -0.4318)
							(mid -0.402042 -0.402042)
							(end -0.4318 -0.3302)
						)
						(arc
							(start -0.4318 0.3302)
							(mid -0.402042 0.402042)
							(end -0.3302 0.4318)
						)
						(arc
							(start 0.3302 0.4318)
							(mid 0.402042 0.402042)
							(end 0.4318 0.3302)
						)
						(arc
							(start 0.4318 -0.3302)
							(mid 0.402042 -0.402042)
							(end 0.3302 -0.4318)
						)
					)
					(width 0)
					(fill yes)
				)
			)
		)
	)
	(footprint ""
		(layer "F.Cu")
		(at 34.741866 -137.508234 180)
		(property "Reference" "PR105"
			(at 0 0 180)
			(layer "F.SilkS")
			(hide yes)
			(effects
				(font
					(size 1.27 1.27)
				)
			)
		)
		(property "Value" "2K7R2F-GP"
			(at 0.064008 -3.993896 180)
			(unlocked yes)
			(layer "F.Fab")
			(hide yes)
			(effects
				(font
					(size 1.016 1.016)
					(thickness 0.1524)
				)
			)
		)
		(property "Device Type" "R402H16"
			(at 0.064008 -5.517896 180)
			(unlocked yes)
			(layer "F.Fab")
			(hide yes)
			(effects
				(font
					(size 1.016 1.016)
					(thickness 0.1524)
				)
			)
		)
		(duplicate_pad_numbers_are_jumpers no)
		(fp_line
			(start 0.508 -0.9398)
			(end -0.508 -0.9398)
			(stroke
				(width 0.1524)
				(type default)
			)
			(layer "F.SilkS")
		)
		(fp_line
			(start -0.508 -0.9398)
			(end -0.508 0.9398)
			(stroke
				(width 0.1524)
				(type default)
			)
			(layer "F.SilkS")
		)
		(fp_rect
			(start -0.508 0.9398)
			(end 0.508 -0.9398)
			(stroke
				(width 0)
				(type default)
			)
			(fill no)
			(layer "F.CrtYd")
		)
		(fp_rect
			(start -0.508 0.9398)
			(end 0.508 -0.9398)
			(stroke
				(width 0)
				(type default)
			)
			(fill no)
			(layer "F.Fab")
		)
		(pad "1" smd custom
			(at 0 -0.4445 180)
			(size 0.1397 0.1397)
			(layers "F.Cu" "F.Mask" "F.Paste")
			(net "P12VL")
			(options
				(clearance outline)
				(anchor circle)
			)
			(primitives
				(gr_poly
					(pts
						(arc
							(start -0.1778 -0.2794)
							(mid -0.249642 -0.249642)
							(end -0.2794 -0.1778)
						)
						(arc
							(start -0.2794 0.1778)
							(mid -0.249642 0.249642)
							(end -0.1778 0.2794)
						)
						(arc
							(start 0.1778 0.2794)
							(mid 0.249642 0.249642)
							(end 0.2794 0.1778)
						)
						(arc
							(start 0.2794 -0.1778)
							(mid 0.249642 -0.249642)
							(end 0.1778 -0.2794)
						)
					)
					(width 0)
					(fill yes)
				)
			)
		)
		(pad "2" smd custom
			(at 0 0.4445 180)
			(size 0.1397 0.1397)
			(layers "F.Cu" "F.Mask" "F.Paste")
			(net "P12VL_2490_PG")
			(options
				(clearance outline)
				(anchor circle)
			)
			(primitives
				(gr_poly
					(pts
						(arc
							(start -0.1778 -0.2794)
							(mid -0.249642 -0.249642)
							(end -0.2794 -0.1778)
						)
						(arc
							(start -0.2794 0.1778)
							(mid -0.249642 0.249642)
							(end -0.1778 0.2794)
						)
						(arc
							(start 0.1778 0.2794)
							(mid 0.249642 0.249642)
							(end 0.2794 0.1778)
						)
						(arc
							(start 0.2794 -0.1778)
							(mid 0.249642 -0.249642)
							(end 0.1778 -0.2794)
						)
					)
					(width 0)
					(fill yes)
				)
			)
		)
	)
	(footprint ""
		(layer "F.Cu")
		(at 25.018238 -481.735892 -90)
		(property "Reference" "F6"
			(at 0 0 270)
			(layer "F.SilkS")
			(hide yes)
			(effects
				(font
					(size 1.27 1.27)
				)
			)
		)
		(property "Value" "FUSE-3A15V-GP"
			(at 0.2286 -10.5918 270)
			(unlocked yes)
			(layer "F.Fab")
			(hide yes)
			(effects
				(font
					(size 1.016 1.016)
					(thickness 0.1524)
				)
			)
		)
		(property "Device Type" "FUSE-7452-UH50"
			(at 0.2286 -12.4968 270)
			(unlocked yes)
			(layer "F.Fab")
			(hide yes)
			(effects
				(font
					(size 1.016 1.016)
					(thickness 0.1524)
				)
			)
		)
		(duplicate_pad_numbers_are_jumpers no)
		(fp_line
			(start -4.9276 2.921)
			(end -4.9276 -2.921)
			(stroke
				(width 0.1524)
				(type default)
			)
			(layer "F.SilkS")
		)
		(fp_line
			(start 4.9276 2.921)
			(end -4.9276 2.921)
			(stroke
				(width 0.1524)
				(type default)
			)
			(layer "F.SilkS")
		)
		(fp_line
			(start -4.9276 -2.921)
			(end 4.9276 -2.921)
			(stroke
				(width 0.1524)
				(type default)
			)
			(layer "F.SilkS")
		)
		(fp_line
			(start 4.9276 -2.921)
			(end 4.9276 2.921)
			(stroke
				(width 0.1524)
				(type default)
			)
			(layer "F.SilkS")
		)
		(fp_poly
			(pts
				(xy -5.08 3.0988) (xy 5.08 3.0988) (xy 5.08 -3.0988) (xy -5.08 -3.0988)
			)
			(stroke
				(width 0)
				(type default)
			)
			(fill no)
			(layer "F.CrtYd")
		)
		(fp_poly
			(pts
				(xy -5.08 -3.0988) (xy 5.08 -3.0988) (xy 5.08 3.0988) (xy -5.08 3.0988)
			)
			(stroke
				(width 0)
				(type default)
			)
			(fill no)
			(layer "F.Fab")
		)
		(pad "1" smd rect
			(at -3.4036 0 270)
			(size 2.2098 5.2832)
			(layers "F.Cu" "F.Mask" "F.Paste")
			(net "P12V_FAN1")
		)
		(pad "2" smd rect
			(at 3.4036 0 270)
			(size 2.2098 5.2832)
			(layers "F.Cu" "F.Mask" "F.Paste")
			(net "P12V")
		)
	)
	(footprint ""
		(layer "F.Cu")
		(at 17.831308 -287.451038)
		(property "Reference" "D9"
			(at 0 0 0)
			(layer "F.SilkS")
			(hide yes)
			(effects
				(font
					(size 1.27 1.27)
				)
			)
		)
		(property "Value" "BAS16H-GP"
			(at 0 -5.5372 0)
			(unlocked yes)
			(layer "F.Fab")
			(hide yes)
			(effects
				(font
					(size 1.016 1.016)
					(thickness 0.1524)
				)
			)
		)
		(property "Device Type" "SOD123AKH48"
			(at 0 -7.0612 0)
			(unlocked yes)
			(layer "F.Fab")
			(hide yes)
			(effects
				(font
					(size 1.016 1.016)
					(thickness 0.1524)
				)
			)
		)
		(duplicate_pad_numbers_are_jumpers no)
		(fp_line
			(start -1.016 -2.667)
			(end -1.016 2.667)
			(stroke
				(width 0.1524)
				(type default)
			)
			(layer "F.SilkS")
		)
		(fp_line
			(start -1.016 2.667)
			(end 1.016 2.667)
			(stroke
				(width 0.1524)
				(type default)
			)
			(layer "F.SilkS")
		)
		(fp_line
			(start 0.889 2.921)
			(end -0.889 2.921)
			(stroke
				(width 0.508)
				(type default)
			)
			(layer "F.SilkS")
		)
		(fp_line
			(start 1.016 -2.667)
			(end -1.016 -2.667)
			(stroke
				(width 0.1524)
				(type default)
			)
			(layer "F.SilkS")
		)
		(fp_line
			(start 1.016 2.667)
			(end 1.016 -2.667)
			(stroke
				(width 0.1524)
				(type default)
			)
			(layer "F.SilkS")
		)
		(fp_rect
			(start -1.143 3.175)
			(end 1.143 -2.794)
			(stroke
				(width 0)
				(type default)
			)
			(fill no)
			(layer "F.CrtYd")
		)
		(fp_poly
			(pts
				(xy -1.143 -2.794) (xy 1.143 -2.794) (xy 1.143 3.175) (xy -1.143 3.175)
			)
			(stroke
				(width 0)
				(type default)
			)
			(fill no)
			(layer "F.Fab")
		)
		(pad "A" smd rect
			(at 0 -1.6891)
			(size 0.889 1.397)
			(layers "F.Cu" "F.Mask" "F.Paste")
			(net "FAN_TACH3")
		)
		(pad "K" smd rect
			(at 0 1.6891)
			(size 0.889 1.397)
			(layers "F.Cu" "F.Mask" "F.Paste")
			(net "P12V")
		)
	)
	(footprint ""
		(layer "F.Cu")
		(at 40.8178 -156.4386 180)
		(property "Reference" "TP17"
			(at 0 0 180)
			(layer "F.SilkS")
			(hide yes)
			(effects
				(font
					(size 1.27 1.27)
				)
			)
		)
		(property "Value" "TPAD32-GP"
			(at 0 -3.166364 180)
			(unlocked yes)
			(layer "F.Fab")
			(hide yes)
			(effects
				(font
					(size 1.016 1.016)
					(thickness 0.1524)
				)
			)
		)
		(property "Device Type" "TPAD32"
			(at 0 -4.690618 180)
			(unlocked yes)
			(layer "F.Fab")
			(hide yes)
			(effects
				(font
					(size 1.016 1.016)
					(thickness 0.1524)
				)
			)
		)
		(duplicate_pad_numbers_are_jumpers no)
		(fp_poly
			(pts
				(arc
					(start -0.7112 0)
					(mid 0.7112 0)
					(end -0.7112 0)
				)
			)
			(stroke
				(width 0)
				(type default)
			)
			(fill no)
			(layer "F.CrtYd")
		)
		(fp_poly
			(pts
				(arc
					(start -0.7112 0)
					(mid 0.7112 0)
					(end -0.7112 0)
				)
			)
			(stroke
				(width 0)
				(type default)
			)
			(fill no)
			(layer "F.Fab")
		)
		(pad "1" smd circle
			(at 0 0 180)
			(size 0.8128 0.8128)
			(layers "F.Cu" "F.Mask" "F.Paste")
			(net "NCT7904_PROCHOT")
		)
	)
	(footprint ""
		(layer "F.Cu")
		(at 7.112 -452.374 90)
		(property "Reference" "D11"
			(at 0 0 90)
			(layer "F.SilkS")
			(hide yes)
			(effects
				(font
					(size 1.27 1.27)
				)
			)
		)
		(property "Value" "BAS16H-GP"
			(at 0 -5.5372 90)
			(unlocked yes)
			(layer "F.Fab")
			(hide yes)
			(effects
				(font
					(size 1.016 1.016)
					(thickness 0.1524)
				)
			)
		)
		(property "Device Type" "SOD123AKH48"
			(at 0 -7.0612 90)
			(unlocked yes)
			(layer "F.Fab")
			(hide yes)
			(effects
				(font
					(size 1.016 1.016)
					(thickness 0.1524)
				)
			)
		)
		(duplicate_pad_numbers_are_jumpers no)
		(fp_line
			(start 1.016 -2.667)
			(end -1.016 -2.667)
			(stroke
				(width 0.1524)
				(type default)
			)
			(layer "F.SilkS")
		)
		(fp_line
			(start -1.016 -2.667)
			(end -1.016 2.667)
			(stroke
				(width 0.1524)
				(type default)
			)
			(layer "F.SilkS")
		)
		(fp_line
			(start 1.016 2.667)
			(end 1.016 -2.667)
			(stroke
				(width 0.1524)
				(type default)
			)
			(layer "F.SilkS")
		)
		(fp_line
			(start -1.016 2.667)
			(end 1.016 2.667)
			(stroke
				(width 0.1524)
				(type default)
			)
			(layer "F.SilkS")
		)
		(fp_line
			(start 0.889 2.921)
			(end -0.889 2.921)
			(stroke
				(width 0.508)
				(type default)
			)
			(layer "F.SilkS")
		)
		(fp_rect
			(start -1.143 3.175)
			(end 1.143 -2.794)
			(stroke
				(width 0)
				(type default)
			)
			(fill no)
			(layer "F.CrtYd")
		)
		(fp_poly
			(pts
				(xy -1.143 -2.794) (xy 1.143 -2.794) (xy 1.143 3.175) (xy -1.143 3.175)
			)
			(stroke
				(width 0)
				(type default)
			)
			(fill no)
			(layer "F.Fab")
		)
		(pad "A" smd rect
			(at 0 -1.6891 90)
			(size 0.889 1.397)
			(layers "F.Cu" "F.Mask" "F.Paste")
			(net "FAN_TACH1")
		)
		(pad "K" smd rect
			(at 0 1.6891 90)
			(size 0.889 1.397)
			(layers "F.Cu" "F.Mask" "F.Paste")
			(net "P12V")
		)
	)
	(footprint ""
		(layer "F.Cu")
		(at 17.119092 -17.602962 180)
		(property "Reference" "R67"
			(at 0 0 180)
			(layer "F.SilkS")
			(hide yes)
			(effects
				(font
					(size 1.27 1.27)
				)
			)
		)
		(property "Value" "4K7R2F-GP"
			(at 0.064008 -3.993896 180)
			(unlocked yes)
			(layer "F.Fab")
			(hide yes)
			(effects
				(font
					(size 1.016 1.016)
					(thickness 0.1524)
				)
			)
		)
		(property "Device Type" "R402H16"
			(at 0.064008 -5.517896 180)
			(unlocked yes)
			(layer "F.Fab")
			(hide yes)
			(effects
				(font
					(size 1.016 1.016)
					(thickness 0.1524)
				)
			)
		)
		(duplicate_pad_numbers_are_jumpers no)
		(fp_line
			(start 0.508 -0.9398)
			(end -0.508 -0.9398)
			(stroke
				(width 0.1524)
				(type default)
			)
			(layer "F.SilkS")
		)
		(fp_line
			(start -0.508 -0.9398)
			(end -0.508 0.9398)
			(stroke
				(width 0.1524)
				(type default)
			)
			(layer "F.SilkS")
		)
		(fp_rect
			(start -0.508 0.9398)
			(end 0.508 -0.9398)
			(stroke
				(width 0)
				(type default)
			)
			(fill no)
			(layer "F.CrtYd")
		)
		(fp_rect
			(start -0.508 1.0668)
			(end 0.508 -0.8128)
			(stroke
				(width 0)
				(type default)
			)
			(fill no)
			(layer "F.Fab")
		)
		(pad "1" smd custom
			(at 0 -0.4445 180)
			(size 0.1397 0.1397)
			(layers "F.Cu" "F.Mask" "F.Paste")
			(net "P12V")
			(options
				(clearance outline)
				(anchor circle)
			)
			(primitives
				(gr_poly
					(pts
						(arc
							(start -0.1778 -0.2794)
							(mid -0.249642 -0.249642)
							(end -0.2794 -0.1778)
						)
						(arc
							(start -0.2794 0.1778)
							(mid -0.249642 0.249642)
							(end -0.1778 0.2794)
						)
						(arc
							(start 0.1778 0.2794)
							(mid 0.249642 0.249642)
							(end 0.2794 0.1778)
						)
						(arc
							(start 0.2794 -0.1778)
							(mid 0.249642 -0.249642)
							(end 0.1778 -0.2794)
						)
					)
					(width 0)
					(fill yes)
				)
			)
		)
		(pad "2" smd custom
			(at 0 0.4445 180)
			(size 0.1397 0.1397)
			(layers "F.Cu" "F.Mask" "F.Paste")
			(net "FAN_TACH12")
			(options
				(clearance outline)
				(anchor circle)
			)
			(primitives
				(gr_poly
					(pts
						(arc
							(start -0.1778 -0.2794)
							(mid -0.249642 -0.249642)
							(end -0.2794 -0.1778)
						)
						(arc
							(start -0.2794 0.1778)
							(mid -0.249642 0.249642)
							(end -0.1778 0.2794)
						)
						(arc
							(start 0.1778 0.2794)
							(mid 0.249642 0.249642)
							(end 0.2794 0.1778)
						)
						(arc
							(start 0.2794 -0.1778)
							(mid 0.249642 -0.249642)
							(end 0.1778 -0.2794)
						)
					)
					(width 0)
					(fill yes)
				)
			)
		)
	)
	(footprint ""
		(layer "F.Cu")
		(at 7.949946 -411.465014 -90)
		(property "Reference" "LED2"
			(at 0 0 270)
			(layer "F.SilkS")
			(hide yes)
			(effects
				(font
					(size 1.27 1.27)
				)
			)
		)
		(property "Value" "LED-RB-6-GP"
			(at -4.6736 3.8354 270)
			(unlocked yes)
			(layer "F.Fab")
			(hide yes)
			(effects
				(font
					(size 1.016 1.016)
					(thickness 0.1524)
				)
			)
		)
		(property "Device Type" "LED-100-3P-067106H325"
			(at -4.6736 2.3114 270)
			(unlocked yes)
			(layer "F.Fab")
			(hide yes)
			(effects
				(font
					(size 1.016 1.016)
					(thickness 0.1524)
				)
			)
		)
		(duplicate_pad_numbers_are_jumpers no)
		(fp_line
			(start -1.7526 10.414)
			(end -1.7526 6.6548)
			(stroke
				(width 0.1524)
				(type default)
			)
			(layer "F.SilkS")
		)
		(fp_line
			(start 1.7526 10.414)
			(end -1.7526 10.414)
			(stroke
				(width 0.1524)
				(type default)
			)
			(layer "F.SilkS")
		)
		(fp_line
			(start -3.6068 6.6548)
			(end -3.6068 -0.889)
			(stroke
				(width 0.1524)
				(type default)
			)
			(layer "F.SilkS")
		)
		(fp_line
			(start -1.7526 6.6548)
			(end -3.6068 6.6548)
			(stroke
				(width 0.1524)
				(type default)
			)
			(layer "F.SilkS")
		)
		(fp_line
			(start 1.7526 6.6548)
			(end 1.7526 10.414)
			(stroke
				(width 0.1524)
				(type default)
			)
			(layer "F.SilkS")
		)
		(fp_line
			(start 3.6068 6.6548)
			(end 1.7526 6.6548)
			(stroke
				(width 0.1524)
				(type default)
			)
			(layer "F.SilkS")
		)
		(fp_line
			(start -3.6068 -0.889)
			(end 3.6068 -0.889)
			(stroke
				(width 0.1524)
				(type default)
			)
			(layer "F.SilkS")
		)
		(fp_line
			(start 3.6068 -0.889)
			(end 3.6068 6.6548)
			(stroke
				(width 0.1524)
				(type default)
			)
			(layer "F.SilkS")
		)
		(fp_circle
			(center -2.54 0)
			(end -2.54 -0.9906)
			(stroke
				(width 0.3048)
				(type default)
			)
			(fill no)
			(layer "F.SilkS")
		)
		(fp_circle
			(center 0 0)
			(end 0 -0.9906)
			(stroke
				(width 0.3048)
				(type default)
			)
			(fill no)
			(layer "F.SilkS")
		)
		(fp_circle
			(center 2.54 0)
			(end 2.54 -0.9906)
			(stroke
				(width 0.3048)
				(type default)
			)
			(fill no)
			(layer "F.SilkS")
		)
		(fp_poly
			(pts
				(xy -1.4986 10.1473) (xy -1.4986 6.4008) (xy -3.3528 6.4008) (xy -3.3528 -0.3937) (xy 3.3528 -0.3937)
				(xy 3.3528 6.4008) (xy 1.4986 6.4008) (xy 1.4986 10.1473)
			)
			(stroke
				(width 0)
				(type default)
			)
			(fill no)
			(layer "F.CrtYd")
		)
		(fp_poly
			(pts
				(xy -2.0066 10.668) (xy 2.0066 10.668) (xy 2.0066 6.9088) (xy 3.8608 6.9088) (xy 3.8608 2.2098)
				(xy 3.3528 2.2098) (xy 3.3528 6.4008) (xy 1.4986 6.4008) (xy 1.4986 10.1473) (xy -1.4986 10.1473)
				(xy -1.4986 6.4008) (xy -3.3528 6.4008) (xy -3.3528 -0.3937) (xy 3.3528 -0.3937) (xy 3.3528 2.1971)
				(xy 3.8608 2.1971) (xy 3.8608 -1.143) (xy -3.8608 -1.143) (xy -3.8608 6.9088) (xy -2.0066 6.9088)
			)
			(stroke
				(width 0)
				(type default)
			)
			(fill no)
			(layer "F.CrtYd")
		)
		(fp_poly
			(pts
				(xy -2.0066 10.668) (xy -2.0066 6.9088) (xy -3.8608 6.9088) (xy -3.8608 -1.143) (xy 3.8608 -1.143)
				(xy 3.8608 6.9088) (xy 2.0066 6.9088) (xy 2.0066 10.668)
			)
			(stroke
				(width 0)
				(type default)
			)
			(fill no)
			(layer "F.Fab")
		)
		(pad "1" thru_hole circle
			(at 2.54 0 270)
			(size 1.27 1.27)
			(drill 0.889)
			(layers "*.Cu" "*.Mask")
			(remove_unused_layers no)
			(net "LED_DR_LED1_BLUE")
			(clearance 0.1651)
			(thermal_gap 0.1651)
		)
		(pad "2" thru_hole circle
			(at 0 0 270)
			(size 1.27 1.27)
			(drill 0.889)
			(layers "*.Cu" "*.Mask")
			(remove_unused_layers no)
			(net "LED_DR_LED1_K")
			(clearance 0.1651)
			(thermal_gap 0.1651)
		)
		(pad "3" thru_hole circle
			(at -2.54 0 270)
			(size 1.27 1.27)
			(drill 0.889)
			(layers "*.Cu" "*.Mask")
			(remove_unused_layers no)
			(net "LED_DR_LED1")
			(clearance 0.1651)
			(thermal_gap 0.1651)
		)
	)
	(footprint ""
		(layer "F.Cu")
		(at 34.2138 -356.185216)
		(property "Reference" "R365"
			(at 0 0 0)
			(layer "F.SilkS")
			(hide yes)
			(effects
				(font
					(size 1.27 1.27)
				)
			)
		)
		(property "Value" "10MR2J-L-GP"
			(at 0.064008 -3.993896 0)
			(unlocked yes)
			(layer "F.Fab")
			(hide yes)
			(effects
				(font
					(size 1.016 1.016)
					(thickness 0.1524)
				)
			)
		)
		(property "Device Type" "R402H16"
			(at 0.064008 -5.517896 0)
			(unlocked yes)
			(layer "F.Fab")
			(hide yes)
			(effects
				(font
					(size 1.016 1.016)
					(thickness 0.1524)
				)
			)
		)
		(duplicate_pad_numbers_are_jumpers no)
		(fp_line
			(start -0.508 -0.9398)
			(end -0.508 0.9398)
			(stroke
				(width 0.1524)
				(type default)
			)
			(layer "F.SilkS")
		)
		(fp_line
			(start 0.508 -0.9398)
			(end -0.508 -0.9398)
			(stroke
				(width 0.1524)
				(type default)
			)
			(layer "F.SilkS")
		)
		(fp_rect
			(start -0.508 0.9398)
			(end 0.508 -0.9398)
			(stroke
				(width 0)
				(type default)
			)
			(fill no)
			(layer "F.CrtYd")
		)
		(fp_rect
			(start -0.508 0.9398)
			(end 0.508 -0.9398)
			(stroke
				(width 0)
				(type default)
			)
			(fill no)
			(layer "F.Fab")
		)
		(pad "1" smd custom
			(at 0 -0.4445)
			(size 0.1397 0.1397)
			(layers "F.Cu" "F.Mask" "F.Paste")
			(net "OTP_RETRY_G")
			(options
				(clearance outline)
				(anchor circle)
			)
			(primitives
				(gr_poly
					(pts
						(arc
							(start -0.1778 -0.2794)
							(mid -0.249642 -0.249642)
							(end -0.2794 -0.1778)
						)
						(arc
							(start -0.2794 0.1778)
							(mid -0.249642 0.249642)
							(end -0.1778 0.2794)
						)
						(arc
							(start 0.1778 0.2794)
							(mid 0.249642 0.249642)
							(end 0.2794 0.1778)
						)
						(arc
							(start 0.2794 -0.1778)
							(mid 0.249642 -0.249642)
							(end 0.1778 -0.2794)
						)
					)
					(width 0)
					(fill yes)
				)
			)
		)
		(pad "2" smd custom
			(at 0 0.4445)
			(size 0.1397 0.1397)
			(layers "F.Cu" "F.Mask" "F.Paste")
			(net "GND")
			(options
				(clearance outline)
				(anchor circle)
			)
			(primitives
				(gr_poly
					(pts
						(arc
							(start -0.1778 -0.2794)
							(mid -0.249642 -0.249642)
							(end -0.2794 -0.1778)
						)
						(arc
							(start -0.2794 0.1778)
							(mid -0.249642 0.249642)
							(end -0.1778 0.2794)
						)
						(arc
							(start 0.1778 0.2794)
							(mid 0.249642 0.249642)
							(end 0.2794 0.1778)
						)
						(arc
							(start 0.2794 -0.1778)
							(mid 0.249642 -0.249642)
							(end 0.1778 -0.2794)
						)
					)
					(width 0)
					(fill yes)
				)
			)
		)
	)
	(footprint ""
		(layer "F.Cu")
		(at 41.7576 -159.1818 -90)
		(property "Reference" "R15"
			(at 0 0 270)
			(layer "F.SilkS")
			(hide yes)
			(effects
				(font
					(size 1.27 1.27)
				)
			)
		)
		(property "Value" "10KR2F-2-GP"
			(at 0.064008 -3.993896 270)
			(unlocked yes)
			(layer "F.Fab")
			(hide yes)
			(effects
				(font
					(size 1.016 1.016)
					(thickness 0.1524)
				)
			)
		)
		(property "Device Type" "R402H16"
			(at 0.064008 -5.517896 270)
			(unlocked yes)
			(layer "F.Fab")
			(hide yes)
			(effects
				(font
					(size 1.016 1.016)
					(thickness 0.1524)
				)
			)
		)
		(duplicate_pad_numbers_are_jumpers no)
		(fp_line
			(start -0.508 -0.9398)
			(end -0.508 0.9398)
			(stroke
				(width 0.1524)
				(type default)
			)
			(layer "F.SilkS")
		)
		(fp_line
			(start 0.508 -0.9398)
			(end -0.508 -0.9398)
			(stroke
				(width 0.1524)
				(type default)
			)
			(layer "F.SilkS")
		)
		(fp_rect
			(start -0.508 0.9398)
			(end 0.508 -0.9398)
			(stroke
				(width 0)
				(type default)
			)
			(fill no)
			(layer "F.CrtYd")
		)
		(fp_rect
			(start -0.508 0.9398)
			(end 0.508 -0.9398)
			(stroke
				(width 0)
				(type default)
			)
			(fill no)
			(layer "F.Fab")
		)
		(pad "1" smd custom
			(at 0 -0.4445 270)
			(size 0.1397 0.1397)
			(layers "F.Cu" "F.Mask" "F.Paste")
			(net "NCT7904_VSEN_P12V_AUX")
			(options
				(clearance outline)
				(anchor circle)
			)
			(primitives
				(gr_poly
					(pts
						(arc
							(start -0.1778 -0.2794)
							(mid -0.249642 -0.249642)
							(end -0.2794 -0.1778)
						)
						(arc
							(start -0.2794 0.1778)
							(mid -0.249642 0.249642)
							(end -0.1778 0.2794)
						)
						(arc
							(start 0.1778 0.2794)
							(mid 0.249642 0.249642)
							(end 0.2794 0.1778)
						)
						(arc
							(start 0.2794 -0.1778)
							(mid 0.249642 -0.249642)
							(end 0.1778 -0.2794)
						)
					)
					(width 0)
					(fill yes)
				)
			)
		)
		(pad "2" smd custom
			(at 0 0.4445 270)
			(size 0.1397 0.1397)
			(layers "F.Cu" "F.Mask" "F.Paste")
			(net "GND")
			(options
				(clearance outline)
				(anchor circle)
			)
			(primitives
				(gr_poly
					(pts
						(arc
							(start -0.1778 -0.2794)
							(mid -0.249642 -0.249642)
							(end -0.2794 -0.1778)
						)
						(arc
							(start -0.2794 0.1778)
							(mid -0.249642 0.249642)
							(end -0.1778 0.2794)
						)
						(arc
							(start 0.1778 0.2794)
							(mid 0.249642 0.249642)
							(end 0.2794 0.1778)
						)
						(arc
							(start 0.2794 -0.1778)
							(mid 0.249642 -0.249642)
							(end 0.1778 -0.2794)
						)
					)
					(width 0)
					(fill yes)
				)
			)
		)
	)
	(footprint ""
		(layer "F.Cu")
		(at 34.716466 -141.089634 180)
		(property "Reference" "PR107"
			(at 0 0 180)
			(layer "F.SilkS")
			(hide yes)
			(effects
				(font
					(size 1.27 1.27)
				)
			)
		)
		(property "Value" "1KR2F-3-GP"
			(at 0.064008 -3.993896 180)
			(unlocked yes)
			(layer "F.Fab")
			(hide yes)
			(effects
				(font
					(size 1.016 1.016)
					(thickness 0.1524)
				)
			)
		)
		(property "Device Type" "R402H16"
			(at 0.064008 -5.517896 180)
			(unlocked yes)
			(layer "F.Fab")
			(hide yes)
			(effects
				(font
					(size 1.016 1.016)
					(thickness 0.1524)
				)
			)
		)
		(duplicate_pad_numbers_are_jumpers no)
		(fp_line
			(start 0.508 -0.9398)
			(end -0.508 -0.9398)
			(stroke
				(width 0.1524)
				(type default)
			)
			(layer "F.SilkS")
		)
		(fp_line
			(start -0.508 -0.9398)
			(end -0.508 0.9398)
			(stroke
				(width 0.1524)
				(type default)
			)
			(layer "F.SilkS")
		)
		(fp_rect
			(start -0.508 0.9398)
			(end 0.508 -0.9398)
			(stroke
				(width 0)
				(type default)
			)
			(fill no)
			(layer "F.CrtYd")
		)
		(fp_rect
			(start -0.508 0.9398)
			(end 0.508 -0.9398)
			(stroke
				(width 0)
				(type default)
			)
			(fill no)
			(layer "F.Fab")
		)
		(pad "1" smd custom
			(at 0 -0.4445 180)
			(size 0.1397 0.1397)
			(layers "F.Cu" "F.Mask" "F.Paste")
			(net "P12VL_2490_PG")
			(options
				(clearance outline)
				(anchor circle)
			)
			(primitives
				(gr_poly
					(pts
						(arc
							(start -0.1778 -0.2794)
							(mid -0.249642 -0.249642)
							(end -0.2794 -0.1778)
						)
						(arc
							(start -0.2794 0.1778)
							(mid -0.249642 0.249642)
							(end -0.1778 0.2794)
						)
						(arc
							(start 0.1778 0.2794)
							(mid 0.249642 0.249642)
							(end 0.2794 0.1778)
						)
						(arc
							(start 0.2794 -0.1778)
							(mid 0.249642 -0.249642)
							(end 0.1778 -0.2794)
						)
					)
					(width 0)
					(fill yes)
				)
			)
		)
		(pad "2" smd custom
			(at 0 0.4445 180)
			(size 0.1397 0.1397)
			(layers "F.Cu" "F.Mask" "F.Paste")
			(net "GND")
			(options
				(clearance outline)
				(anchor circle)
			)
			(primitives
				(gr_poly
					(pts
						(arc
							(start -0.1778 -0.2794)
							(mid -0.249642 -0.249642)
							(end -0.2794 -0.1778)
						)
						(arc
							(start -0.2794 0.1778)
							(mid -0.249642 0.249642)
							(end -0.1778 0.2794)
						)
						(arc
							(start 0.1778 0.2794)
							(mid 0.249642 0.249642)
							(end 0.2794 0.1778)
						)
						(arc
							(start 0.2794 -0.1778)
							(mid 0.249642 -0.249642)
							(end 0.1778 -0.2794)
						)
					)
					(width 0)
					(fill yes)
				)
			)
		)
	)
	(footprint ""
		(layer "F.Cu")
		(at 20.3454 -245.4148 -90)
		(property "Reference" "PC41"
			(at 0 0 270)
			(layer "F.SilkS")
			(hide yes)
			(effects
				(font
					(size 1.27 1.27)
				)
			)
		)
		(property "Value" "SCD1U16V2KX-3GP"
			(at 1.1811 -2.7051 270)
			(unlocked yes)
			(layer "F.Fab")
			(hide yes)
			(effects
				(font
					(size 1.016 1.016)
					(thickness 0.1524)
				)
			)
		)
		(property "Device Type" "C402H22"
			(at 1.1811 -4.2291 270)
			(unlocked yes)
			(layer "F.Fab")
			(hide yes)
			(effects
				(font
					(size 1.016 1.016)
					(thickness 0.1524)
				)
			)
		)
		(duplicate_pad_numbers_are_jumpers no)
		(fp_rect
			(start -0.4318 0.9525)
			(end 0.4318 -0.9525)
			(stroke
				(width 0)
				(type default)
			)
			(fill no)
			(layer "F.CrtYd")
		)
		(fp_rect
			(start -0.4318 0.9525)
			(end 0.4318 -0.9525)
			(stroke
				(width 0)
				(type default)
			)
			(fill no)
			(layer "F.Fab")
		)
		(pad "1" smd custom
			(at 0 -0.4445 270)
			(size 0.1524 0.1524)
			(layers "F.Cu" "F.Mask" "F.Paste")
			(net "P3V3_BS_NET")
			(options
				(clearance outline)
				(anchor circle)
			)
			(primitives
				(gr_poly
					(pts
						(arc
							(start 0.3048 -0.2032)
							(mid 0.275042 -0.275042)
							(end 0.2032 -0.3048)
						)
						(arc
							(start -0.2032 -0.3048)
							(mid -0.275042 -0.275042)
							(end -0.3048 -0.2032)
						)
						(arc
							(start -0.3048 0.2032)
							(mid -0.275042 0.275042)
							(end -0.2032 0.3048)
						)
						(arc
							(start 0.2032 0.3048)
							(mid 0.275042 0.275042)
							(end 0.3048 0.2032)
						)
					)
					(width 0)
					(fill yes)
				)
			)
		)
		(pad "2" smd custom
			(at 0 0.4445 270)
			(size 0.1524 0.1524)
			(layers "F.Cu" "F.Mask" "F.Paste")
			(net "P3V3_LX")
			(options
				(clearance outline)
				(anchor circle)
			)
			(primitives
				(gr_poly
					(pts
						(arc
							(start 0.3048 -0.2032)
							(mid 0.275042 -0.275042)
							(end 0.2032 -0.3048)
						)
						(arc
							(start -0.2032 -0.3048)
							(mid -0.275042 -0.275042)
							(end -0.3048 -0.2032)
						)
						(arc
							(start -0.3048 0.2032)
							(mid -0.275042 0.275042)
							(end -0.2032 0.3048)
						)
						(arc
							(start 0.2032 0.3048)
							(mid 0.275042 0.275042)
							(end 0.3048 0.2032)
						)
					)
					(width 0)
					(fill yes)
				)
			)
		)
	)
	(footprint ""
		(layer "F.Cu")
		(at 18.796 -260.4516 -90)
		(property "Reference" "R80"
			(at 0 0 270)
			(layer "F.SilkS")
			(hide yes)
			(effects
				(font
					(size 1.27 1.27)
				)
			)
		)
		(property "Value" "4K7R2F-GP"
			(at 0.064008 -3.993896 270)
			(unlocked yes)
			(layer "F.Fab")
			(hide yes)
			(effects
				(font
					(size 1.016 1.016)
					(thickness 0.1524)
				)
			)
		)
		(property "Device Type" "R402H16"
			(at 0.064008 -5.517896 270)
			(unlocked yes)
			(layer "F.Fab")
			(hide yes)
			(effects
				(font
					(size 1.016 1.016)
					(thickness 0.1524)
				)
			)
		)
		(duplicate_pad_numbers_are_jumpers no)
		(fp_line
			(start -0.508 -0.9398)
			(end -0.508 0.9398)
			(stroke
				(width 0.1524)
				(type default)
			)
			(layer "F.SilkS")
		)
		(fp_line
			(start 0.508 -0.9398)
			(end -0.508 -0.9398)
			(stroke
				(width 0.1524)
				(type default)
			)
			(layer "F.SilkS")
		)
		(fp_rect
			(start -0.508 0.9398)
			(end 0.508 -0.9398)
			(stroke
				(width 0)
				(type default)
			)
			(fill no)
			(layer "F.CrtYd")
		)
		(fp_rect
			(start -0.508 0.9398)
			(end 0.508 -0.9398)
			(stroke
				(width 0)
				(type default)
			)
			(fill no)
			(layer "F.Fab")
		)
		(pad "1" smd custom
			(at 0 -0.4445 270)
			(size 0.1397 0.1397)
			(layers "F.Cu" "F.Mask" "F.Paste")
			(net "P12V")
			(options
				(clearance outline)
				(anchor circle)
			)
			(primitives
				(gr_poly
					(pts
						(arc
							(start -0.1778 -0.2794)
							(mid -0.249642 -0.249642)
							(end -0.2794 -0.1778)
						)
						(arc
							(start -0.2794 0.1778)
							(mid -0.249642 0.249642)
							(end -0.1778 0.2794)
						)
						(arc
							(start 0.1778 0.2794)
							(mid 0.249642 0.249642)
							(end 0.2794 0.1778)
						)
						(arc
							(start 0.2794 -0.1778)
							(mid 0.249642 -0.249642)
							(end 0.1778 -0.2794)
						)
					)
					(width 0)
					(fill yes)
				)
			)
		)
		(pad "2" smd custom
			(at 0 0.4445 270)
			(size 0.1397 0.1397)
			(layers "F.Cu" "F.Mask" "F.Paste")
			(net "FAN_TACH6")
			(options
				(clearance outline)
				(anchor circle)
			)
			(primitives
				(gr_poly
					(pts
						(arc
							(start -0.1778 -0.2794)
							(mid -0.249642 -0.249642)
							(end -0.2794 -0.1778)
						)
						(arc
							(start -0.2794 0.1778)
							(mid -0.249642 0.249642)
							(end -0.1778 0.2794)
						)
						(arc
							(start 0.1778 0.2794)
							(mid 0.249642 0.249642)
							(end 0.2794 0.1778)
						)
						(arc
							(start 0.2794 -0.1778)
							(mid 0.249642 -0.249642)
							(end 0.1778 -0.2794)
						)
					)
					(width 0)
					(fill yes)
				)
			)
		)
	)
	(footprint ""
		(layer "F.Cu")
		(at 12.7 -447.1162 90)
		(property "Reference" "C46"
			(at 0 0 90)
			(layer "F.SilkS")
			(hide yes)
			(effects
				(font
					(size 1.27 1.27)
				)
			)
		)
		(property "Value" "SCD1U16V2KX-3GP"
			(at 1.1811 -2.7051 90)
			(unlocked yes)
			(layer "F.Fab")
			(hide yes)
			(effects
				(font
					(size 1.016 1.016)
					(thickness 0.1524)
				)
			)
		)
		(property "Device Type" "C402H22"
			(at 1.1811 -4.2291 90)
			(unlocked yes)
			(layer "F.Fab")
			(hide yes)
			(effects
				(font
					(size 1.016 1.016)
					(thickness 0.1524)
				)
			)
		)
		(duplicate_pad_numbers_are_jumpers no)
		(fp_rect
			(start -0.4318 0.9525)
			(end 0.4318 -0.9525)
			(stroke
				(width 0)
				(type default)
			)
			(fill no)
			(layer "F.CrtYd")
		)
		(fp_rect
			(start -0.4318 0.9525)
			(end 0.4318 -0.9525)
			(stroke
				(width 0)
				(type default)
			)
			(fill no)
			(layer "F.Fab")
		)
		(pad "1" smd custom
			(at 0 -0.4445 90)
			(size 0.1524 0.1524)
			(layers "F.Cu" "F.Mask" "F.Paste")
			(net "FAN_TACH2")
			(options
				(clearance outline)
				(anchor circle)
			)
			(primitives
				(gr_poly
					(pts
						(arc
							(start 0.3048 -0.2032)
							(mid 0.275042 -0.275042)
							(end 0.2032 -0.3048)
						)
						(arc
							(start -0.2032 -0.3048)
							(mid -0.275042 -0.275042)
							(end -0.3048 -0.2032)
						)
						(arc
							(start -0.3048 0.2032)
							(mid -0.275042 0.275042)
							(end -0.2032 0.3048)
						)
						(arc
							(start 0.2032 0.3048)
							(mid 0.275042 0.275042)
							(end 0.3048 0.2032)
						)
					)
					(width 0)
					(fill yes)
				)
			)
		)
		(pad "2" smd custom
			(at 0 0.4445 90)
			(size 0.1524 0.1524)
			(layers "F.Cu" "F.Mask" "F.Paste")
			(net "GND")
			(options
				(clearance outline)
				(anchor circle)
			)
			(primitives
				(gr_poly
					(pts
						(arc
							(start 0.3048 -0.2032)
							(mid 0.275042 -0.275042)
							(end 0.2032 -0.3048)
						)
						(arc
							(start -0.2032 -0.3048)
							(mid -0.275042 -0.275042)
							(end -0.3048 -0.2032)
						)
						(arc
							(start -0.3048 0.2032)
							(mid -0.275042 0.275042)
							(end -0.2032 0.3048)
						)
						(arc
							(start 0.2032 0.3048)
							(mid 0.275042 0.275042)
							(end 0.3048 0.2032)
						)
					)
					(width 0)
					(fill yes)
				)
			)
		)
	)
	(footprint ""
		(layer "F.Cu")
		(at 23.622 -366.4712 -90)
		(property "Reference" "C58"
			(at 0 0 270)
			(layer "F.SilkS")
			(hide yes)
			(effects
				(font
					(size 1.27 1.27)
				)
			)
		)
		(property "Value" "SCD1U25V2KX-GP"
			(at 1.1811 -2.7051 270)
			(unlocked yes)
			(layer "F.Fab")
			(hide yes)
			(effects
				(font
					(size 1.016 1.016)
					(thickness 0.1524)
				)
			)
		)
		(property "Device Type" "C402H22"
			(at 1.1811 -4.2291 270)
			(unlocked yes)
			(layer "F.Fab")
			(hide yes)
			(effects
				(font
					(size 1.016 1.016)
					(thickness 0.1524)
				)
			)
		)
		(duplicate_pad_numbers_are_jumpers no)
		(fp_rect
			(start -0.4318 0.9525)
			(end 0.4318 -0.9525)
			(stroke
				(width 0)
				(type default)
			)
			(fill no)
			(layer "F.CrtYd")
		)
		(fp_rect
			(start -0.4318 0.9525)
			(end 0.4318 -0.9525)
			(stroke
				(width 0)
				(type default)
			)
			(fill no)
			(layer "F.Fab")
		)
		(pad "1" smd custom
			(at 0 -0.4445 270)
			(size 0.1524 0.1524)
			(layers "F.Cu" "F.Mask" "F.Paste")
			(net "ADM1276_ISET")
			(options
				(clearance outline)
				(anchor circle)
			)
			(primitives
				(gr_poly
					(pts
						(arc
							(start 0.3048 -0.2032)
							(mid 0.275042 -0.275042)
							(end 0.2032 -0.3048)
						)
						(arc
							(start -0.2032 -0.3048)
							(mid -0.275042 -0.275042)
							(end -0.3048 -0.2032)
						)
						(arc
							(start -0.3048 0.2032)
							(mid -0.275042 0.275042)
							(end -0.2032 0.3048)
						)
						(arc
							(start 0.2032 0.3048)
							(mid 0.275042 0.275042)
							(end 0.3048 0.2032)
						)
					)
					(width 0)
					(fill yes)
				)
			)
		)
		(pad "2" smd custom
			(at 0 0.4445 270)
			(size 0.1524 0.1524)
			(layers "F.Cu" "F.Mask" "F.Paste")
			(net "GND")
			(options
				(clearance outline)
				(anchor circle)
			)
			(primitives
				(gr_poly
					(pts
						(arc
							(start 0.3048 -0.2032)
							(mid 0.275042 -0.275042)
							(end 0.2032 -0.3048)
						)
						(arc
							(start -0.2032 -0.3048)
							(mid -0.275042 -0.275042)
							(end -0.3048 -0.2032)
						)
						(arc
							(start -0.3048 0.2032)
							(mid -0.275042 0.275042)
							(end -0.2032 0.3048)
						)
						(arc
							(start 0.2032 0.3048)
							(mid 0.275042 0.275042)
							(end 0.3048 0.2032)
						)
					)
					(width 0)
					(fill yes)
				)
			)
		)
	)
	(footprint ""
		(layer "F.Cu")
		(at 27.686 -381 180)
		(property "Reference" "PR17"
			(at 0 0 180)
			(layer "F.SilkS")
			(hide yes)
			(effects
				(font
					(size 1.27 1.27)
				)
			)
		)
		(property "Value" "10R2F-L-GP"
			(at 0.064008 -3.993896 180)
			(unlocked yes)
			(layer "F.Fab")
			(hide yes)
			(effects
				(font
					(size 1.016 1.016)
					(thickness 0.1524)
				)
			)
		)
		(property "Device Type" "R402H14"
			(at 0.064008 -5.517896 180)
			(unlocked yes)
			(layer "F.Fab")
			(hide yes)
			(effects
				(font
					(size 1.016 1.016)
					(thickness 0.1524)
				)
			)
		)
		(duplicate_pad_numbers_are_jumpers no)
		(fp_line
			(start 0.508 -0.9398)
			(end -0.508 -0.9398)
			(stroke
				(width 0.1524)
				(type default)
			)
			(layer "F.SilkS")
		)
		(fp_line
			(start -0.508 -0.9398)
			(end -0.508 0.9398)
			(stroke
				(width 0.1524)
				(type default)
			)
			(layer "F.SilkS")
		)
		(fp_rect
			(start -0.508 0.9398)
			(end 0.508 -0.9398)
			(stroke
				(width 0)
				(type default)
			)
			(fill no)
			(layer "F.CrtYd")
		)
		(fp_rect
			(start -0.508 0.9398)
			(end 0.508 -0.9398)
			(stroke
				(width 0)
				(type default)
			)
			(fill no)
			(layer "F.Fab")
		)
		(pad "1" smd custom
			(at 0 -0.4445 180)
			(size 0.1397 0.1397)
			(layers "F.Cu" "F.Mask" "F.Paste")
			(net "ADM1276_SENSE+")
			(options
				(clearance outline)
				(anchor circle)
			)
			(primitives
				(gr_poly
					(pts
						(arc
							(start -0.1778 -0.2794)
							(mid -0.249642 -0.249642)
							(end -0.2794 -0.1778)
						)
						(arc
							(start -0.2794 0.1778)
							(mid -0.249642 0.249642)
							(end -0.1778 0.2794)
						)
						(arc
							(start 0.1778 0.2794)
							(mid 0.249642 0.249642)
							(end 0.2794 0.1778)
						)
						(arc
							(start 0.2794 -0.1778)
							(mid 0.249642 -0.249642)
							(end 0.1778 -0.2794)
						)
					)
					(width 0)
					(fill yes)
				)
			)
		)
		(pad "2" smd custom
			(at 0 0.4445 180)
			(size 0.1397 0.1397)
			(layers "F.Cu" "F.Mask" "F.Paste")
			(net "SENSE+_R4")
			(options
				(clearance outline)
				(anchor circle)
			)
			(primitives
				(gr_poly
					(pts
						(arc
							(start -0.1778 -0.2794)
							(mid -0.249642 -0.249642)
							(end -0.2794 -0.1778)
						)
						(arc
							(start -0.2794 0.1778)
							(mid -0.249642 0.249642)
							(end -0.1778 0.2794)
						)
						(arc
							(start 0.1778 0.2794)
							(mid 0.249642 0.249642)
							(end 0.2794 0.1778)
						)
						(arc
							(start 0.2794 -0.1778)
							(mid 0.249642 -0.249642)
							(end 0.1778 -0.2794)
						)
					)
					(width 0)
					(fill yes)
				)
			)
		)
	)
	(footprint ""
		(layer "F.Cu")
		(at 18.8214 -259.3086 -90)
		(property "Reference" "R78"
			(at 0 0 270)
			(layer "F.SilkS")
			(hide yes)
			(effects
				(font
					(size 1.27 1.27)
				)
			)
		)
		(property "Value" "4K7R2F-GP"
			(at 0.064008 -3.993896 270)
			(unlocked yes)
			(layer "F.Fab")
			(hide yes)
			(effects
				(font
					(size 1.016 1.016)
					(thickness 0.1524)
				)
			)
		)
		(property "Device Type" "R402H16"
			(at 0.064008 -5.517896 270)
			(unlocked yes)
			(layer "F.Fab")
			(hide yes)
			(effects
				(font
					(size 1.016 1.016)
					(thickness 0.1524)
				)
			)
		)
		(duplicate_pad_numbers_are_jumpers no)
		(fp_line
			(start -0.508 -0.9398)
			(end -0.508 0.9398)
			(stroke
				(width 0.1524)
				(type default)
			)
			(layer "F.SilkS")
		)
		(fp_line
			(start 0.508 -0.9398)
			(end -0.508 -0.9398)
			(stroke
				(width 0.1524)
				(type default)
			)
			(layer "F.SilkS")
		)
		(fp_rect
			(start -0.508 0.9398)
			(end 0.508 -0.9398)
			(stroke
				(width 0)
				(type default)
			)
			(fill no)
			(layer "F.CrtYd")
		)
		(fp_rect
			(start -0.508 0.9398)
			(end 0.508 -0.9398)
			(stroke
				(width 0)
				(type default)
			)
			(fill no)
			(layer "F.Fab")
		)
		(pad "1" smd custom
			(at 0 -0.4445 270)
			(size 0.1397 0.1397)
			(layers "F.Cu" "F.Mask" "F.Paste")
			(net "P12V")
			(options
				(clearance outline)
				(anchor circle)
			)
			(primitives
				(gr_poly
					(pts
						(arc
							(start -0.1778 -0.2794)
							(mid -0.249642 -0.249642)
							(end -0.2794 -0.1778)
						)
						(arc
							(start -0.2794 0.1778)
							(mid -0.249642 0.249642)
							(end -0.1778 0.2794)
						)
						(arc
							(start 0.1778 0.2794)
							(mid 0.249642 0.249642)
							(end 0.2794 0.1778)
						)
						(arc
							(start 0.2794 -0.1778)
							(mid 0.249642 -0.249642)
							(end 0.1778 -0.2794)
						)
					)
					(width 0)
					(fill yes)
				)
			)
		)
		(pad "2" smd custom
			(at 0 0.4445 270)
			(size 0.1397 0.1397)
			(layers "F.Cu" "F.Mask" "F.Paste")
			(net "PWM_OUT_FAN3_NET")
			(options
				(clearance outline)
				(anchor circle)
			)
			(primitives
				(gr_poly
					(pts
						(arc
							(start -0.1778 -0.2794)
							(mid -0.249642 -0.249642)
							(end -0.2794 -0.1778)
						)
						(arc
							(start -0.2794 0.1778)
							(mid -0.249642 0.249642)
							(end -0.1778 0.2794)
						)
						(arc
							(start 0.1778 0.2794)
							(mid 0.249642 0.249642)
							(end 0.2794 0.1778)
						)
						(arc
							(start 0.2794 -0.1778)
							(mid 0.249642 -0.249642)
							(end 0.1778 -0.2794)
						)
					)
					(width 0)
					(fill yes)
				)
			)
		)
	)
	(footprint ""
		(layer "F.Cu")
		(at 18.0594 -262.1534 90)
		(property "Reference" "D5"
			(at 0 0 90)
			(layer "F.SilkS")
			(hide yes)
			(effects
				(font
					(size 1.27 1.27)
				)
			)
		)
		(property "Value" "BAS16H-GP"
			(at 0 -5.5372 90)
			(unlocked yes)
			(layer "F.Fab")
			(hide yes)
			(effects
				(font
					(size 1.016 1.016)
					(thickness 0.1524)
				)
			)
		)
		(property "Device Type" "SOD123AKH48"
			(at 0 -7.0612 90)
			(unlocked yes)
			(layer "F.Fab")
			(hide yes)
			(effects
				(font
					(size 1.016 1.016)
					(thickness 0.1524)
				)
			)
		)
		(duplicate_pad_numbers_are_jumpers no)
		(fp_line
			(start 1.016 -2.667)
			(end -1.016 -2.667)
			(stroke
				(width 0.1524)
				(type default)
			)
			(layer "F.SilkS")
		)
		(fp_line
			(start -1.016 -2.667)
			(end -1.016 2.667)
			(stroke
				(width 0.1524)
				(type default)
			)
			(layer "F.SilkS")
		)
		(fp_line
			(start 1.016 2.667)
			(end 1.016 -2.667)
			(stroke
				(width 0.1524)
				(type default)
			)
			(layer "F.SilkS")
		)
		(fp_line
			(start -1.016 2.667)
			(end 1.016 2.667)
			(stroke
				(width 0.1524)
				(type default)
			)
			(layer "F.SilkS")
		)
		(fp_line
			(start 0.889 2.921)
			(end -0.889 2.921)
			(stroke
				(width 0.508)
				(type default)
			)
			(layer "F.SilkS")
		)
		(fp_rect
			(start -1.143 3.175)
			(end 1.143 -2.794)
			(stroke
				(width 0)
				(type default)
			)
			(fill no)
			(layer "F.CrtYd")
		)
		(fp_poly
			(pts
				(xy -1.143 -2.794) (xy 1.143 -2.794) (xy 1.143 3.175) (xy -1.143 3.175)
			)
			(stroke
				(width 0)
				(type default)
			)
			(fill no)
			(layer "F.Fab")
		)
		(pad "A" smd rect
			(at 0 -1.6891 90)
			(size 0.889 1.397)
			(layers "F.Cu" "F.Mask" "F.Paste")
			(net "FAN_TACH6")
		)
		(pad "K" smd rect
			(at 0 1.6891 90)
			(size 0.889 1.397)
			(layers "F.Cu" "F.Mask" "F.Paste")
			(net "P12V")
		)
	)
	(footprint ""
		(layer "F.Cu")
		(at 26.035 -268.8336 90)
		(property "Reference" "C40"
			(at 0 0 90)
			(layer "F.SilkS")
			(hide yes)
			(effects
				(font
					(size 1.27 1.27)
				)
			)
		)
		(property "Value" "SC1U25V3KX-1-GP"
			(at 0 -2.8194 90)
			(unlocked yes)
			(layer "F.Fab")
			(hide yes)
			(effects
				(font
					(size 1.016 1.016)
					(thickness 0.1524)
				)
			)
		)
		(property "Device Type" "C603H36"
			(at 0 -4.3434 90)
			(unlocked yes)
			(layer "F.Fab")
			(hide yes)
			(effects
				(font
					(size 1.016 1.016)
					(thickness 0.1524)
				)
			)
		)
		(duplicate_pad_numbers_are_jumpers no)
		(fp_line
			(start 0.508 0)
			(end -0.508 0)
			(stroke
				(width 0.2032)
				(type default)
			)
			(layer "F.SilkS")
		)
		(fp_rect
			(start -0.5842 1.3335)
			(end 0.5842 -1.3335)
			(stroke
				(width 0)
				(type default)
			)
			(fill no)
			(layer "F.CrtYd")
		)
		(fp_rect
			(start -0.5842 1.3335)
			(end 0.5842 -1.3335)
			(stroke
				(width 0)
				(type default)
			)
			(fill no)
			(layer "F.Fab")
		)
		(pad "1" smd custom
			(at 0 -0.762 90)
			(size 0.2159 0.2159)
			(layers "F.Cu" "F.Mask" "F.Paste")
			(net "P12V")
			(options
				(clearance outline)
				(anchor circle)
			)
			(primitives
				(gr_poly
					(pts
						(arc
							(start -0.3302 -0.4318)
							(mid -0.402042 -0.402042)
							(end -0.4318 -0.3302)
						)
						(arc
							(start -0.4318 0.3302)
							(mid -0.402042 0.402042)
							(end -0.3302 0.4318)
						)
						(arc
							(start 0.3302 0.4318)
							(mid 0.402042 0.402042)
							(end 0.4318 0.3302)
						)
						(arc
							(start 0.4318 -0.3302)
							(mid 0.402042 -0.402042)
							(end 0.3302 -0.4318)
						)
					)
					(width 0)
					(fill yes)
				)
			)
		)
		(pad "2" smd custom
			(at 0 0.762 90)
			(size 0.2159 0.2159)
			(layers "F.Cu" "F.Mask" "F.Paste")
			(net "GND")
			(options
				(clearance outline)
				(anchor circle)
			)
			(primitives
				(gr_poly
					(pts
						(arc
							(start -0.3302 -0.4318)
							(mid -0.402042 -0.402042)
							(end -0.4318 -0.3302)
						)
						(arc
							(start -0.4318 0.3302)
							(mid -0.402042 0.402042)
							(end -0.3302 0.4318)
						)
						(arc
							(start 0.3302 0.4318)
							(mid 0.402042 0.402042)
							(end 0.4318 0.3302)
						)
						(arc
							(start 0.4318 -0.3302)
							(mid 0.402042 -0.402042)
							(end 0.3302 -0.4318)
						)
					)
					(width 0)
					(fill yes)
				)
			)
		)
	)
	(footprint ""
		(layer "F.Cu")
		(at 13.7922 -66.4464 180)
		(property "Reference" "R151"
			(at 0 0 180)
			(layer "F.SilkS")
			(hide yes)
			(effects
				(font
					(size 1.27 1.27)
				)
			)
		)
		(property "Value" "10R2F-L-GP"
			(at 0.064008 -3.993896 180)
			(unlocked yes)
			(layer "F.Fab")
			(hide yes)
			(effects
				(font
					(size 1.016 1.016)
					(thickness 0.1524)
				)
			)
		)
		(property "Device Type" "R402H14"
			(at 0.064008 -5.517896 180)
			(unlocked yes)
			(layer "F.Fab")
			(hide yes)
			(effects
				(font
					(size 1.016 1.016)
					(thickness 0.1524)
				)
			)
		)
		(duplicate_pad_numbers_are_jumpers no)
		(fp_line
			(start 0.508 -0.9398)
			(end -0.508 -0.9398)
			(stroke
				(width 0.1524)
				(type default)
			)
			(layer "F.SilkS")
		)
		(fp_line
			(start -0.508 -0.9398)
			(end -0.508 0.9398)
			(stroke
				(width 0.1524)
				(type default)
			)
			(layer "F.SilkS")
		)
		(fp_rect
			(start -0.508 0.9398)
			(end 0.508 -0.9398)
			(stroke
				(width 0)
				(type default)
			)
			(fill no)
			(layer "F.CrtYd")
		)
		(fp_rect
			(start -0.508 0.9398)
			(end 0.508 -0.9398)
			(stroke
				(width 0)
				(type default)
			)
			(fill no)
			(layer "F.Fab")
		)
		(pad "1" smd custom
			(at 0 -0.4445 180)
			(size 0.1397 0.1397)
			(layers "F.Cu" "F.Mask" "F.Paste")
			(net "I2C_C_SCL_CONN_R")
			(options
				(clearance outline)
				(anchor circle)
			)
			(primitives
				(gr_poly
					(pts
						(arc
							(start -0.1778 -0.2794)
							(mid -0.249642 -0.249642)
							(end -0.2794 -0.1778)
						)
						(arc
							(start -0.2794 0.1778)
							(mid -0.249642 0.249642)
							(end -0.1778 0.2794)
						)
						(arc
							(start 0.1778 0.2794)
							(mid 0.249642 0.249642)
							(end 0.2794 0.1778)
						)
						(arc
							(start 0.2794 -0.1778)
							(mid 0.249642 -0.249642)
							(end 0.1778 -0.2794)
						)
					)
					(width 0)
					(fill yes)
				)
			)
		)
		(pad "2" smd custom
			(at 0 0.4445 180)
			(size 0.1397 0.1397)
			(layers "F.Cu" "F.Mask" "F.Paste")
			(net "I2C_C_SCL")
			(options
				(clearance outline)
				(anchor circle)
			)
			(primitives
				(gr_poly
					(pts
						(arc
							(start -0.1778 -0.2794)
							(mid -0.249642 -0.249642)
							(end -0.2794 -0.1778)
						)
						(arc
							(start -0.2794 0.1778)
							(mid -0.249642 0.249642)
							(end -0.1778 0.2794)
						)
						(arc
							(start 0.1778 0.2794)
							(mid 0.249642 0.249642)
							(end 0.2794 0.1778)
						)
						(arc
							(start 0.2794 -0.1778)
							(mid 0.249642 -0.249642)
							(end 0.1778 -0.2794)
						)
					)
					(width 0)
					(fill yes)
				)
			)
		)
	)
	(footprint ""
		(layer "F.Cu")
		(at 17.018 -185.42 -90)
		(property "Reference" "R79"
			(at 0 0 270)
			(layer "F.SilkS")
			(hide yes)
			(effects
				(font
					(size 1.27 1.27)
				)
			)
		)
		(property "Value" "4K7R2F-GP"
			(at 0.064008 -3.993896 270)
			(unlocked yes)
			(layer "F.Fab")
			(hide yes)
			(effects
				(font
					(size 1.016 1.016)
					(thickness 0.1524)
				)
			)
		)
		(property "Device Type" "R402H16"
			(at 0.064008 -5.517896 270)
			(unlocked yes)
			(layer "F.Fab")
			(hide yes)
			(effects
				(font
					(size 1.016 1.016)
					(thickness 0.1524)
				)
			)
		)
		(duplicate_pad_numbers_are_jumpers no)
		(fp_line
			(start -0.508 -0.9398)
			(end -0.508 0.9398)
			(stroke
				(width 0.1524)
				(type default)
			)
			(layer "F.SilkS")
		)
		(fp_line
			(start 0.508 -0.9398)
			(end -0.508 -0.9398)
			(stroke
				(width 0.1524)
				(type default)
			)
			(layer "F.SilkS")
		)
		(fp_rect
			(start -0.508 0.9398)
			(end 0.508 -0.9398)
			(stroke
				(width 0)
				(type default)
			)
			(fill no)
			(layer "F.CrtYd")
		)
		(fp_rect
			(start -0.508 0.9398)
			(end 0.508 -0.9398)
			(stroke
				(width 0)
				(type default)
			)
			(fill no)
			(layer "F.Fab")
		)
		(pad "1" smd custom
			(at 0 -0.4445 270)
			(size 0.1397 0.1397)
			(layers "F.Cu" "F.Mask" "F.Paste")
			(net "P12V")
			(options
				(clearance outline)
				(anchor circle)
			)
			(primitives
				(gr_poly
					(pts
						(arc
							(start -0.1778 -0.2794)
							(mid -0.249642 -0.249642)
							(end -0.2794 -0.1778)
						)
						(arc
							(start -0.2794 0.1778)
							(mid -0.249642 0.249642)
							(end -0.1778 0.2794)
						)
						(arc
							(start 0.1778 0.2794)
							(mid 0.249642 0.249642)
							(end 0.2794 0.1778)
						)
						(arc
							(start 0.2794 -0.1778)
							(mid 0.249642 -0.249642)
							(end 0.1778 -0.2794)
						)
					)
					(width 0)
					(fill yes)
				)
			)
		)
		(pad "2" smd custom
			(at 0 0.4445 270)
			(size 0.1397 0.1397)
			(layers "F.Cu" "F.Mask" "F.Paste")
			(net "PWM_OUT_FAN4_NET")
			(options
				(clearance outline)
				(anchor circle)
			)
			(primitives
				(gr_poly
					(pts
						(arc
							(start -0.1778 -0.2794)
							(mid -0.249642 -0.249642)
							(end -0.2794 -0.1778)
						)
						(arc
							(start -0.2794 0.1778)
							(mid -0.249642 0.249642)
							(end -0.1778 0.2794)
						)
						(arc
							(start 0.1778 0.2794)
							(mid 0.249642 0.249642)
							(end 0.2794 0.1778)
						)
						(arc
							(start 0.2794 -0.1778)
							(mid 0.249642 -0.249642)
							(end 0.1778 -0.2794)
						)
					)
					(width 0)
					(fill yes)
				)
			)
		)
	)
	(footprint ""
		(layer "F.Cu")
		(at 28.321 -352.425 -90)
		(property "Reference" "C260"
			(at 0 0 270)
			(layer "F.SilkS")
			(hide yes)
			(effects
				(font
					(size 1.27 1.27)
				)
			)
		)
		(property "Value" "SC10U25V6KX-1GP"
			(at -0.0762 -5.1308 270)
			(unlocked yes)
			(layer "F.Fab")
			(hide yes)
			(effects
				(font
					(size 1.016 1.016)
					(thickness 0.1524)
				)
			)
		)
		(property "Device Type" "C1206H71"
			(at -0.127 -6.6548 270)
			(unlocked yes)
			(layer "F.Fab")
			(hide yes)
			(effects
				(font
					(size 1.016 1.016)
					(thickness 0.1524)
				)
			)
		)
		(duplicate_pad_numbers_are_jumpers no)
		(fp_line
			(start -1.016 2.2352)
			(end -1.016 0.8382)
			(stroke
				(width 0.1524)
				(type default)
			)
			(layer "F.SilkS")
		)
		(fp_line
			(start 1.016 2.2352)
			(end -1.016 2.2352)
			(stroke
				(width 0.1524)
				(type default)
			)
			(layer "F.SilkS")
		)
		(fp_line
			(start 1.016 0.8382)
			(end 1.016 2.2352)
			(stroke
				(width 0.1524)
				(type default)
			)
			(layer "F.SilkS")
		)
		(fp_line
			(start -1.016 -0.8382)
			(end -1.016 -2.2352)
			(stroke
				(width 0.1524)
				(type default)
			)
			(layer "F.SilkS")
		)
		(fp_line
			(start -1.016 -2.2352)
			(end 1.016 -2.2352)
			(stroke
				(width 0.1524)
				(type default)
			)
			(layer "F.SilkS")
		)
		(fp_line
			(start 1.016 -2.2352)
			(end 1.016 -0.8382)
			(stroke
				(width 0.1524)
				(type default)
			)
			(layer "F.SilkS")
		)
		(fp_rect
			(start -1.0922 2.3114)
			(end 1.0922 -2.3114)
			(stroke
				(width 0)
				(type default)
			)
			(fill no)
			(layer "F.CrtYd")
		)
		(fp_poly
			(pts
				(xy 1.0922 -2.3114) (xy 1.0922 2.3114) (xy -1.0922 2.3114) (xy -1.0922 -2.3114)
			)
			(stroke
				(width 0)
				(type default)
			)
			(fill no)
			(layer "F.Fab")
		)
		(pad "1" smd rect
			(at 0 -1.397 270)
			(size 1.651 1.27)
			(layers "F.Cu" "F.Mask" "F.Paste")
			(net "OTP_RETRY_G")
		)
		(pad "2" smd rect
			(at 0 1.397 270)
			(size 1.651 1.27)
			(layers "F.Cu" "F.Mask" "F.Paste")
			(net "GND")
		)
	)
	(footprint ""
		(layer "F.Cu")
		(at 29.718 -368.808 90)
		(property "Reference" "PU1"
			(at 0 0 90)
			(layer "F.SilkS")
			(hide yes)
			(effects
				(font
					(size 1.27 1.27)
				)
			)
		)
		(property "Value" "ADM1276-3ACPZ-RL-GP"
			(at -5.3975 -5.0292 90)
			(unlocked yes)
			(layer "F.Fab")
			(hide yes)
			(effects
				(font
					(size 1.016 1.016)
					(thickness 0.1524)
				)
			)
		)
		(property "Device Type" "QFN20-G3D25H32"
			(at -5.3975 -6.5532 90)
			(unlocked yes)
			(layer "F.Fab")
			(hide yes)
			(effects
				(font
					(size 1.016 1.016)
					(thickness 0.1524)
				)
			)
		)
		(duplicate_pad_numbers_are_jumpers no)
		(fp_line
			(start -3.5179 -3.5179)
			(end -2.2479 -3.5179)
			(stroke
				(width 0.1524)
				(type default)
			)
			(layer "F.SilkS")
		)
		(fp_line
			(start -1.3208 -3.302)
			(end -1.3208 -3.81)
			(stroke
				(width 0.1524)
				(type default)
			)
			(layer "F.SilkS")
		)
		(fp_line
			(start -3.5179 -2.2479)
			(end -3.5179 -3.5179)
			(stroke
				(width 0.1524)
				(type default)
			)
			(layer "F.SilkS")
		)
		(fp_line
			(start 3.302 -1.2954)
			(end 4.064 -1.2954)
			(stroke
				(width 0.1524)
				(type default)
			)
			(layer "F.SilkS")
		)
		(fp_line
			(start -4.064 1.2954)
			(end -3.302 1.2954)
			(stroke
				(width 0.1524)
				(type default)
			)
			(layer "F.SilkS")
		)
		(fp_line
			(start -3.5179 2.2479)
			(end -3.5179 3.5179)
			(stroke
				(width 0.1524)
				(type default)
			)
			(layer "F.SilkS")
		)
		(fp_line
			(start 3.5179 3.5179)
			(end 3.5179 2.2479)
			(stroke
				(width 0.1524)
				(type default)
			)
			(layer "F.SilkS")
		)
		(fp_line
			(start 2.2479 3.5179)
			(end 3.5179 3.5179)
			(stroke
				(width 0.1524)
				(type default)
			)
			(layer "F.SilkS")
		)
		(fp_line
			(start -3.5179 3.5179)
			(end -2.2479 3.5179)
			(stroke
				(width 0.1524)
				(type default)
			)
			(layer "F.SilkS")
		)
		(fp_line
			(start 1.2954 3.81)
			(end 1.2954 3.302)
			(stroke
				(width 0.1524)
				(type default)
			)
			(layer "F.SilkS")
		)
		(fp_poly
			(pts
				(xy 2.2479 -3.5179) (xy 3.5179 -2.2479) (xy 3.5179 -3.5179)
			)
			(stroke
				(width 0)
				(type default)
			)
			(fill yes)
			(layer "F.SilkS")
		)
		(fp_rect
			(start -2.5019 2.5019)
			(end 2.5019 -2.5019)
			(stroke
				(width 0)
				(type default)
			)
			(fill no)
			(layer "F.CrtYd")
		)
		(fp_poly
			(pts
				(xy -3.5179 3.5179) (xy -3.5179 -2.49682) (xy -2.5019 -2.49682) (xy -2.5019 2.5019) (xy 2.5019 2.5019)
				(xy 2.5019 -2.5019) (xy -3.5179 -2.5019) (xy -3.5179 -3.5179) (xy 3.5179 -3.5179) (xy 3.5179 3.5179)
			)
			(stroke
				(width 0)
				(type default)
			)
			(fill no)
			(layer "F.CrtYd")
		)
		(fp_rect
			(start -3.5179 3.5179)
			(end 3.5179 -3.5179)
			(stroke
				(width 0)
				(type default)
			)
			(fill no)
			(layer "F.Fab")
		)
		(pad "1" smd rect
			(at 1.299972 -2.4384 90)
			(size 0.4064 1.143)
			(layers "F.Cu" "F.Mask" "F.Paste")
			(net "ADM1276_OV")
		)
		(pad "2" smd rect
			(at 0.649986 -2.4384 90)
			(size 0.4064 1.143)
			(layers "F.Cu" "F.Mask" "F.Paste")
			(net "ADM1276_VCAP")
		)
		(pad "3" smd rect
			(at 0 -2.4384 90)
			(size 0.4064 1.143)
			(layers "F.Cu" "F.Mask" "F.Paste")
			(net "ADM1276_ISET")
		)
		(pad "4" smd rect
			(at -0.649986 -2.4384 90)
			(size 0.4064 1.143)
			(layers "F.Cu" "F.Mask" "F.Paste")
			(net "ADM1276_SS")
		)
		(pad "5" smd rect
			(at -1.299972 -2.4384 90)
			(size 0.4064 1.143)
			(layers "F.Cu" "F.Mask" "F.Paste")
			(net "ADM1276_TIMER")
		)
		(pad "6" smd rect
			(at -2.4384 -1.299972 90)
			(size 1.143 0.4064)
			(layers "F.Cu" "F.Mask" "F.Paste")
			(net "ADM1276_LATCH#")
		)
		(pad "7" smd rect
			(at -2.4384 -0.649986 90)
			(size 1.143 0.4064)
			(layers "F.Cu" "F.Mask" "F.Paste")
			(net "ADM1276_ADR")
		)
		(pad "8" smd rect
			(at -2.4384 0 90)
			(size 1.143 0.4064)
			(layers "F.Cu" "F.Mask" "F.Paste")
			(net "ADM1276_EN")
		)
		(pad "9" smd rect
			(at -2.4384 0.649986 90)
			(size 1.143 0.4064)
			(layers "F.Cu" "F.Mask" "F.Paste")
			(net "ADM1276_GPIO2")
		)
		(pad "10" smd rect
			(at -2.4384 1.299972 90)
			(size 1.143 0.4064)
			(layers "F.Cu" "F.Mask" "F.Paste")
			(net "I2C_C_SDA_ADM1276")
		)
		(pad "11" smd rect
			(at -1.299972 2.4384 90)
			(size 0.4064 1.143)
			(layers "F.Cu" "F.Mask" "F.Paste")
			(net "I2C_C_SCL_ADM1276")
		)
		(pad "12" smd rect
			(at -0.649986 2.4384 90)
			(size 0.4064 1.143)
			(layers "F.Cu" "F.Mask" "F.Paste")
			(net "ADM1276_PWRGD")
		)
		(pad "13" smd rect
			(at 0 2.4384 90)
			(size 0.4064 1.143)
			(layers "F.Cu" "F.Mask" "F.Paste")
			(net "ADM1276_FLB")
		)
		(pad "14" smd rect
			(at 0.649986 2.4384 90)
			(size 0.4064 1.143)
			(layers "F.Cu" "F.Mask" "F.Paste")
			(net "ADM1276_VOUT")
		)
		(pad "15" smd rect
			(at 1.299972 2.4384 90)
			(size 0.4064 1.143)
			(layers "F.Cu" "F.Mask" "F.Paste")
			(net "GND")
		)
		(pad "16" smd rect
			(at 2.4384 1.299972 90)
			(size 1.143 0.4064)
			(layers "F.Cu" "F.Mask" "F.Paste")
			(net "ADM1276_GATE_DRV")
		)
		(pad "17" smd rect
			(at 2.4384 0.649986 90)
			(size 1.143 0.4064)
			(layers "F.Cu" "F.Mask" "F.Paste")
			(net "ADM1276_SENSE-")
		)
		(pad "18" smd rect
			(at 2.4384 0 90)
			(size 1.143 0.4064)
			(layers "F.Cu" "F.Mask" "F.Paste")
			(net "ADM1276_SENSE+")
		)
		(pad "19" smd rect
			(at 2.4384 -0.649986 90)
			(size 1.143 0.4064)
			(layers "F.Cu" "F.Mask" "F.Paste")
			(net "ADM1276_VCC")
		)
		(pad "20" smd rect
			(at 2.4384 -1.299972 90)
			(size 1.143 0.4064)
			(layers "F.Cu" "F.Mask" "F.Paste")
			(net "ADM1276_UV")
		)
		(pad "21" smd rect
			(at 0 0 90)
			(size 3.2512 3.2512)
			(layers "F.Cu" "F.Mask" "F.Paste")
			(net "GND")
		)
	)
	(footprint ""
		(layer "F.Cu")
		(at 16.052292 -289.636962 180)
		(property "Reference" "R102"
			(at 0 0 180)
			(layer "F.SilkS")
			(hide yes)
			(effects
				(font
					(size 1.27 1.27)
				)
			)
		)
		(property "Value" "10KR2F-2-GP"
			(at 0.064008 -3.993896 180)
			(unlocked yes)
			(layer "F.Fab")
			(hide yes)
			(effects
				(font
					(size 1.016 1.016)
					(thickness 0.1524)
				)
			)
		)
		(property "Device Type" "R402H16"
			(at 0.064008 -5.517896 180)
			(unlocked yes)
			(layer "F.Fab")
			(hide yes)
			(effects
				(font
					(size 1.016 1.016)
					(thickness 0.1524)
				)
			)
		)
		(duplicate_pad_numbers_are_jumpers no)
		(fp_line
			(start 0.508 -0.9398)
			(end -0.508 -0.9398)
			(stroke
				(width 0.1524)
				(type default)
			)
			(layer "F.SilkS")
		)
		(fp_line
			(start -0.508 -0.9398)
			(end -0.508 0.9398)
			(stroke
				(width 0.1524)
				(type default)
			)
			(layer "F.SilkS")
		)
		(fp_rect
			(start -0.508 0.9398)
			(end 0.508 -0.9398)
			(stroke
				(width 0)
				(type default)
			)
			(fill no)
			(layer "F.CrtYd")
		)
		(fp_rect
			(start -0.508 0.9398)
			(end 0.508 -0.9398)
			(stroke
				(width 0)
				(type default)
			)
			(fill no)
			(layer "F.Fab")
		)
		(pad "1" smd custom
			(at 0 -0.4445 180)
			(size 0.1397 0.1397)
			(layers "F.Cu" "F.Mask" "F.Paste")
			(net "FANIN_3")
			(options
				(clearance outline)
				(anchor circle)
			)
			(primitives
				(gr_poly
					(pts
						(arc
							(start -0.1778 -0.2794)
							(mid -0.249642 -0.249642)
							(end -0.2794 -0.1778)
						)
						(arc
							(start -0.2794 0.1778)
							(mid -0.249642 0.249642)
							(end -0.1778 0.2794)
						)
						(arc
							(start 0.1778 0.2794)
							(mid 0.249642 0.249642)
							(end 0.2794 0.1778)
						)
						(arc
							(start 0.2794 -0.1778)
							(mid 0.249642 -0.249642)
							(end 0.1778 -0.2794)
						)
					)
					(width 0)
					(fill yes)
				)
			)
		)
		(pad "2" smd custom
			(at 0 0.4445 180)
			(size 0.1397 0.1397)
			(layers "F.Cu" "F.Mask" "F.Paste")
			(net "GND")
			(options
				(clearance outline)
				(anchor circle)
			)
			(primitives
				(gr_poly
					(pts
						(arc
							(start -0.1778 -0.2794)
							(mid -0.249642 -0.249642)
							(end -0.2794 -0.1778)
						)
						(arc
							(start -0.2794 0.1778)
							(mid -0.249642 0.249642)
							(end -0.1778 0.2794)
						)
						(arc
							(start 0.1778 0.2794)
							(mid 0.249642 0.249642)
							(end 0.2794 0.1778)
						)
						(arc
							(start 0.2794 -0.1778)
							(mid 0.249642 -0.249642)
							(end 0.1778 -0.2794)
						)
					)
					(width 0)
					(fill yes)
				)
			)
		)
	)
	(footprint ""
		(layer "F.Cu")
		(at 21.336 -375.285 -90)
		(property "Reference" "PC10"
			(at 0 0 270)
			(layer "F.SilkS")
			(hide yes)
			(effects
				(font
					(size 1.27 1.27)
				)
			)
		)
		(property "Value" "SC1U25V5KX-1GP"
			(at -0.0762 -6.1214 270)
			(unlocked yes)
			(layer "F.Fab")
			(hide yes)
			(effects
				(font
					(size 1.016 1.016)
					(thickness 0.1524)
				)
			)
		)
		(property "Device Type" "C805H58"
			(at -0.0762 -8.1534 270)
			(unlocked yes)
			(layer "F.Fab")
			(hide yes)
			(effects
				(font
					(size 1.016 1.016)
					(thickness 0.1524)
				)
			)
		)
		(duplicate_pad_numbers_are_jumpers no)
		(fp_line
			(start 0.635 0)
			(end -0.635 0)
			(stroke
				(width 0.508)
				(type default)
			)
			(layer "F.SilkS")
		)
		(fp_rect
			(start -0.9652 1.778)
			(end 0.9652 -1.778)
			(stroke
				(width 0)
				(type default)
			)
			(fill no)
			(layer "F.CrtYd")
		)
		(fp_poly
			(pts
				(xy -0.9652 -1.778) (xy 0.9652 -1.778) (xy 0.9652 1.778) (xy -0.9652 1.778)
			)
			(stroke
				(width 0)
				(type default)
			)
			(fill no)
			(layer "F.Fab")
		)
		(pad "1" smd rect
			(at 0 -0.9652 270)
			(size 1.397 1.143)
			(layers "F.Cu" "F.Mask" "F.Paste")
			(net "ADM1276_UV")
		)
		(pad "2" smd rect
			(at 0 0.9652 270)
			(size 1.397 1.143)
			(layers "F.Cu" "F.Mask" "F.Paste")
			(net "GND")
		)
	)
	(footprint ""
		(layer "F.Cu")
		(at 20.500086 -56.999886 -90)
		(property "Reference" "CN9"
			(at 0 0 270)
			(layer "F.SilkS")
			(hide yes)
			(effects
				(font
					(size 1.27 1.27)
				)
			)
		)
		(property "Value" "FCI-CONN52-4R-1-GP"
			(at -30.89656 -6.096 270)
			(unlocked yes)
			(layer "F.Fab")
			(hide yes)
			(effects
				(font
					(size 1.016 1.016)
					(thickness 0.1524)
				)
			)
		)
		(property "Device Type" "51952-220LF"
			(at -30.89656 -7.62 270)
			(unlocked yes)
			(layer "F.Fab")
			(hide yes)
			(effects
				(font
					(size 1.016 1.016)
					(thickness 0.1524)
				)
			)
		)
		(duplicate_pad_numbers_are_jumpers no)
		(fp_line
			(start -29.464 3.7338)
			(end -29.464 -3.7338)
			(stroke
				(width 0.1524)
				(type default)
			)
			(layer "F.SilkS")
		)
		(fp_line
			(start 29.464 3.7338)
			(end -29.464 3.7338)
			(stroke
				(width 0.1524)
				(type default)
			)
			(layer "F.SilkS")
		)
		(fp_line
			(start -29.464 -3.7338)
			(end -22.225 -3.7338)
			(stroke
				(width 0.1524)
				(type default)
			)
			(layer "F.SilkS")
		)
		(fp_line
			(start -22.225 -3.7338)
			(end -22.225 -11.3538)
			(stroke
				(width 0.1524)
				(type default)
			)
			(layer "F.SilkS")
		)
		(fp_line
			(start 22.225 -3.7338)
			(end 29.464 -3.7338)
			(stroke
				(width 0.1524)
				(type default)
			)
			(layer "F.SilkS")
		)
		(fp_line
			(start 29.464 -3.7338)
			(end 29.464 3.7338)
			(stroke
				(width 0.1524)
				(type default)
			)
			(layer "F.SilkS")
		)
		(fp_line
			(start -22.225 -11.3538)
			(end 22.225 -11.3538)
			(stroke
				(width 0.1524)
				(type default)
			)
			(layer "F.SilkS")
		)
		(fp_line
			(start 22.225 -11.3538)
			(end 22.225 -3.7338)
			(stroke
				(width 0.1524)
				(type default)
			)
			(layer "F.SilkS")
		)
		(fp_circle
			(center -15.88008 0)
			(end -15.88008 -1.0795)
			(stroke
				(width 0.3048)
				(type default)
			)
			(fill no)
			(layer "F.SilkS")
		)
		(fp_circle
			(center -13.34008 0)
			(end -13.34008 -1.0795)
			(stroke
				(width 0.3048)
				(type default)
			)
			(fill no)
			(layer "F.SilkS")
		)
		(fp_circle
			(center -10.80008 0)
			(end -10.80008 -1.0795)
			(stroke
				(width 0.3048)
				(type default)
			)
			(fill no)
			(layer "F.SilkS")
		)
		(fp_circle
			(center -8.26008 0)
			(end -8.26008 -1.0795)
			(stroke
				(width 0.3048)
				(type default)
			)
			(fill no)
			(layer "F.SilkS")
		)
		(fp_circle
			(center -5.08 0)
			(end -5.08 -1.0795)
			(stroke
				(width 0.3048)
				(type default)
			)
			(fill no)
			(layer "F.SilkS")
		)
		(fp_circle
			(center -2.54 0)
			(end -2.54 -1.0795)
			(stroke
				(width 0.3048)
				(type default)
			)
			(fill no)
			(layer "F.SilkS")
		)
		(fp_circle
			(center 0 0)
			(end 0 -1.0795)
			(stroke
				(width 0.3048)
				(type default)
			)
			(fill no)
			(layer "F.SilkS")
		)
		(fp_circle
			(center 2.54 0)
			(end 2.54 -1.0795)
			(stroke
				(width 0.3048)
				(type default)
			)
			(fill no)
			(layer "F.SilkS")
		)
		(fp_circle
			(center 5.08 0)
			(end 5.08 -1.0795)
			(stroke
				(width 0.3048)
				(type default)
			)
			(fill no)
			(layer "F.SilkS")
		)
		(fp_circle
			(center 8.26008 0)
			(end 8.26008 -1.0795)
			(stroke
				(width 0.3048)
				(type default)
			)
			(fill no)
			(layer "F.SilkS")
		)
		(fp_circle
			(center 10.80008 0)
			(end 10.80008 -1.0795)
			(stroke
				(width 0.3048)
				(type default)
			)
			(fill no)
			(layer "F.SilkS")
		)
		(fp_circle
			(center 13.34008 0)
			(end 13.34008 -1.0795)
			(stroke
				(width 0.3048)
				(type default)
			)
			(fill no)
			(layer "F.SilkS")
		)
		(fp_circle
			(center 15.88008 0)
			(end 15.88008 -1.0795)
			(stroke
				(width 0.3048)
				(type default)
			)
			(fill no)
			(layer "F.SilkS")
		)
		(fp_circle
			(center -15.88008 -2.54)
			(end -15.88008 -3.6195)
			(stroke
				(width 0.3048)
				(type default)
			)
			(fill no)
			(layer "F.SilkS")
		)
		(fp_circle
			(center -13.34008 -2.54)
			(end -13.34008 -3.6195)
			(stroke
				(width 0.3048)
				(type default)
			)
			(fill no)
			(layer "F.SilkS")
		)
		(fp_circle
			(center -10.80008 -2.54)
			(end -10.80008 -3.6195)
			(stroke
				(width 0.3048)
				(type default)
			)
			(fill no)
			(layer "F.SilkS")
		)
		(fp_circle
			(center -8.26008 -2.54)
			(end -8.26008 -3.6195)
			(stroke
				(width 0.3048)
				(type default)
			)
			(fill no)
			(layer "F.SilkS")
		)
		(fp_circle
			(center -5.08 -2.54)
			(end -5.08 -3.6195)
			(stroke
				(width 0.3048)
				(type default)
			)
			(fill no)
			(layer "F.SilkS")
		)
		(fp_circle
			(center -2.54 -2.54)
			(end -2.54 -3.6195)
			(stroke
				(width 0.3048)
				(type default)
			)
			(fill no)
			(layer "F.SilkS")
		)
		(fp_circle
			(center 0 -2.54)
			(end 0 -3.6195)
			(stroke
				(width 0.3048)
				(type default)
			)
			(fill no)
			(layer "F.SilkS")
		)
		(fp_circle
			(center 2.54 -2.54)
			(end 2.54 -3.6195)
			(stroke
				(width 0.3048)
				(type default)
			)
			(fill no)
			(layer "F.SilkS")
		)
		(fp_circle
			(center 5.08 -2.54)
			(end 5.08 -3.6195)
			(stroke
				(width 0.3048)
				(type default)
			)
			(fill no)
			(layer "F.SilkS")
		)
		(fp_circle
			(center 8.26008 -2.54)
			(end 8.26008 -3.6195)
			(stroke
				(width 0.3048)
				(type default)
			)
			(fill no)
			(layer "F.SilkS")
		)
		(fp_circle
			(center 10.80008 -2.54)
			(end 10.80008 -3.6195)
			(stroke
				(width 0.3048)
				(type default)
			)
			(fill no)
			(layer "F.SilkS")
		)
		(fp_circle
			(center 13.34008 -2.54)
			(end 13.34008 -3.6195)
			(stroke
				(width 0.3048)
				(type default)
			)
			(fill no)
			(layer "F.SilkS")
		)
		(fp_circle
			(center 15.88008 -2.54)
			(end 15.88008 -3.6195)
			(stroke
				(width 0.3048)
				(type default)
			)
			(fill no)
			(layer "F.SilkS")
		)
		(fp_circle
			(center -15.88008 -5.08)
			(end -15.88008 -6.1595)
			(stroke
				(width 0.3048)
				(type default)
			)
			(fill no)
			(layer "F.SilkS")
		)
		(fp_circle
			(center -13.34008 -5.08)
			(end -13.34008 -6.1595)
			(stroke
				(width 0.3048)
				(type default)
			)
			(fill no)
			(layer "F.SilkS")
		)
		(fp_circle
			(center -10.80008 -5.08)
			(end -10.80008 -6.1595)
			(stroke
				(width 0.3048)
				(type default)
			)
			(fill no)
			(layer "F.SilkS")
		)
		(fp_circle
			(center -8.26008 -5.08)
			(end -8.26008 -6.1595)
			(stroke
				(width 0.3048)
				(type default)
			)
			(fill no)
			(layer "F.SilkS")
		)
		(fp_circle
			(center -5.08 -5.08)
			(end -5.08 -6.1595)
			(stroke
				(width 0.3048)
				(type default)
			)
			(fill no)
			(layer "F.SilkS")
		)
		(fp_circle
			(center -2.54 -5.08)
			(end -2.54 -6.1595)
			(stroke
				(width 0.3048)
				(type default)
			)
			(fill no)
			(layer "F.SilkS")
		)
		(fp_circle
			(center 0 -5.08)
			(end 0 -6.1595)
			(stroke
				(width 0.3048)
				(type default)
			)
			(fill no)
			(layer "F.SilkS")
		)
		(fp_circle
			(center 2.54 -5.08)
			(end 2.54 -6.1595)
			(stroke
				(width 0.3048)
				(type default)
			)
			(fill no)
			(layer "F.SilkS")
		)
		(fp_circle
			(center 5.08 -5.08)
			(end 5.08 -6.1595)
			(stroke
				(width 0.3048)
				(type default)
			)
			(fill no)
			(layer "F.SilkS")
		)
		(fp_circle
			(center 8.26008 -5.08)
			(end 8.26008 -6.1595)
			(stroke
				(width 0.3048)
				(type default)
			)
			(fill no)
			(layer "F.SilkS")
		)
		(fp_circle
			(center 10.80008 -5.08)
			(end 10.80008 -6.1595)
			(stroke
				(width 0.3048)
				(type default)
			)
			(fill no)
			(layer "F.SilkS")
		)
		(fp_circle
			(center 13.34008 -5.08)
			(end 13.34008 -6.1595)
			(stroke
				(width 0.3048)
				(type default)
			)
			(fill no)
			(layer "F.SilkS")
		)
		(fp_circle
			(center 15.88008 -5.08)
			(end 15.88008 -6.1595)
			(stroke
				(width 0.3048)
				(type default)
			)
			(fill no)
			(layer "F.SilkS")
		)
		(fp_circle
			(center -15.88008 -7.62)
			(end -15.88008 -8.6995)
			(stroke
				(width 0.3048)
				(type default)
			)
			(fill no)
			(layer "F.SilkS")
		)
		(fp_circle
			(center -13.34008 -7.62)
			(end -13.34008 -8.6995)
			(stroke
				(width 0.3048)
				(type default)
			)
			(fill no)
			(layer "F.SilkS")
		)
		(fp_circle
			(center -10.80008 -7.62)
			(end -10.80008 -8.6995)
			(stroke
				(width 0.3048)
				(type default)
			)
			(fill no)
			(layer "F.SilkS")
		)
		(fp_circle
			(center -8.26008 -7.62)
			(end -8.26008 -8.6995)
			(stroke
				(width 0.3048)
				(type default)
			)
			(fill no)
			(layer "F.SilkS")
		)
		(fp_circle
			(center -5.08 -7.62)
			(end -5.08 -8.6995)
			(stroke
				(width 0.3048)
				(type default)
			)
			(fill no)
			(layer "F.SilkS")
		)
		(fp_circle
			(center -2.54 -7.62)
			(end -2.54 -8.6995)
			(stroke
				(width 0.3048)
				(type default)
			)
			(fill no)
			(layer "F.SilkS")
		)
		(fp_circle
			(center 0 -7.62)
			(end 0 -8.6995)
			(stroke
				(width 0.3048)
				(type default)
			)
			(fill no)
			(layer "F.SilkS")
		)
		(fp_circle
			(center 2.54 -7.62)
			(end 2.54 -8.6995)
			(stroke
				(width 0.3048)
				(type default)
			)
			(fill no)
			(layer "F.SilkS")
		)
		(fp_circle
			(center 5.08 -7.62)
			(end 5.08 -8.6995)
			(stroke
				(width 0.3048)
				(type default)
			)
			(fill no)
			(layer "F.SilkS")
		)
		(fp_circle
			(center 8.26008 -7.62)
			(end 8.26008 -8.6995)
			(stroke
				(width 0.3048)
				(type default)
			)
			(fill no)
			(layer "F.SilkS")
		)
		(fp_circle
			(center 10.80008 -7.62)
			(end 10.80008 -8.6995)
			(stroke
				(width 0.3048)
				(type default)
			)
			(fill no)
			(layer "F.SilkS")
		)
		(fp_circle
			(center 13.34008 -7.62)
			(end 13.34008 -8.6995)
			(stroke
				(width 0.3048)
				(type default)
			)
			(fill no)
			(layer "F.SilkS")
		)
		(fp_circle
			(center 15.88008 -7.62)
			(end 15.88008 -8.6995)
			(stroke
				(width 0.3048)
				(type default)
			)
			(fill no)
			(layer "F.SilkS")
		)
		(fp_poly
			(pts
				(xy -29.21 3.4798) (xy -29.21 -3.4798) (xy -21.971 -3.4798) (xy -21.971 -11.0998) (xy 21.971 -11.0998)
				(xy 21.971 -3.4798) (xy 29.21 -3.4798) (xy 29.21 3.4798)
			)
			(stroke
				(width 0)
				(type default)
			)
			(fill no)
			(layer "F.CrtYd")
		)
		(fp_poly
			(pts
				(xy -29.718 3.9878) (xy -29.718 -11.6078) (xy 29.718 -11.6078) (xy 29.718 -0.00635) (xy 29.21 -0.00635)
				(xy 29.21 -3.4798) (xy 21.971 -3.4798) (xy 21.971 -11.0998) (xy -21.971 -11.0998) (xy -21.971 -3.4798)
				(xy -29.21 -3.4798) (xy -29.21 3.4798) (xy 29.21 3.4798) (xy 29.21 0.00635) (xy 29.718 0.00635)
				(xy 29.718 3.9878)
			)
			(stroke
				(width 0)
				(type default)
			)
			(fill no)
			(layer "F.CrtYd")
		)
		(fp_poly
			(pts
				(xy -29.718 3.9878) (xy -29.718 -11.6078) (xy 29.718 -11.6078) (xy 29.718 3.9878)
			)
			(stroke
				(width 0)
				(type default)
			)
			(fill no)
			(layer "F.Fab")
		)
		(pad "" np_thru_hole circle
			(at -26.67 0 270)
			(size 0.254 0.254)
			(drill 3.2004)
			(layers "*.Cu" "*.Mask")
			(clearance 1.8288)
			(thermal_gap 1.8288)
		)
		(pad "" np_thru_hole circle
			(at -21.59 0 270)
			(size 0.254 0.254)
			(drill 2.5146)
			(layers "*.Cu" "*.Mask")
			(clearance 1.4859)
			(thermal_gap 1.4859)
		)
		(pad "" np_thru_hole circle
			(at 21.59 0 270)
			(size 0.254 0.254)
			(drill 2.5146)
			(layers "*.Cu" "*.Mask")
			(clearance 1.4859)
			(thermal_gap 1.4859)
		)
		(pad "" np_thru_hole circle
			(at 26.67 0 270)
			(size 0.254 0.254)
			(drill 3.2004)
			(layers "*.Cu" "*.Mask")
			(clearance 1.8288)
			(thermal_gap 1.8288)
		)
		(pad "A1" thru_hole circle
			(at -5.08 0 270)
			(size 1.4478 1.4478)
			(drill 1.0414)
			(layers "*.Cu" "*.Mask")
			(remove_unused_layers no)
			(net "I2C_C_SDA_CONN_R")
			(clearance 0.1524)
			(thermal_gap 0.1524)
		)
		(pad "A2" thru_hole circle
			(at -2.54 0 270)
			(size 1.4478 1.4478)
			(drill 1.0414)
			(layers "*.Cu" "*.Mask")
			(remove_unused_layers no)
			(net "GND")
			(clearance 0.1524)
			(thermal_gap 0.1524)
		)
		(pad "A3" thru_hole circle
			(at 0 0 270)
			(size 1.4478 1.4478)
			(drill 1.0414)
			(layers "*.Cu" "*.Mask")
			(remove_unused_layers no)
			(net "I2C_C_SCL_CONN_R")
			(clearance 0.1524)
			(thermal_gap 0.1524)
		)
		(pad "A4" thru_hole circle
			(at 2.54 0 270)
			(size 1.4478 1.4478)
			(drill 1.0414)
			(layers "*.Cu" "*.Mask")
			(remove_unused_layers no)
			(net "GND")
			(clearance 0.1524)
			(thermal_gap 0.1524)
		)
		(pad "A5" thru_hole circle
			(at 5.08 0 270)
			(size 1.4478 1.4478)
			(drill 1.0414)
			(layers "*.Cu" "*.Mask")
			(remove_unused_layers no)
			(net "PWM_EXP_1B")
			(clearance 0.1524)
			(thermal_gap 0.1524)
		)
		(pad "B1" thru_hole circle
			(at -5.08 -2.54 270)
			(size 1.4478 1.4478)
			(drill 1.0414)
			(layers "*.Cu" "*.Mask")
			(remove_unused_layers no)
			(net "GND")
			(clearance 0.1524)
			(thermal_gap 0.1524)
		)
		(pad "B2" thru_hole circle
			(at -2.54 -2.54 270)
			(size 1.4478 1.4478)
			(drill 1.0414)
			(layers "*.Cu" "*.Mask")
			(remove_unused_layers no)
			(net "PWM_EXP_1A")
			(clearance 0.1524)
			(thermal_gap 0.1524)
		)
		(pad "B3" thru_hole circle
			(at 0 -2.54 270)
			(size 1.4478 1.4478)
			(drill 1.0414)
			(layers "*.Cu" "*.Mask")
			(remove_unused_layers no)
			(net "GND")
			(clearance 0.1524)
			(thermal_gap 0.1524)
		)
		(pad "B4" thru_hole circle
			(at 2.54 -2.54 270)
			(size 1.4478 1.4478)
			(drill 1.0414)
			(layers "*.Cu" "*.Mask")
			(remove_unused_layers no)
			(net "SELF_1B_HB")
			(clearance 0.1524)
			(thermal_gap 0.1524)
		)
		(pad "B5" thru_hole circle
			(at 5.08 -2.54 270)
			(size 1.4478 1.4478)
			(drill 1.0414)
			(layers "*.Cu" "*.Mask")
			(remove_unused_layers no)
			(net "GND")
			(clearance 0.1524)
			(thermal_gap 0.1524)
		)
		(pad "C1" thru_hole circle
			(at -5.08 -5.08 270)
			(size 1.4478 1.4478)
			(drill 1.0414)
			(layers "*.Cu" "*.Mask")
			(remove_unused_layers no)
			(net "P12VU_2490_EN_1")
			(clearance 0.1524)
			(thermal_gap 0.1524)
		)
		(pad "C2" thru_hole circle
			(at -2.54 -5.08 270)
			(size 1.4478 1.4478)
			(drill 1.0414)
			(layers "*.Cu" "*.Mask")
			(remove_unused_layers no)
			(net "P12VU_2490_EN_2")
			(clearance 0.1524)
			(thermal_gap 0.1524)
		)
		(pad "C3" thru_hole circle
			(at 0 -5.08 270)
			(size 1.4478 1.4478)
			(drill 1.0414)
			(layers "*.Cu" "*.Mask")
			(remove_unused_layers no)
			(net "SELF_1A_HB")
			(clearance 0.1524)
			(thermal_gap 0.1524)
		)
		(pad "C4" thru_hole circle
			(at 2.54 -5.08 270)
			(size 1.4478 1.4478)
			(drill 1.0414)
			(layers "*.Cu" "*.Mask")
			(remove_unused_layers no)
			(net "SEB_PEER_1A_HB")
			(clearance 0.1524)
			(thermal_gap 0.1524)
		)
		(pad "C5" thru_hole circle
			(at 5.08 -5.08 270)
			(size 1.4478 1.4478)
			(drill 1.0414)
			(layers "*.Cu" "*.Mask")
			(remove_unused_layers no)
			(net "SEB_PEER_1B_HB")
			(clearance 0.1524)
			(thermal_gap 0.1524)
		)
		(pad "D1" thru_hole circle
			(at -5.08 -7.62 270)
			(size 1.4478 1.4478)
			(drill 1.0414)
			(layers "*.Cu" "*.Mask")
			(remove_unused_layers no)
			(net "PEER_TRAY PRESENT_UPPER")
			(clearance 0.1524)
			(thermal_gap 0.1524)
		)
		(pad "D2" thru_hole circle
			(at -2.54 -7.62 270)
			(size 1.4478 1.4478)
			(drill 1.0414)
			(layers "*.Cu" "*.Mask")
			(remove_unused_layers no)
			(net "UPPER_TRAY_ID")
			(clearance 0.1524)
			(thermal_gap 0.1524)
		)
		(pad "D3" thru_hole circle
			(at 0 -7.62 270)
			(size 1.4478 1.4478)
			(drill 1.0414)
			(layers "*.Cu" "*.Mask")
			(remove_unused_layers no)
			(net "FCB_HW_REVISION")
			(clearance 0.1524)
			(thermal_gap 0.1524)
		)
		(pad "D4" thru_hole circle
			(at 2.54 -7.62 270)
			(size 1.4478 1.4478)
			(drill 1.0414)
			(layers "*.Cu" "*.Mask")
			(remove_unused_layers no)
			(net "SD_LATCH_RELEASE_U")
			(clearance 0.1524)
			(thermal_gap 0.1524)
		)
		(pad "D5" thru_hole circle
			(at 5.08 -7.62 270)
			(size 1.4478 1.4478)
			(drill 1.0414)
			(layers "*.Cu" "*.Mask")
			(remove_unused_layers no)
			(net "SELF_TRAY_PRESENT_UPPER")
			(clearance 0.1524)
			(thermal_gap 0.1524)
		)
		(pad "P1_1" thru_hole circle
			(at -15.88008 0 270)
			(size 1.4478 1.4478)
			(drill 1.0414)
			(layers "*.Cu" "*.Mask")
			(remove_unused_layers no)
			(net "P12VU")
			(clearance 0.1524)
			(thermal_gap 0.1524)
		)
		(pad "P1_2" thru_hole circle
			(at -15.88008 -2.54 270)
			(size 1.4478 1.4478)
			(drill 1.0414)
			(layers "*.Cu" "*.Mask")
			(remove_unused_layers no)
			(net "P12VU")
			(clearance 0.1524)
			(thermal_gap 0.1524)
		)
		(pad "P1_3" thru_hole circle
			(at -15.88008 -5.08 270)
			(size 1.4478 1.4478)
			(drill 1.0414)
			(layers "*.Cu" "*.Mask")
			(remove_unused_layers no)
			(net "P12VU")
			(clearance 0.1524)
			(thermal_gap 0.1524)
		)
		(pad "P1_4" thru_hole circle
			(at -15.88008 -7.62 270)
			(size 1.4478 1.4478)
			(drill 1.0414)
			(layers "*.Cu" "*.Mask")
			(remove_unused_layers no)
			(net "P12VU")
			(clearance 0.1524)
			(thermal_gap 0.1524)
		)
		(pad "P1_5" thru_hole circle
			(at -13.34008 0 270)
			(size 1.4478 1.4478)
			(drill 1.0414)
			(layers "*.Cu" "*.Mask")
			(remove_unused_layers no)
			(net "P12VU")
			(clearance 0.1524)
			(thermal_gap 0.1524)
		)
		(pad "P1_6" thru_hole circle
			(at -13.34008 -2.54 270)
			(size 1.4478 1.4478)
			(drill 1.0414)
			(layers "*.Cu" "*.Mask")
			(remove_unused_layers no)
			(net "P12VU")
			(clearance 0.1524)
			(thermal_gap 0.1524)
		)
		(pad "P1_7" thru_hole circle
			(at -13.34008 -5.08 270)
			(size 1.4478 1.4478)
			(drill 1.0414)
			(layers "*.Cu" "*.Mask")
			(remove_unused_layers no)
			(net "P12VU")
			(clearance 0.1524)
			(thermal_gap 0.1524)
		)
		(pad "P1_8" thru_hole circle
			(at -13.34008 -7.62 270)
			(size 1.4478 1.4478)
			(drill 1.0414)
			(layers "*.Cu" "*.Mask")
			(remove_unused_layers no)
			(net "P12VU")
			(clearance 0.1524)
			(thermal_gap 0.1524)
		)
		(pad "P2_1" thru_hole circle
			(at -10.80008 0 270)
			(size 1.4478 1.4478)
			(drill 1.0414)
			(layers "*.Cu" "*.Mask")
			(remove_unused_layers no)
			(net "P12VU")
			(clearance 0.1524)
			(thermal_gap 0.1524)
		)
		(pad "P2_2" thru_hole circle
			(at -10.80008 -2.54 270)
			(size 1.4478 1.4478)
			(drill 1.0414)
			(layers "*.Cu" "*.Mask")
			(remove_unused_layers no)
			(net "P12VU")
			(clearance 0.1524)
			(thermal_gap 0.1524)
		)
		(pad "P2_3" thru_hole circle
			(at -10.80008 -5.08 270)
			(size 1.4478 1.4478)
			(drill 1.0414)
			(layers "*.Cu" "*.Mask")
			(remove_unused_layers no)
			(net "P12VU")
			(clearance 0.1524)
			(thermal_gap 0.1524)
		)
		(pad "P2_4" thru_hole circle
			(at -10.80008 -7.62 270)
			(size 1.4478 1.4478)
			(drill 1.0414)
			(layers "*.Cu" "*.Mask")
			(remove_unused_layers no)
			(net "P12VU")
			(clearance 0.1524)
			(thermal_gap 0.1524)
		)
		(pad "P2_5" thru_hole circle
			(at -8.26008 0 270)
			(size 1.4478 1.4478)
			(drill 1.0414)
			(layers "*.Cu" "*.Mask")
			(remove_unused_layers no)
			(net "P12VU")
			(clearance 0.1524)
			(thermal_gap 0.1524)
		)
		(pad "P2_6" thru_hole circle
			(at -8.26008 -2.54 270)
			(size 1.4478 1.4478)
			(drill 1.0414)
			(layers "*.Cu" "*.Mask")
			(remove_unused_layers no)
			(net "P12VU")
			(clearance 0.1524)
			(thermal_gap 0.1524)
		)
		(pad "P2_7" thru_hole circle
			(at -8.26008 -5.08 270)
			(size 1.4478 1.4478)
			(drill 1.0414)
			(layers "*.Cu" "*.Mask")
			(remove_unused_layers no)
			(net "P12VU")
			(clearance 0.1524)
			(thermal_gap 0.1524)
		)
		(pad "P2_8" thru_hole circle
			(at -8.26008 -7.62 270)
			(size 1.4478 1.4478)
			(drill 1.0414)
			(layers "*.Cu" "*.Mask")
			(remove_unused_layers no)
			(net "P12VU")
			(clearance 0.1524)
			(thermal_gap 0.1524)
		)
		(pad "P3_1" thru_hole circle
			(at 8.26008 0 270)
			(size 1.4478 1.4478)
			(drill 1.0414)
			(layers "*.Cu" "*.Mask")
			(remove_unused_layers no)
			(net "GND")
			(clearance 0.1524)
			(thermal_gap 0.1524)
		)
		(pad "P3_2" thru_hole circle
			(at 8.26008 -2.54 270)
			(size 1.4478 1.4478)
			(drill 1.0414)
			(layers "*.Cu" "*.Mask")
			(remove_unused_layers no)
			(net "GND")
			(clearance 0.1524)
			(thermal_gap 0.1524)
		)
		(pad "P3_3" thru_hole circle
			(at 8.26008 -5.08 270)
			(size 1.4478 1.4478)
			(drill 1.0414)
			(layers "*.Cu" "*.Mask")
			(remove_unused_layers no)
			(net "GND")
			(clearance 0.1524)
			(thermal_gap 0.1524)
		)
		(pad "P3_4" thru_hole circle
			(at 8.26008 -7.62 270)
			(size 1.4478 1.4478)
			(drill 1.0414)
			(layers "*.Cu" "*.Mask")
			(remove_unused_layers no)
			(net "GND")
			(clearance 0.1524)
			(thermal_gap 0.1524)
		)
		(pad "P3_5" thru_hole circle
			(at 10.80008 0 270)
			(size 1.4478 1.4478)
			(drill 1.0414)
			(layers "*.Cu" "*.Mask")
			(remove_unused_layers no)
			(net "GND")
			(clearance 0.1524)
			(thermal_gap 0.1524)
		)
		(pad "P3_6" thru_hole circle
			(at 10.80008 -2.54 270)
			(size 1.4478 1.4478)
			(drill 1.0414)
			(layers "*.Cu" "*.Mask")
			(remove_unused_layers no)
			(net "GND")
			(clearance 0.1524)
			(thermal_gap 0.1524)
		)
		(pad "P3_7" thru_hole circle
			(at 10.80008 -5.08 270)
			(size 1.4478 1.4478)
			(drill 1.0414)
			(layers "*.Cu" "*.Mask")
			(remove_unused_layers no)
			(net "GND")
			(clearance 0.1524)
			(thermal_gap 0.1524)
		)
		(pad "P3_8" thru_hole circle
			(at 10.80008 -7.62 270)
			(size 1.4478 1.4478)
			(drill 1.0414)
			(layers "*.Cu" "*.Mask")
			(remove_unused_layers no)
			(net "GND")
			(clearance 0.1524)
			(thermal_gap 0.1524)
		)
		(pad "P4_1" thru_hole circle
			(at 13.34008 0 270)
			(size 1.4478 1.4478)
			(drill 1.0414)
			(layers "*.Cu" "*.Mask")
			(remove_unused_layers no)
			(net "GND")
			(clearance 0.1524)
			(thermal_gap 0.1524)
		)
		(pad "P4_2" thru_hole circle
			(at 13.34008 -2.54 270)
			(size 1.4478 1.4478)
			(drill 1.0414)
			(layers "*.Cu" "*.Mask")
			(remove_unused_layers no)
			(net "GND")
			(clearance 0.1524)
			(thermal_gap 0.1524)
		)
		(pad "P4_3" thru_hole circle
			(at 13.34008 -5.08 270)
			(size 1.4478 1.4478)
			(drill 1.0414)
			(layers "*.Cu" "*.Mask")
			(remove_unused_layers no)
			(net "GND")
			(clearance 0.1524)
			(thermal_gap 0.1524)
		)
		(pad "P4_4" thru_hole circle
			(at 13.34008 -7.62 270)
			(size 1.4478 1.4478)
			(drill 1.0414)
			(layers "*.Cu" "*.Mask")
			(remove_unused_layers no)
			(net "GND")
			(clearance 0.1524)
			(thermal_gap 0.1524)
		)
		(pad "P4_5" thru_hole circle
			(at 15.88008 0 270)
			(size 1.4478 1.4478)
			(drill 1.0414)
			(layers "*.Cu" "*.Mask")
			(remove_unused_layers no)
			(net "GND")
			(clearance 0.1524)
			(thermal_gap 0.1524)
		)
		(pad "P4_6" thru_hole circle
			(at 15.88008 -2.54 270)
			(size 1.4478 1.4478)
			(drill 1.0414)
			(layers "*.Cu" "*.Mask")
			(remove_unused_layers no)
			(net "GND")
			(clearance 0.1524)
			(thermal_gap 0.1524)
		)
		(pad "P4_7" thru_hole circle
			(at 15.88008 -5.08 270)
			(size 1.4478 1.4478)
			(drill 1.0414)
			(layers "*.Cu" "*.Mask")
			(remove_unused_layers no)
			(net "GND")
			(clearance 0.1524)
			(thermal_gap 0.1524)
		)
		(pad "P4_8" thru_hole circle
			(at 15.88008 -7.62 270)
			(size 1.4478 1.4478)
			(drill 1.0414)
			(layers "*.Cu" "*.Mask")
			(remove_unused_layers no)
			(net "GND")
			(clearance 0.1524)
			(thermal_gap 0.1524)
		)
		(zone
			(layers "F.Cu" "B.Cu" "In1.Cu" "In2.Cu")
			(hatch none 0.5)
			(connect_pads
				(clearance 0)
			)
			(min_thickness 0.25)
			(keepout
				(tracks not_allowed)
				(vias allowed)
				(pads allowed)
				(copperpour not_allowed)
				(footprints allowed)
			)
			(placement
				(enabled no)
				(sheetname "")
			)
			(fill
				(thermal_gap 0.5)
				(thermal_bridge_width 0.5)
				(island_removal_mode 0)
			)
			(polygon
				(pts
					(arc
						(start 22.062186 -78.589886)
						(mid 18.937986 -78.589886)
						(end 22.062186 -78.589886)
					)
				)
			)
		)
		(zone
			(layers "F.Cu" "B.Cu" "In1.Cu" "In2.Cu")
			(hatch none 0.5)
			(connect_pads
				(clearance 0)
			)
			(min_thickness 0.25)
			(keepout
				(tracks not_allowed)
				(vias allowed)
				(pads allowed)
				(copperpour not_allowed)
				(footprints allowed)
			)
			(placement
				(enabled no)
				(sheetname "")
			)
			(fill
				(thermal_gap 0.5)
				(thermal_bridge_width 0.5)
				(island_removal_mode 0)
			)
			(polygon
				(pts
					(arc
						(start 22.062186 -35.409886)
						(mid 18.937986 -35.409886)
						(end 22.062186 -35.409886)
					)
				)
			)
		)
		(zone
			(layers "F.Cu" "B.Cu" "In1.Cu" "In2.Cu")
			(hatch none 0.5)
			(connect_pads
				(clearance 0)
			)
			(min_thickness 0.25)
			(keepout
				(tracks not_allowed)
				(vias allowed)
				(pads allowed)
				(copperpour not_allowed)
				(footprints allowed)
			)
			(placement
				(enabled no)
				(sheetname "")
			)
			(fill
				(thermal_gap 0.5)
				(thermal_bridge_width 0.5)
				(island_removal_mode 0)
			)
			(polygon
				(pts
					(arc
						(start 22.405086 -83.669886)
						(mid 18.595086 -83.669886)
						(end 22.405086 -83.669886)
					)
				)
			)
		)
		(zone
			(layers "F.Cu" "B.Cu" "In1.Cu" "In2.Cu")
			(hatch none 0.5)
			(connect_pads
				(clearance 0)
			)
			(min_thickness 0.25)
			(keepout
				(tracks not_allowed)
				(vias allowed)
				(pads allowed)
				(copperpour not_allowed)
				(footprints allowed)
			)
			(placement
				(enabled no)
				(sheetname "")
			)
			(fill
				(thermal_gap 0.5)
				(thermal_bridge_width 0.5)
				(island_removal_mode 0)
			)
			(polygon
				(pts
					(arc
						(start 22.405086 -30.329886)
						(mid 18.595086 -30.329886)
						(end 22.405086 -30.329886)
					)
				)
			)
		)
	)
	(footprint ""
		(layer "F.Cu")
		(at 29.972 -361.315 180)
		(property "Reference" "PR15"
			(at 0 0 180)
			(layer "F.SilkS")
			(hide yes)
			(effects
				(font
					(size 1.27 1.27)
				)
			)
		)
		(property "Value" "4K7R2J-2-GP"
			(at 0.064008 -3.993896 180)
			(unlocked yes)
			(layer "F.Fab")
			(hide yes)
			(effects
				(font
					(size 1.016 1.016)
					(thickness 0.1524)
				)
			)
		)
		(property "Device Type" "R402H16"
			(at 0.064008 -5.517896 180)
			(unlocked yes)
			(layer "F.Fab")
			(hide yes)
			(effects
				(font
					(size 1.016 1.016)
					(thickness 0.1524)
				)
			)
		)
		(duplicate_pad_numbers_are_jumpers no)
		(fp_line
			(start 0.508 -0.9398)
			(end -0.508 -0.9398)
			(stroke
				(width 0.1524)
				(type default)
			)
			(layer "F.SilkS")
		)
		(fp_line
			(start -0.508 -0.9398)
			(end -0.508 0.9398)
			(stroke
				(width 0.1524)
				(type default)
			)
			(layer "F.SilkS")
		)
		(fp_rect
			(start -0.508 0.9398)
			(end 0.508 -0.9398)
			(stroke
				(width 0)
				(type default)
			)
			(fill no)
			(layer "F.CrtYd")
		)
		(fp_rect
			(start -0.508 0.9398)
			(end 0.508 -0.9398)
			(stroke
				(width 0)
				(type default)
			)
			(fill no)
			(layer "F.Fab")
		)
		(pad "1" smd custom
			(at 0 -0.4445 180)
			(size 0.1397 0.1397)
			(layers "F.Cu" "F.Mask" "F.Paste")
			(net "P3V3")
			(options
				(clearance outline)
				(anchor circle)
			)
			(primitives
				(gr_poly
					(pts
						(arc
							(start -0.1778 -0.2794)
							(mid -0.249642 -0.249642)
							(end -0.2794 -0.1778)
						)
						(arc
							(start -0.2794 0.1778)
							(mid -0.249642 0.249642)
							(end -0.1778 0.2794)
						)
						(arc
							(start 0.1778 0.2794)
							(mid 0.249642 0.249642)
							(end 0.2794 0.1778)
						)
						(arc
							(start 0.2794 -0.1778)
							(mid 0.249642 -0.249642)
							(end 0.1778 -0.2794)
						)
					)
					(width 0)
					(fill yes)
				)
			)
		)
		(pad "2" smd custom
			(at 0 0.4445 180)
			(size 0.1397 0.1397)
			(layers "F.Cu" "F.Mask" "F.Paste")
			(net "ADM1276_GPIO2")
			(options
				(clearance outline)
				(anchor circle)
			)
			(primitives
				(gr_poly
					(pts
						(arc
							(start -0.1778 -0.2794)
							(mid -0.249642 -0.249642)
							(end -0.2794 -0.1778)
						)
						(arc
							(start -0.2794 0.1778)
							(mid -0.249642 0.249642)
							(end -0.1778 0.2794)
						)
						(arc
							(start 0.1778 0.2794)
							(mid 0.249642 0.249642)
							(end 0.2794 0.1778)
						)
						(arc
							(start 0.2794 -0.1778)
							(mid 0.249642 -0.249642)
							(end 0.1778 -0.2794)
						)
					)
					(width 0)
					(fill yes)
				)
			)
		)
	)
	(footprint ""
		(layer "F.Cu")
		(at 26.289 -151.3078)
		(property "Reference" "C5"
			(at 0 0 0)
			(layer "F.SilkS")
			(hide yes)
			(effects
				(font
					(size 1.27 1.27)
				)
			)
		)
		(property "Value" "SCD1U16V2KX-3GP"
			(at 1.1811 -2.7051 0)
			(unlocked yes)
			(layer "F.Fab")
			(hide yes)
			(effects
				(font
					(size 1.016 1.016)
					(thickness 0.1524)
				)
			)
		)
		(property "Device Type" "C402H22"
			(at 1.1811 -4.2291 0)
			(unlocked yes)
			(layer "F.Fab")
			(hide yes)
			(effects
				(font
					(size 1.016 1.016)
					(thickness 0.1524)
				)
			)
		)
		(duplicate_pad_numbers_are_jumpers no)
		(fp_rect
			(start -0.4318 0.9525)
			(end 0.4318 -0.9525)
			(stroke
				(width 0)
				(type default)
			)
			(fill no)
			(layer "F.CrtYd")
		)
		(fp_rect
			(start -0.4318 0.9525)
			(end 0.4318 -0.9525)
			(stroke
				(width 0)
				(type default)
			)
			(fill no)
			(layer "F.Fab")
		)
		(pad "1" smd custom
			(at 0 -0.4445)
			(size 0.1524 0.1524)
			(layers "F.Cu" "F.Mask" "F.Paste")
			(net "NCT7904_VREF")
			(options
				(clearance outline)
				(anchor circle)
			)
			(primitives
				(gr_poly
					(pts
						(arc
							(start 0.3048 -0.2032)
							(mid 0.275042 -0.275042)
							(end 0.2032 -0.3048)
						)
						(arc
							(start -0.2032 -0.3048)
							(mid -0.275042 -0.275042)
							(end -0.3048 -0.2032)
						)
						(arc
							(start -0.3048 0.2032)
							(mid -0.275042 0.275042)
							(end -0.2032 0.3048)
						)
						(arc
							(start 0.2032 0.3048)
							(mid 0.275042 0.275042)
							(end 0.3048 0.2032)
						)
					)
					(width 0)
					(fill yes)
				)
			)
		)
		(pad "2" smd custom
			(at 0 0.4445)
			(size 0.1524 0.1524)
			(layers "F.Cu" "F.Mask" "F.Paste")
			(net "GND")
			(options
				(clearance outline)
				(anchor circle)
			)
			(primitives
				(gr_poly
					(pts
						(arc
							(start 0.3048 -0.2032)
							(mid 0.275042 -0.275042)
							(end 0.2032 -0.3048)
						)
						(arc
							(start -0.2032 -0.3048)
							(mid -0.275042 -0.275042)
							(end -0.3048 -0.2032)
						)
						(arc
							(start -0.3048 0.2032)
							(mid -0.275042 0.275042)
							(end -0.2032 0.3048)
						)
						(arc
							(start 0.2032 0.3048)
							(mid 0.275042 0.275042)
							(end 0.3048 0.2032)
						)
					)
					(width 0)
					(fill yes)
				)
			)
		)
	)
	(footprint ""
		(layer "F.Cu")
		(at 38.6334 -254.381)
		(property "Reference" "R58"
			(at 0 0 0)
			(layer "F.SilkS")
			(hide yes)
			(effects
				(font
					(size 1.27 1.27)
				)
			)
		)
		(property "Value" "330R2J-3-GP"
			(at 0.064008 -3.993896 0)
			(unlocked yes)
			(layer "F.Fab")
			(hide yes)
			(effects
				(font
					(size 1.016 1.016)
					(thickness 0.1524)
				)
			)
		)
		(property "Device Type" "R402H16"
			(at 0.064008 -5.517896 0)
			(unlocked yes)
			(layer "F.Fab")
			(hide yes)
			(effects
				(font
					(size 1.016 1.016)
					(thickness 0.1524)
				)
			)
		)
		(duplicate_pad_numbers_are_jumpers no)
		(fp_line
			(start -0.508 -0.9398)
			(end -0.508 0.9398)
			(stroke
				(width 0.1524)
				(type default)
			)
			(layer "F.SilkS")
		)
		(fp_line
			(start 0.508 -0.9398)
			(end -0.508 -0.9398)
			(stroke
				(width 0.1524)
				(type default)
			)
			(layer "F.SilkS")
		)
		(fp_rect
			(start -0.508 0.9398)
			(end 0.508 -0.9398)
			(stroke
				(width 0)
				(type default)
			)
			(fill no)
			(layer "F.CrtYd")
		)
		(fp_rect
			(start -0.508 0.9398)
			(end 0.508 -0.9398)
			(stroke
				(width 0)
				(type default)
			)
			(fill no)
			(layer "F.Fab")
		)
		(pad "1" smd custom
			(at 0 -0.4445)
			(size 0.1397 0.1397)
			(layers "F.Cu" "F.Mask" "F.Paste")
			(net "P3V3")
			(options
				(clearance outline)
				(anchor circle)
			)
			(primitives
				(gr_poly
					(pts
						(arc
							(start -0.1778 -0.2794)
							(mid -0.249642 -0.249642)
							(end -0.2794 -0.1778)
						)
						(arc
							(start -0.2794 0.1778)
							(mid -0.249642 0.249642)
							(end -0.1778 0.2794)
						)
						(arc
							(start 0.1778 0.2794)
							(mid 0.249642 0.249642)
							(end 0.2794 0.1778)
						)
						(arc
							(start 0.2794 -0.1778)
							(mid 0.249642 -0.249642)
							(end 0.1778 -0.2794)
						)
					)
					(width 0)
					(fill yes)
				)
			)
		)
		(pad "2" smd custom
			(at 0 0.4445)
			(size 0.1397 0.1397)
			(layers "F.Cu" "F.Mask" "F.Paste")
			(net "LED_DR_LED6_RESERVE")
			(options
				(clearance outline)
				(anchor circle)
			)
			(primitives
				(gr_poly
					(pts
						(arc
							(start -0.1778 -0.2794)
							(mid -0.249642 -0.249642)
							(end -0.2794 -0.1778)
						)
						(arc
							(start -0.2794 0.1778)
							(mid -0.249642 0.249642)
							(end -0.1778 0.2794)
						)
						(arc
							(start 0.1778 0.2794)
							(mid 0.249642 0.249642)
							(end 0.2794 0.1778)
						)
						(arc
							(start 0.2794 -0.1778)
							(mid 0.249642 -0.249642)
							(end 0.1778 -0.2794)
						)
					)
					(width 0)
					(fill yes)
				)
			)
		)
	)
	(footprint ""
		(layer "F.Cu")
		(at 20.828 -179.1716 180)
		(property "Reference" "R87"
			(at 0 0 180)
			(layer "F.SilkS")
			(hide yes)
			(effects
				(font
					(size 1.27 1.27)
				)
			)
		)
		(property "Value" "27KR3F-GP"
			(at -0.0254 -2.5146 180)
			(unlocked yes)
			(layer "F.Fab")
			(hide yes)
			(effects
				(font
					(size 1.016 1.016)
					(thickness 0.1524)
				)
			)
		)
		(property "Device Type" "R603H22"
			(at -0.0254 -4.0386 180)
			(unlocked yes)
			(layer "F.Fab")
			(hide yes)
			(effects
				(font
					(size 1.016 1.016)
					(thickness 0.1524)
				)
			)
		)
		(duplicate_pad_numbers_are_jumpers no)
		(fp_line
			(start 0.2032 0)
			(end 0.4826 0)
			(stroke
				(width 0.2032)
				(type default)
			)
			(layer "F.SilkS")
		)
		(fp_line
			(start -0.4826 0)
			(end -0.2032 0)
			(stroke
				(width 0.2032)
				(type default)
			)
			(layer "F.SilkS")
		)
		(fp_rect
			(start -0.5842 1.3335)
			(end 0.5842 -1.3335)
			(stroke
				(width 0)
				(type default)
			)
			(fill no)
			(layer "F.CrtYd")
		)
		(fp_rect
			(start -0.5842 1.3335)
			(end 0.5842 -1.3335)
			(stroke
				(width 0)
				(type default)
			)
			(fill no)
			(layer "F.Fab")
		)
		(pad "1" smd custom
			(at 0 -0.762 180)
			(size 0.2159 0.2159)
			(layers "F.Cu" "F.Mask" "F.Paste")
			(net "FANIN_7")
			(options
				(clearance outline)
				(anchor circle)
			)
			(primitives
				(gr_poly
					(pts
						(arc
							(start -0.3302 -0.4318)
							(mid -0.402042 -0.402042)
							(end -0.4318 -0.3302)
						)
						(arc
							(start -0.4318 0.3302)
							(mid -0.402042 0.402042)
							(end -0.3302 0.4318)
						)
						(arc
							(start 0.3302 0.4318)
							(mid 0.402042 0.402042)
							(end 0.4318 0.3302)
						)
						(arc
							(start 0.4318 -0.3302)
							(mid 0.402042 -0.402042)
							(end 0.3302 -0.4318)
						)
					)
					(width 0)
					(fill yes)
				)
			)
		)
		(pad "2" smd custom
			(at 0 0.762 180)
			(size 0.2159 0.2159)
			(layers "F.Cu" "F.Mask" "F.Paste")
			(net "FAN_TACH7")
			(options
				(clearance outline)
				(anchor circle)
			)
			(primitives
				(gr_poly
					(pts
						(arc
							(start -0.3302 -0.4318)
							(mid -0.402042 -0.402042)
							(end -0.4318 -0.3302)
						)
						(arc
							(start -0.4318 0.3302)
							(mid -0.402042 0.402042)
							(end -0.3302 0.4318)
						)
						(arc
							(start 0.3302 0.4318)
							(mid 0.402042 0.402042)
							(end 0.4318 0.3302)
						)
						(arc
							(start 0.4318 -0.3302)
							(mid 0.402042 -0.402042)
							(end 0.3302 -0.4318)
						)
					)
					(width 0)
					(fill yes)
				)
			)
		)
	)
	(footprint ""
		(layer "F.Cu")
		(at 26.0604 -224.3074)
		(property "Reference" "R141"
			(at 0 0 0)
			(layer "F.SilkS")
			(hide yes)
			(effects
				(font
					(size 1.27 1.27)
				)
			)
		)
		(property "Value" "0R2J-2-GP"
			(at 0.064008 -3.993896 0)
			(unlocked yes)
			(layer "F.Fab")
			(hide yes)
			(effects
				(font
					(size 1.016 1.016)
					(thickness 0.1524)
				)
			)
		)
		(property "Device Type" "R402H16"
			(at 0.064008 -5.517896 0)
			(unlocked yes)
			(layer "F.Fab")
			(hide yes)
			(effects
				(font
					(size 1.016 1.016)
					(thickness 0.1524)
				)
			)
		)
		(duplicate_pad_numbers_are_jumpers no)
		(fp_line
			(start -0.508 -0.9398)
			(end -0.508 0.9398)
			(stroke
				(width 0.1524)
				(type default)
			)
			(layer "F.SilkS")
		)
		(fp_line
			(start 0.508 -0.9398)
			(end -0.508 -0.9398)
			(stroke
				(width 0.1524)
				(type default)
			)
			(layer "F.SilkS")
		)
		(fp_rect
			(start -0.508 0.9398)
			(end 0.508 -0.9398)
			(stroke
				(width 0)
				(type default)
			)
			(fill no)
			(layer "F.CrtYd")
		)
		(fp_rect
			(start -0.508 0.9398)
			(end 0.508 -0.9398)
			(stroke
				(width 0)
				(type default)
			)
			(fill no)
			(layer "F.Fab")
		)
		(pad "1" smd custom
			(at 0 -0.4445)
			(size 0.1397 0.1397)
			(layers "F.Cu" "F.Mask" "F.Paste")
			(net "PWM_OUT_FAN1_NET")
			(options
				(clearance outline)
				(anchor circle)
			)
			(primitives
				(gr_poly
					(pts
						(arc
							(start -0.1778 -0.2794)
							(mid -0.249642 -0.249642)
							(end -0.2794 -0.1778)
						)
						(arc
							(start -0.2794 0.1778)
							(mid -0.249642 0.249642)
							(end -0.1778 0.2794)
						)
						(arc
							(start 0.1778 0.2794)
							(mid 0.249642 0.249642)
							(end 0.2794 0.1778)
						)
						(arc
							(start 0.2794 -0.1778)
							(mid 0.249642 -0.249642)
							(end 0.1778 -0.2794)
						)
					)
					(width 0)
					(fill yes)
				)
			)
		)
		(pad "2" smd custom
			(at 0 0.4445)
			(size 0.1397 0.1397)
			(layers "F.Cu" "F.Mask" "F.Paste")
			(net "PWM_OUT_FAN1")
			(options
				(clearance outline)
				(anchor circle)
			)
			(primitives
				(gr_poly
					(pts
						(arc
							(start -0.1778 -0.2794)
							(mid -0.249642 -0.249642)
							(end -0.2794 -0.1778)
						)
						(arc
							(start -0.2794 0.1778)
							(mid -0.249642 0.249642)
							(end -0.1778 0.2794)
						)
						(arc
							(start 0.1778 0.2794)
							(mid 0.249642 0.249642)
							(end 0.2794 0.1778)
						)
						(arc
							(start 0.2794 -0.1778)
							(mid 0.249642 -0.249642)
							(end 0.1778 -0.2794)
						)
					)
					(width 0)
					(fill yes)
				)
			)
		)
	)
	(footprint ""
		(layer "F.Cu")
		(at 14.8844 -71.12 -90)
		(property "Reference" "R167"
			(at 0 0 270)
			(layer "F.SilkS")
			(hide yes)
			(effects
				(font
					(size 1.27 1.27)
				)
			)
		)
		(property "Value" "4K7R2F-GP"
			(at 0.064008 -3.993896 270)
			(unlocked yes)
			(layer "F.Fab")
			(hide yes)
			(effects
				(font
					(size 1.016 1.016)
					(thickness 0.1524)
				)
			)
		)
		(property "Device Type" "R402H16"
			(at 0.064008 -5.517896 270)
			(unlocked yes)
			(layer "F.Fab")
			(hide yes)
			(effects
				(font
					(size 1.016 1.016)
					(thickness 0.1524)
				)
			)
		)
		(duplicate_pad_numbers_are_jumpers no)
		(fp_line
			(start -0.508 -0.9398)
			(end -0.508 0.9398)
			(stroke
				(width 0.1524)
				(type default)
			)
			(layer "F.SilkS")
		)
		(fp_line
			(start 0.508 -0.9398)
			(end -0.508 -0.9398)
			(stroke
				(width 0.1524)
				(type default)
			)
			(layer "F.SilkS")
		)
		(fp_rect
			(start -0.508 0.9398)
			(end 0.508 -0.9398)
			(stroke
				(width 0)
				(type default)
			)
			(fill no)
			(layer "F.CrtYd")
		)
		(fp_rect
			(start -0.508 0.9398)
			(end 0.508 -0.9398)
			(stroke
				(width 0)
				(type default)
			)
			(fill no)
			(layer "F.Fab")
		)
		(pad "1" smd custom
			(at 0 -0.4445 270)
			(size 0.1397 0.1397)
			(layers "F.Cu" "F.Mask" "F.Paste")
			(net "P3V3")
			(options
				(clearance outline)
				(anchor circle)
			)
			(primitives
				(gr_poly
					(pts
						(arc
							(start -0.1778 -0.2794)
							(mid -0.249642 -0.249642)
							(end -0.2794 -0.1778)
						)
						(arc
							(start -0.2794 0.1778)
							(mid -0.249642 0.249642)
							(end -0.1778 0.2794)
						)
						(arc
							(start 0.1778 0.2794)
							(mid 0.249642 0.249642)
							(end 0.2794 0.1778)
						)
						(arc
							(start 0.2794 -0.1778)
							(mid 0.249642 -0.249642)
							(end 0.1778 -0.2794)
						)
					)
					(width 0)
					(fill yes)
				)
			)
		)
		(pad "2" smd custom
			(at 0 0.4445 270)
			(size 0.1397 0.1397)
			(layers "F.Cu" "F.Mask" "F.Paste")
			(net "PWM_BUFFER_IN_FAN1_FAN2")
			(options
				(clearance outline)
				(anchor circle)
			)
			(primitives
				(gr_poly
					(pts
						(arc
							(start -0.1778 -0.2794)
							(mid -0.249642 -0.249642)
							(end -0.2794 -0.1778)
						)
						(arc
							(start -0.2794 0.1778)
							(mid -0.249642 0.249642)
							(end -0.1778 0.2794)
						)
						(arc
							(start 0.1778 0.2794)
							(mid 0.249642 0.249642)
							(end 0.2794 0.1778)
						)
						(arc
							(start 0.2794 -0.1778)
							(mid 0.249642 -0.249642)
							(end 0.1778 -0.2794)
						)
					)
					(width 0)
					(fill yes)
				)
			)
		)
	)
	(footprint ""
		(layer "F.Cu")
		(at 31.877 -22.479 90)
		(property "Reference" "TC13"
			(at 0 0 90)
			(layer "F.SilkS")
			(hide yes)
			(effects
				(font
					(size 1.27 1.27)
				)
			)
		)
		(property "Value" "ST15U25VDM-1-GP"
			(at 0 -9.6012 90)
			(unlocked yes)
			(layer "F.Fab")
			(hide yes)
			(effects
				(font
					(size 1.016 1.016)
					(thickness 0.1524)
				)
			)
		)
		(property "Device Type" "CT7343H79"
			(at 0 -11.1252 90)
			(unlocked yes)
			(layer "F.Fab")
			(hide yes)
			(effects
				(font
					(size 1.016 1.016)
					(thickness 0.1524)
				)
			)
		)
		(duplicate_pad_numbers_are_jumpers no)
		(fp_line
			(start 2.286 -4.8768)
			(end -2.286 -4.8768)
			(stroke
				(width 0.1524)
				(type default)
			)
			(layer "F.SilkS")
		)
		(fp_line
			(start -2.286 -4.8768)
			(end -2.286 -2.032)
			(stroke
				(width 0.1524)
				(type default)
			)
			(layer "F.SilkS")
		)
		(fp_line
			(start 2.1082 -4.699)
			(end -2.1082 -4.699)
			(stroke
				(width 0.508)
				(type default)
			)
			(layer "F.SilkS")
		)
		(fp_line
			(start 2.286 -2.032)
			(end 2.286 -4.8768)
			(stroke
				(width 0.1524)
				(type default)
			)
			(layer "F.SilkS")
		)
		(fp_line
			(start 2.286 2.032)
			(end 2.286 4.8768)
			(stroke
				(width 0.1524)
				(type default)
			)
			(layer "F.SilkS")
		)
		(fp_line
			(start 2.286 4.8768)
			(end -2.286 4.8768)
			(stroke
				(width 0.1524)
				(type default)
			)
			(layer "F.SilkS")
		)
		(fp_line
			(start -2.286 4.8768)
			(end -2.286 2.032)
			(stroke
				(width 0.1524)
				(type default)
			)
			(layer "F.SilkS")
		)
		(fp_rect
			(start -2.1463 3.6449)
			(end 2.1463 -3.6449)
			(stroke
				(width 0)
				(type default)
			)
			(fill no)
			(layer "F.CrtYd")
		)
		(fp_poly
			(pts
				(xy -2.54 4.953) (xy -2.54 4.2926) (xy -3.81 4.2926) (xy -3.81 -4.2926) (xy -2.54 -4.2926) (xy -2.54 -4.953)
				(xy 2.54 -4.953) (xy 2.54 -4.2926) (xy 3.81 -4.2926) (xy 3.81 -1.6256) (xy 2.1463 -1.6256) (xy 2.1463 -3.6449)
				(xy -2.1463 -3.6449) (xy -2.1463 3.6449) (xy 2.1463 3.6449) (xy 2.1463 -1.6129) (xy 3.81 -1.6129)
				(xy 3.81 4.2926) (xy 2.54 4.2926) (xy 2.54 4.953)
			)
			(stroke
				(width 0)
				(type default)
			)
			(fill no)
			(layer "F.CrtYd")
		)
		(fp_rect
			(start 2.54 4.2926)
			(end 3.81 -4.2926)
			(stroke
				(width 0)
				(type default)
			)
			(fill no)
			(layer "F.Fab")
		)
		(fp_rect
			(start -3.81 4.2926)
			(end -2.54 -4.2926)
			(stroke
				(width 0)
				(type default)
			)
			(fill no)
			(layer "F.Fab")
		)
		(fp_rect
			(start -2.54 4.953)
			(end 2.54 -4.953)
			(stroke
				(width 0)
				(type default)
			)
			(fill no)
			(layer "F.Fab")
		)
		(pad "1" smd rect
			(at 0 -3.1496 90)
			(size 2.413 2.286)
			(layers "F.Cu" "F.Mask" "F.Paste")
			(net "P12V")
		)
		(pad "2" smd rect
			(at 0 3.1496 90)
			(size 2.413 2.286)
			(layers "F.Cu" "F.Mask" "F.Paste")
			(net "GND")
		)
		(zone
			(layer "F.Cu")
			(hatch none 0.5)
			(connect_pads
				(clearance 0)
			)
			(min_thickness 0.25)
			(keepout
				(tracks allowed)
				(vias not_allowed)
				(pads allowed)
				(copperpour not_allowed)
				(footprints allowed)
			)
			(placement
				(enabled no)
				(sheetname "")
			)
			(fill
				(thermal_gap 0.5)
				(thermal_bridge_width 0.5)
				(island_removal_mode 0)
			)
			(polygon
				(pts
					(xy 30.1879 -23.9903) (xy 27.2796 -23.9903) (xy 27.2796 -20.9677) (xy 30.1752 -20.9677) (xy 30.5054 -20.9677)
					(xy 30.5054 -23.9903)
				)
			)
		)
		(zone
			(layer "F.Cu")
			(hatch none 0.5)
			(connect_pads
				(clearance 0)
			)
			(min_thickness 0.25)
			(keepout
				(tracks allowed)
				(vias not_allowed)
				(pads allowed)
				(copperpour not_allowed)
				(footprints allowed)
			)
			(placement
				(enabled no)
				(sheetname "")
			)
			(fill
				(thermal_gap 0.5)
				(thermal_bridge_width 0.5)
				(island_removal_mode 0)
			)
			(polygon
				(pts
					(xy 36.4744 -20.9677) (xy 36.4744 -23.9903) (xy 33.5788 -23.9903) (xy 33.2486 -23.9903) (xy 33.2486 -20.9677)
					(xy 33.5788 -20.9677)
				)
			)
		)
	)
	(footprint ""
		(layer "F.Cu")
		(at 8.2296 -450.6976 -90)
		(property "Reference" "R95"
			(at 0 0 270)
			(layer "F.SilkS")
			(hide yes)
			(effects
				(font
					(size 1.27 1.27)
				)
			)
		)
		(property "Value" "4K7R2F-GP"
			(at 0.064008 -3.993896 270)
			(unlocked yes)
			(layer "F.Fab")
			(hide yes)
			(effects
				(font
					(size 1.016 1.016)
					(thickness 0.1524)
				)
			)
		)
		(property "Device Type" "R402H16"
			(at 0.064008 -5.517896 270)
			(unlocked yes)
			(layer "F.Fab")
			(hide yes)
			(effects
				(font
					(size 1.016 1.016)
					(thickness 0.1524)
				)
			)
		)
		(duplicate_pad_numbers_are_jumpers no)
		(fp_line
			(start -0.508 -0.9398)
			(end -0.508 0.9398)
			(stroke
				(width 0.1524)
				(type default)
			)
			(layer "F.SilkS")
		)
		(fp_line
			(start 0.508 -0.9398)
			(end -0.508 -0.9398)
			(stroke
				(width 0.1524)
				(type default)
			)
			(layer "F.SilkS")
		)
		(fp_rect
			(start -0.508 0.9398)
			(end 0.508 -0.9398)
			(stroke
				(width 0)
				(type default)
			)
			(fill no)
			(layer "F.CrtYd")
		)
		(fp_rect
			(start -0.508 0.9398)
			(end 0.508 -0.9398)
			(stroke
				(width 0)
				(type default)
			)
			(fill no)
			(layer "F.Fab")
		)
		(pad "1" smd custom
			(at 0 -0.4445 270)
			(size 0.1397 0.1397)
			(layers "F.Cu" "F.Mask" "F.Paste")
			(net "P12V")
			(options
				(clearance outline)
				(anchor circle)
			)
			(primitives
				(gr_poly
					(pts
						(arc
							(start -0.1778 -0.2794)
							(mid -0.249642 -0.249642)
							(end -0.2794 -0.1778)
						)
						(arc
							(start -0.2794 0.1778)
							(mid -0.249642 0.249642)
							(end -0.1778 0.2794)
						)
						(arc
							(start 0.1778 0.2794)
							(mid 0.249642 0.249642)
							(end 0.2794 0.1778)
						)
						(arc
							(start 0.2794 -0.1778)
							(mid 0.249642 -0.249642)
							(end 0.1778 -0.2794)
						)
					)
					(width 0)
					(fill yes)
				)
			)
		)
		(pad "2" smd custom
			(at 0 0.4445 270)
			(size 0.1397 0.1397)
			(layers "F.Cu" "F.Mask" "F.Paste")
			(net "FAN_TACH1")
			(options
				(clearance outline)
				(anchor circle)
			)
			(primitives
				(gr_poly
					(pts
						(arc
							(start -0.1778 -0.2794)
							(mid -0.249642 -0.249642)
							(end -0.2794 -0.1778)
						)
						(arc
							(start -0.2794 0.1778)
							(mid -0.249642 0.249642)
							(end -0.1778 0.2794)
						)
						(arc
							(start 0.1778 0.2794)
							(mid 0.249642 0.249642)
							(end 0.2794 0.1778)
						)
						(arc
							(start 0.2794 -0.1778)
							(mid 0.249642 -0.249642)
							(end 0.1778 -0.2794)
						)
					)
					(width 0)
					(fill yes)
				)
			)
		)
	)
	(footprint ""
		(layer "F.Cu")
		(at 43.815 -389.001 90)
		(property "Reference" "TC9"
			(at 0 0 90)
			(layer "F.SilkS")
			(hide yes)
			(effects
				(font
					(size 1.27 1.27)
				)
			)
		)
		(property "Value" "ST68U16VDM-1-GP"
			(at 0 -9.6012 90)
			(unlocked yes)
			(layer "F.Fab")
			(hide yes)
			(effects
				(font
					(size 1.016 1.016)
					(thickness 0.1524)
				)
			)
		)
		(property "Device Type" "CT7343H79"
			(at 0 -11.1252 90)
			(unlocked yes)
			(layer "F.Fab")
			(hide yes)
			(effects
				(font
					(size 1.016 1.016)
					(thickness 0.1524)
				)
			)
		)
		(duplicate_pad_numbers_are_jumpers no)
		(fp_line
			(start 2.286 -4.8768)
			(end -2.286 -4.8768)
			(stroke
				(width 0.1524)
				(type default)
			)
			(layer "F.SilkS")
		)
		(fp_line
			(start -2.286 -4.8768)
			(end -2.286 -2.032)
			(stroke
				(width 0.1524)
				(type default)
			)
			(layer "F.SilkS")
		)
		(fp_line
			(start 2.1082 -4.699)
			(end -2.1082 -4.699)
			(stroke
				(width 0.508)
				(type default)
			)
			(layer "F.SilkS")
		)
		(fp_line
			(start 2.286 -2.032)
			(end 2.286 -4.8768)
			(stroke
				(width 0.1524)
				(type default)
			)
			(layer "F.SilkS")
		)
		(fp_line
			(start 2.286 2.032)
			(end 2.286 4.8768)
			(stroke
				(width 0.1524)
				(type default)
			)
			(layer "F.SilkS")
		)
		(fp_line
			(start 2.286 4.8768)
			(end -2.286 4.8768)
			(stroke
				(width 0.1524)
				(type default)
			)
			(layer "F.SilkS")
		)
		(fp_line
			(start -2.286 4.8768)
			(end -2.286 2.032)
			(stroke
				(width 0.1524)
				(type default)
			)
			(layer "F.SilkS")
		)
		(fp_rect
			(start -2.1463 3.6449)
			(end 2.1463 -3.6449)
			(stroke
				(width 0)
				(type default)
			)
			(fill no)
			(layer "F.CrtYd")
		)
		(fp_poly
			(pts
				(xy -2.54 4.953) (xy -2.54 4.2926) (xy -3.81 4.2926) (xy -3.81 -4.2926) (xy -2.54 -4.2926) (xy -2.54 -4.953)
				(xy 2.54 -4.953) (xy 2.54 -4.2926) (xy 3.81 -4.2926) (xy 3.81 -1.6256) (xy 2.1463 -1.6256) (xy 2.1463 -3.6449)
				(xy -2.1463 -3.6449) (xy -2.1463 3.6449) (xy 2.1463 3.6449) (xy 2.1463 -1.6129) (xy 3.81 -1.6129)
				(xy 3.81 4.2926) (xy 2.54 4.2926) (xy 2.54 4.953)
			)
			(stroke
				(width 0)
				(type default)
			)
			(fill no)
			(layer "F.CrtYd")
		)
		(fp_rect
			(start 2.54 4.2926)
			(end 3.81 -4.2926)
			(stroke
				(width 0)
				(type default)
			)
			(fill no)
			(layer "F.Fab")
		)
		(fp_rect
			(start -3.81 4.2926)
			(end -2.54 -4.2926)
			(stroke
				(width 0)
				(type default)
			)
			(fill no)
			(layer "F.Fab")
		)
		(fp_rect
			(start -2.54 4.953)
			(end 2.54 -4.953)
			(stroke
				(width 0)
				(type default)
			)
			(fill no)
			(layer "F.Fab")
		)
		(pad "1" smd rect
			(at 0 -3.1496 90)
			(size 2.413 2.286)
			(layers "F.Cu" "F.Mask" "F.Paste")
			(net "P12V")
		)
		(pad "2" smd rect
			(at 0 3.1496 90)
			(size 2.413 2.286)
			(layers "F.Cu" "F.Mask" "F.Paste")
			(net "GND")
		)
		(zone
			(layer "F.Cu")
			(hatch none 0.5)
			(connect_pads
				(clearance 0)
			)
			(min_thickness 0.25)
			(keepout
				(tracks allowed)
				(vias not_allowed)
				(pads allowed)
				(copperpour not_allowed)
				(footprints allowed)
			)
			(placement
				(enabled no)
				(sheetname "")
			)
			(fill
				(thermal_gap 0.5)
				(thermal_bridge_width 0.5)
				(island_removal_mode 0)
			)
			(polygon
				(pts
					(xy 42.1259 -390.5123) (xy 39.2176 -390.5123) (xy 39.2176 -387.4897) (xy 42.1132 -387.4897) (xy 42.4434 -387.4897)
					(xy 42.4434 -390.5123)
				)
			)
		)
		(zone
			(layer "F.Cu")
			(hatch none 0.5)
			(connect_pads
				(clearance 0)
			)
			(min_thickness 0.25)
			(keepout
				(tracks allowed)
				(vias not_allowed)
				(pads allowed)
				(copperpour not_allowed)
				(footprints allowed)
			)
			(placement
				(enabled no)
				(sheetname "")
			)
			(fill
				(thermal_gap 0.5)
				(thermal_bridge_width 0.5)
				(island_removal_mode 0)
			)
			(polygon
				(pts
					(xy 48.4124 -387.4897) (xy 48.4124 -390.5123) (xy 45.5168 -390.5123) (xy 45.1866 -390.5123) (xy 45.1866 -387.4897)
					(xy 45.5168 -387.4897)
				)
			)
		)
	)
	(footprint ""
		(layer "F.Cu")
		(at 22.225 -222.416116 180)
		(property "Reference" "C16"
			(at 0 0 180)
			(layer "F.SilkS")
			(hide yes)
			(effects
				(font
					(size 1.27 1.27)
				)
			)
		)
		(property "Value" "SCD1U50V3KX-GP"
			(at 0 -2.8194 180)
			(unlocked yes)
			(layer "F.Fab")
			(hide yes)
			(effects
				(font
					(size 1.016 1.016)
					(thickness 0.1524)
				)
			)
		)
		(property "Device Type" "C603H36"
			(at 0 -4.3434 180)
			(unlocked yes)
			(layer "F.Fab")
			(hide yes)
			(effects
				(font
					(size 1.016 1.016)
					(thickness 0.1524)
				)
			)
		)
		(duplicate_pad_numbers_are_jumpers no)
		(fp_line
			(start 0.508 0)
			(end -0.508 0)
			(stroke
				(width 0.2032)
				(type default)
			)
			(layer "F.SilkS")
		)
		(fp_rect
			(start -0.5842 1.3335)
			(end 0.5842 -1.3335)
			(stroke
				(width 0)
				(type default)
			)
			(fill no)
			(layer "F.CrtYd")
		)
		(fp_rect
			(start -0.5842 1.3335)
			(end 0.5842 -1.3335)
			(stroke
				(width 0)
				(type default)
			)
			(fill no)
			(layer "F.Fab")
		)
		(pad "1" smd custom
			(at 0 -0.762 180)
			(size 0.2159 0.2159)
			(layers "F.Cu" "F.Mask" "F.Paste")
			(net "P3V3")
			(options
				(clearance outline)
				(anchor circle)
			)
			(primitives
				(gr_poly
					(pts
						(arc
							(start -0.3302 -0.4318)
							(mid -0.402042 -0.402042)
							(end -0.4318 -0.3302)
						)
						(arc
							(start -0.4318 0.3302)
							(mid -0.402042 0.402042)
							(end -0.3302 0.4318)
						)
						(arc
							(start 0.3302 0.4318)
							(mid 0.402042 0.402042)
							(end 0.4318 0.3302)
						)
						(arc
							(start 0.4318 -0.3302)
							(mid 0.402042 -0.402042)
							(end 0.3302 -0.4318)
						)
					)
					(width 0)
					(fill yes)
				)
			)
		)
		(pad "2" smd custom
			(at 0 0.762 180)
			(size 0.2159 0.2159)
			(layers "F.Cu" "F.Mask" "F.Paste")
			(net "GND")
			(options
				(clearance outline)
				(anchor circle)
			)
			(primitives
				(gr_poly
					(pts
						(arc
							(start -0.3302 -0.4318)
							(mid -0.402042 -0.402042)
							(end -0.4318 -0.3302)
						)
						(arc
							(start -0.4318 0.3302)
							(mid -0.402042 0.402042)
							(end -0.3302 0.4318)
						)
						(arc
							(start 0.3302 0.4318)
							(mid 0.402042 0.402042)
							(end 0.4318 0.3302)
						)
						(arc
							(start 0.4318 -0.3302)
							(mid 0.402042 -0.402042)
							(end 0.3302 -0.4318)
						)
					)
					(width 0)
					(fill yes)
				)
			)
		)
	)
	(footprint ""
		(layer "F.Cu")
		(at 41.7576 -158.1658 90)
		(property "Reference" "R50"
			(at 0 0 90)
			(layer "F.SilkS")
			(hide yes)
			(effects
				(font
					(size 1.27 1.27)
				)
			)
		)
		(property "Value" "0R2J-2-GP"
			(at 0.064008 -3.993896 90)
			(unlocked yes)
			(layer "F.Fab")
			(hide yes)
			(effects
				(font
					(size 1.016 1.016)
					(thickness 0.1524)
				)
			)
		)
		(property "Device Type" "R402H16"
			(at 0.064008 -5.517896 90)
			(unlocked yes)
			(layer "F.Fab")
			(hide yes)
			(effects
				(font
					(size 1.016 1.016)
					(thickness 0.1524)
				)
			)
		)
		(duplicate_pad_numbers_are_jumpers no)
		(fp_line
			(start 0.508 -0.9398)
			(end -0.508 -0.9398)
			(stroke
				(width 0.1524)
				(type default)
			)
			(layer "F.SilkS")
		)
		(fp_line
			(start -0.508 -0.9398)
			(end -0.508 0.9398)
			(stroke
				(width 0.1524)
				(type default)
			)
			(layer "F.SilkS")
		)
		(fp_rect
			(start -0.508 0.9398)
			(end 0.508 -0.9398)
			(stroke
				(width 0)
				(type default)
			)
			(fill no)
			(layer "F.CrtYd")
		)
		(fp_rect
			(start -0.508 0.9398)
			(end 0.508 -0.9398)
			(stroke
				(width 0)
				(type default)
			)
			(fill no)
			(layer "F.Fab")
		)
		(pad "1" smd custom
			(at 0 -0.4445 90)
			(size 0.1397 0.1397)
			(layers "F.Cu" "F.Mask" "F.Paste")
			(net "NCT7904_VSEN1")
			(options
				(clearance outline)
				(anchor circle)
			)
			(primitives
				(gr_poly
					(pts
						(arc
							(start -0.1778 -0.2794)
							(mid -0.249642 -0.249642)
							(end -0.2794 -0.1778)
						)
						(arc
							(start -0.2794 0.1778)
							(mid -0.249642 0.249642)
							(end -0.1778 0.2794)
						)
						(arc
							(start 0.1778 0.2794)
							(mid 0.249642 0.249642)
							(end 0.2794 0.1778)
						)
						(arc
							(start 0.2794 -0.1778)
							(mid 0.249642 -0.249642)
							(end 0.1778 -0.2794)
						)
					)
					(width 0)
					(fill yes)
				)
			)
		)
		(pad "2" smd custom
			(at 0 0.4445 90)
			(size 0.1397 0.1397)
			(layers "F.Cu" "F.Mask" "F.Paste")
			(net "NCT7904_VSEN_P12V_AUX")
			(options
				(clearance outline)
				(anchor circle)
			)
			(primitives
				(gr_poly
					(pts
						(arc
							(start -0.1778 -0.2794)
							(mid -0.249642 -0.249642)
							(end -0.2794 -0.1778)
						)
						(arc
							(start -0.2794 0.1778)
							(mid -0.249642 0.249642)
							(end -0.1778 0.2794)
						)
						(arc
							(start 0.1778 0.2794)
							(mid 0.249642 0.249642)
							(end 0.2794 0.1778)
						)
						(arc
							(start 0.2794 -0.1778)
							(mid 0.249642 -0.249642)
							(end 0.1778 -0.2794)
						)
					)
					(width 0)
					(fill yes)
				)
			)
		)
	)
	(footprint ""
		(layer "F.Cu")
		(at 13.081 -448.2338 90)
		(property "Reference" "R101"
			(at 0 0 90)
			(layer "F.SilkS")
			(hide yes)
			(effects
				(font
					(size 1.27 1.27)
				)
			)
		)
		(property "Value" "27KR3F-GP"
			(at -0.0254 -2.5146 90)
			(unlocked yes)
			(layer "F.Fab")
			(hide yes)
			(effects
				(font
					(size 1.016 1.016)
					(thickness 0.1524)
				)
			)
		)
		(property "Device Type" "R603H22"
			(at -0.0254 -4.0386 90)
			(unlocked yes)
			(layer "F.Fab")
			(hide yes)
			(effects
				(font
					(size 1.016 1.016)
					(thickness 0.1524)
				)
			)
		)
		(duplicate_pad_numbers_are_jumpers no)
		(fp_line
			(start 0.2032 0)
			(end 0.4826 0)
			(stroke
				(width 0.2032)
				(type default)
			)
			(layer "F.SilkS")
		)
		(fp_line
			(start -0.4826 0)
			(end -0.2032 0)
			(stroke
				(width 0.2032)
				(type default)
			)
			(layer "F.SilkS")
		)
		(fp_rect
			(start -0.5842 1.3335)
			(end 0.5842 -1.3335)
			(stroke
				(width 0)
				(type default)
			)
			(fill no)
			(layer "F.CrtYd")
		)
		(fp_rect
			(start -0.5842 1.3335)
			(end 0.5842 -1.3335)
			(stroke
				(width 0)
				(type default)
			)
			(fill no)
			(layer "F.Fab")
		)
		(pad "1" smd custom
			(at 0 -0.762 90)
			(size 0.2159 0.2159)
			(layers "F.Cu" "F.Mask" "F.Paste")
			(net "FAN_TACH2")
			(options
				(clearance outline)
				(anchor circle)
			)
			(primitives
				(gr_poly
					(pts
						(arc
							(start -0.3302 -0.4318)
							(mid -0.402042 -0.402042)
							(end -0.4318 -0.3302)
						)
						(arc
							(start -0.4318 0.3302)
							(mid -0.402042 0.402042)
							(end -0.3302 0.4318)
						)
						(arc
							(start 0.3302 0.4318)
							(mid 0.402042 0.402042)
							(end 0.4318 0.3302)
						)
						(arc
							(start 0.4318 -0.3302)
							(mid 0.402042 -0.402042)
							(end 0.3302 -0.4318)
						)
					)
					(width 0)
					(fill yes)
				)
			)
		)
		(pad "2" smd custom
			(at 0 0.762 90)
			(size 0.2159 0.2159)
			(layers "F.Cu" "F.Mask" "F.Paste")
			(net "FANIN_2")
			(options
				(clearance outline)
				(anchor circle)
			)
			(primitives
				(gr_poly
					(pts
						(arc
							(start -0.3302 -0.4318)
							(mid -0.402042 -0.402042)
							(end -0.4318 -0.3302)
						)
						(arc
							(start -0.4318 0.3302)
							(mid -0.402042 0.402042)
							(end -0.3302 0.4318)
						)
						(arc
							(start 0.3302 0.4318)
							(mid 0.402042 0.402042)
							(end 0.4318 0.3302)
						)
						(arc
							(start 0.4318 -0.3302)
							(mid 0.402042 -0.402042)
							(end 0.3302 -0.4318)
						)
					)
					(width 0)
					(fill yes)
				)
			)
		)
	)
	(footprint ""
		(layer "F.Cu")
		(at 36.5252 -254.381)
		(property "Reference" "R48"
			(at 0 0 0)
			(layer "F.SilkS")
			(hide yes)
			(effects
				(font
					(size 1.27 1.27)
				)
			)
		)
		(property "Value" "4K7R2J-2-GP"
			(at 0.064008 -3.993896 0)
			(unlocked yes)
			(layer "F.Fab")
			(hide yes)
			(effects
				(font
					(size 1.016 1.016)
					(thickness 0.1524)
				)
			)
		)
		(property "Device Type" "R402H16"
			(at 0.064008 -5.517896 0)
			(unlocked yes)
			(layer "F.Fab")
			(hide yes)
			(effects
				(font
					(size 1.016 1.016)
					(thickness 0.1524)
				)
			)
		)
		(duplicate_pad_numbers_are_jumpers no)
		(fp_line
			(start -0.508 -0.9398)
			(end -0.508 0.9398)
			(stroke
				(width 0.1524)
				(type default)
			)
			(layer "F.SilkS")
		)
		(fp_line
			(start 0.508 -0.9398)
			(end -0.508 -0.9398)
			(stroke
				(width 0.1524)
				(type default)
			)
			(layer "F.SilkS")
		)
		(fp_rect
			(start -0.508 0.9398)
			(end 0.508 -0.9398)
			(stroke
				(width 0)
				(type default)
			)
			(fill no)
			(layer "F.CrtYd")
		)
		(fp_rect
			(start -0.508 0.9398)
			(end 0.508 -0.9398)
			(stroke
				(width 0)
				(type default)
			)
			(fill no)
			(layer "F.Fab")
		)
		(pad "1" smd custom
			(at 0 -0.4445)
			(size 0.1397 0.1397)
			(layers "F.Cu" "F.Mask" "F.Paste")
			(net "P3V3")
			(options
				(clearance outline)
				(anchor circle)
			)
			(primitives
				(gr_poly
					(pts
						(arc
							(start -0.1778 -0.2794)
							(mid -0.249642 -0.249642)
							(end -0.2794 -0.1778)
						)
						(arc
							(start -0.2794 0.1778)
							(mid -0.249642 0.249642)
							(end -0.1778 0.2794)
						)
						(arc
							(start 0.1778 0.2794)
							(mid 0.249642 0.249642)
							(end 0.2794 0.1778)
						)
						(arc
							(start 0.2794 -0.1778)
							(mid 0.249642 -0.249642)
							(end 0.1778 -0.2794)
						)
					)
					(width 0)
					(fill yes)
				)
			)
		)
		(pad "2" smd custom
			(at 0 0.4445)
			(size 0.1397 0.1397)
			(layers "F.Cu" "F.Mask" "F.Paste")
			(net "LED_DRV_RST")
			(options
				(clearance outline)
				(anchor circle)
			)
			(primitives
				(gr_poly
					(pts
						(arc
							(start -0.1778 -0.2794)
							(mid -0.249642 -0.249642)
							(end -0.2794 -0.1778)
						)
						(arc
							(start -0.2794 0.1778)
							(mid -0.249642 0.249642)
							(end -0.1778 0.2794)
						)
						(arc
							(start 0.1778 0.2794)
							(mid 0.249642 0.249642)
							(end 0.2794 0.1778)
						)
						(arc
							(start 0.2794 -0.1778)
							(mid 0.249642 -0.249642)
							(end 0.1778 -0.2794)
						)
					)
					(width 0)
					(fill yes)
				)
			)
		)
	)
	(footprint ""
		(layer "F.Cu")
		(at 18.7706 -141.5034 180)
		(property "Reference" "PR106"
			(at 0 0 180)
			(layer "F.SilkS")
			(hide yes)
			(effects
				(font
					(size 1.27 1.27)
				)
			)
		)
		(property "Value" "1KR2F-3-GP"
			(at 0.064008 -3.993896 180)
			(unlocked yes)
			(layer "F.Fab")
			(hide yes)
			(effects
				(font
					(size 1.016 1.016)
					(thickness 0.1524)
				)
			)
		)
		(property "Device Type" "R402H16"
			(at 0.064008 -5.517896 180)
			(unlocked yes)
			(layer "F.Fab")
			(hide yes)
			(effects
				(font
					(size 1.016 1.016)
					(thickness 0.1524)
				)
			)
		)
		(duplicate_pad_numbers_are_jumpers no)
		(fp_line
			(start 0.508 -0.9398)
			(end -0.508 -0.9398)
			(stroke
				(width 0.1524)
				(type default)
			)
			(layer "F.SilkS")
		)
		(fp_line
			(start -0.508 -0.9398)
			(end -0.508 0.9398)
			(stroke
				(width 0.1524)
				(type default)
			)
			(layer "F.SilkS")
		)
		(fp_rect
			(start -0.508 0.9398)
			(end 0.508 -0.9398)
			(stroke
				(width 0)
				(type default)
			)
			(fill no)
			(layer "F.CrtYd")
		)
		(fp_rect
			(start -0.508 0.9398)
			(end 0.508 -0.9398)
			(stroke
				(width 0)
				(type default)
			)
			(fill no)
			(layer "F.Fab")
		)
		(pad "1" smd custom
			(at 0 -0.4445 180)
			(size 0.1397 0.1397)
			(layers "F.Cu" "F.Mask" "F.Paste")
			(net "P12VU_2490_PG")
			(options
				(clearance outline)
				(anchor circle)
			)
			(primitives
				(gr_poly
					(pts
						(arc
							(start -0.1778 -0.2794)
							(mid -0.249642 -0.249642)
							(end -0.2794 -0.1778)
						)
						(arc
							(start -0.2794 0.1778)
							(mid -0.249642 0.249642)
							(end -0.1778 0.2794)
						)
						(arc
							(start 0.1778 0.2794)
							(mid 0.249642 0.249642)
							(end 0.2794 0.1778)
						)
						(arc
							(start 0.2794 -0.1778)
							(mid 0.249642 -0.249642)
							(end 0.1778 -0.2794)
						)
					)
					(width 0)
					(fill yes)
				)
			)
		)
		(pad "2" smd custom
			(at 0 0.4445 180)
			(size 0.1397 0.1397)
			(layers "F.Cu" "F.Mask" "F.Paste")
			(net "GND")
			(options
				(clearance outline)
				(anchor circle)
			)
			(primitives
				(gr_poly
					(pts
						(arc
							(start -0.1778 -0.2794)
							(mid -0.249642 -0.249642)
							(end -0.2794 -0.1778)
						)
						(arc
							(start -0.2794 0.1778)
							(mid -0.249642 0.249642)
							(end -0.1778 0.2794)
						)
						(arc
							(start 0.1778 0.2794)
							(mid 0.249642 0.249642)
							(end 0.2794 0.1778)
						)
						(arc
							(start 0.2794 -0.1778)
							(mid 0.249642 -0.249642)
							(end 0.1778 -0.2794)
						)
					)
					(width 0)
					(fill yes)
				)
			)
		)
	)
	(footprint ""
		(layer "F.Cu")
		(at 36.0426 -369.1382 -90)
		(property "Reference" "PR4"
			(at 0 0 270)
			(layer "F.SilkS")
			(hide yes)
			(effects
				(font
					(size 1.27 1.27)
				)
			)
		)
		(property "Value" "49K9R2F-L-GP"
			(at 0.064008 -3.993896 270)
			(unlocked yes)
			(layer "F.Fab")
			(hide yes)
			(effects
				(font
					(size 1.016 1.016)
					(thickness 0.1524)
				)
			)
		)
		(property "Device Type" "R402H16"
			(at 0.064008 -5.517896 270)
			(unlocked yes)
			(layer "F.Fab")
			(hide yes)
			(effects
				(font
					(size 1.016 1.016)
					(thickness 0.1524)
				)
			)
		)
		(duplicate_pad_numbers_are_jumpers no)
		(fp_line
			(start -0.508 -0.9398)
			(end -0.508 0.9398)
			(stroke
				(width 0.1524)
				(type default)
			)
			(layer "F.SilkS")
		)
		(fp_line
			(start 0.508 -0.9398)
			(end -0.508 -0.9398)
			(stroke
				(width 0.1524)
				(type default)
			)
			(layer "F.SilkS")
		)
		(fp_rect
			(start -0.508 0.9398)
			(end 0.508 -0.9398)
			(stroke
				(width 0)
				(type default)
			)
			(fill no)
			(layer "F.CrtYd")
		)
		(fp_rect
			(start -0.508 0.9398)
			(end 0.508 -0.9398)
			(stroke
				(width 0)
				(type default)
			)
			(fill no)
			(layer "F.Fab")
		)
		(pad "1" smd custom
			(at 0 -0.4445 270)
			(size 0.1397 0.1397)
			(layers "F.Cu" "F.Mask" "F.Paste")
			(net "P12V_AUX")
			(options
				(clearance outline)
				(anchor circle)
			)
			(primitives
				(gr_poly
					(pts
						(arc
							(start -0.1778 -0.2794)
							(mid -0.249642 -0.249642)
							(end -0.2794 -0.1778)
						)
						(arc
							(start -0.2794 0.1778)
							(mid -0.249642 0.249642)
							(end -0.1778 0.2794)
						)
						(arc
							(start 0.1778 0.2794)
							(mid 0.249642 0.249642)
							(end 0.2794 0.1778)
						)
						(arc
							(start 0.2794 -0.1778)
							(mid 0.249642 -0.249642)
							(end 0.1778 -0.2794)
						)
					)
					(width 0)
					(fill yes)
				)
			)
		)
		(pad "2" smd custom
			(at 0 0.4445 270)
			(size 0.1397 0.1397)
			(layers "F.Cu" "F.Mask" "F.Paste")
			(net "ADM1276_PWRGD")
			(options
				(clearance outline)
				(anchor circle)
			)
			(primitives
				(gr_poly
					(pts
						(arc
							(start -0.1778 -0.2794)
							(mid -0.249642 -0.249642)
							(end -0.2794 -0.1778)
						)
						(arc
							(start -0.2794 0.1778)
							(mid -0.249642 0.249642)
							(end -0.1778 0.2794)
						)
						(arc
							(start 0.1778 0.2794)
							(mid 0.249642 0.249642)
							(end 0.2794 0.1778)
						)
						(arc
							(start 0.2794 -0.1778)
							(mid 0.249642 -0.249642)
							(end 0.1778 -0.2794)
						)
					)
					(width 0)
					(fill yes)
				)
			)
		)
	)
	(footprint ""
		(layer "F.Cu")
		(at 29.9212 -247.4214)
		(property "Reference" "U5"
			(at 0 0 0)
			(layer "F.SilkS")
			(hide yes)
			(effects
				(font
					(size 1.27 1.27)
				)
			)
		)
		(property "Value" "24LC64T-I-GP"
			(at 0 -12.1412 0)
			(unlocked yes)
			(layer "F.Fab")
			(hide yes)
			(effects
				(font
					(size 1.016 1.016)
					(thickness 0.1524)
				)
			)
		)
		(property "Device Type" "SSOIC8-1H44"
			(at 0 -13.6652 0)
			(unlocked yes)
			(layer "F.Fab")
			(hide yes)
			(effects
				(font
					(size 1.016 1.016)
					(thickness 0.1524)
				)
			)
		)
		(duplicate_pad_numbers_are_jumpers no)
		(fp_line
			(start -1.778 -1.778)
			(end -1.778 2.667)
			(stroke
				(width 0.2032)
				(type default)
			)
			(layer "F.SilkS")
		)
		(fp_line
			(start -1.778 -1.778)
			(end 1.397 -1.778)
			(stroke
				(width 0.2032)
				(type default)
			)
			(layer "F.SilkS")
		)
		(fp_line
			(start -1.778 1.778)
			(end -1.778 3.81)
			(stroke
				(width 0.508)
				(type default)
			)
			(layer "F.SilkS")
		)
		(fp_line
			(start -1.143 0)
			(end -1.778 -0.635)
			(stroke
				(width 0.2032)
				(type default)
			)
			(layer "F.SilkS")
		)
		(fp_line
			(start -1.143 0)
			(end -1.778 0.635)
			(stroke
				(width 0.2032)
				(type default)
			)
			(layer "F.SilkS")
		)
		(fp_line
			(start 1.397 -1.778)
			(end 1.397 1.778)
			(stroke
				(width 0.2032)
				(type default)
			)
			(layer "F.SilkS")
		)
		(fp_line
			(start 1.397 1.778)
			(end -1.778 1.778)
			(stroke
				(width 0.2032)
				(type default)
			)
			(layer "F.SilkS")
		)
		(fp_poly
			(pts
				(xy -2.032 3.81) (xy 2.032 3.81) (xy 2.032 -3.81) (xy -2.032 -3.81)
			)
			(stroke
				(width 0)
				(type default)
			)
			(fill no)
			(layer "F.CrtYd")
		)
		(fp_poly
			(pts
				(xy -2.032 -3.81) (xy 2.032 -3.81) (xy 2.032 3.81) (xy -2.032 3.81)
			)
			(stroke
				(width 0)
				(type default)
			)
			(fill no)
			(layer "F.Fab")
		)
		(pad "1" smd rect
			(at -0.97536 2.8194)
			(size 0.3556 1.524)
			(layers "F.Cu" "F.Mask" "F.Paste")
			(net "FCB_EEPROM_A0")
		)
		(pad "2" smd rect
			(at -0.32512 2.8194)
			(size 0.3556 1.524)
			(layers "F.Cu" "F.Mask" "F.Paste")
			(net "FCB_EEPROM_A1")
		)
		(pad "3" smd rect
			(at 0.32512 2.8194)
			(size 0.3556 1.524)
			(layers "F.Cu" "F.Mask" "F.Paste")
			(net "FCB_EEPROM_A2")
		)
		(pad "4" smd rect
			(at 0.97536 2.8194)
			(size 0.3556 1.524)
			(layers "F.Cu" "F.Mask" "F.Paste")
			(net "GND")
		)
		(pad "5" smd rect
			(at 0.97536 -2.8194)
			(size 0.3556 1.524)
			(layers "F.Cu" "F.Mask" "F.Paste")
			(net "I2C_C_SDA_EEPROM")
		)
		(pad "6" smd rect
			(at 0.32512 -2.8194)
			(size 0.3556 1.524)
			(layers "F.Cu" "F.Mask" "F.Paste")
			(net "I2C_C_SCL_EEPROM")
		)
		(pad "7" smd rect
			(at -0.32512 -2.8194)
			(size 0.3556 1.524)
			(layers "F.Cu" "F.Mask" "F.Paste")
			(net "EEPROM_WP")
		)
		(pad "8" smd rect
			(at -0.97536 -2.8194)
			(size 0.3556 1.524)
			(layers "F.Cu" "F.Mask" "F.Paste")
			(net "P3V3")
		)
	)
	(footprint ""
		(layer "F.Cu")
		(at 34.99231 -167.734234)
		(property "Reference" "R9"
			(at 0 0 0)
			(layer "F.SilkS")
			(hide yes)
			(effects
				(font
					(size 1.27 1.27)
				)
			)
		)
		(property "Value" "100KR2J-1-GP"
			(at 0.064008 -3.993896 0)
			(unlocked yes)
			(layer "F.Fab")
			(hide yes)
			(effects
				(font
					(size 1.016 1.016)
					(thickness 0.1524)
				)
			)
		)
		(property "Device Type" "R402H16"
			(at 0.064008 -5.517896 0)
			(unlocked yes)
			(layer "F.Fab")
			(hide yes)
			(effects
				(font
					(size 1.016 1.016)
					(thickness 0.1524)
				)
			)
		)
		(duplicate_pad_numbers_are_jumpers no)
		(fp_line
			(start -0.508 -0.9398)
			(end -0.508 0.9398)
			(stroke
				(width 0.1524)
				(type default)
			)
			(layer "F.SilkS")
		)
		(fp_line
			(start 0.508 -0.9398)
			(end -0.508 -0.9398)
			(stroke
				(width 0.1524)
				(type default)
			)
			(layer "F.SilkS")
		)
		(fp_rect
			(start -0.508 0.9398)
			(end 0.508 -0.9398)
			(stroke
				(width 0)
				(type default)
			)
			(fill no)
			(layer "F.CrtYd")
		)
		(fp_rect
			(start -0.508 0.9398)
			(end 0.508 -0.9398)
			(stroke
				(width 0)
				(type default)
			)
			(fill no)
			(layer "F.Fab")
		)
		(pad "1" smd custom
			(at 0 -0.4445)
			(size 0.1397 0.1397)
			(layers "F.Cu" "F.Mask" "F.Paste")
			(net "P3V3")
			(options
				(clearance outline)
				(anchor circle)
			)
			(primitives
				(gr_poly
					(pts
						(arc
							(start -0.1778 -0.2794)
							(mid -0.249642 -0.249642)
							(end -0.2794 -0.1778)
						)
						(arc
							(start -0.2794 0.1778)
							(mid -0.249642 0.249642)
							(end -0.1778 0.2794)
						)
						(arc
							(start 0.1778 0.2794)
							(mid 0.249642 0.249642)
							(end 0.2794 0.1778)
						)
						(arc
							(start 0.2794 -0.1778)
							(mid 0.249642 -0.249642)
							(end 0.1778 -0.2794)
						)
					)
					(width 0)
					(fill yes)
				)
			)
		)
		(pad "2" smd custom
			(at 0 0.4445)
			(size 0.1397 0.1397)
			(layers "F.Cu" "F.Mask" "F.Paste")
			(net "NCT7904_ADR")
			(options
				(clearance outline)
				(anchor circle)
			)
			(primitives
				(gr_poly
					(pts
						(arc
							(start -0.1778 -0.2794)
							(mid -0.249642 -0.249642)
							(end -0.2794 -0.1778)
						)
						(arc
							(start -0.2794 0.1778)
							(mid -0.249642 0.249642)
							(end -0.1778 0.2794)
						)
						(arc
							(start 0.1778 0.2794)
							(mid 0.249642 0.249642)
							(end 0.2794 0.1778)
						)
						(arc
							(start 0.2794 -0.1778)
							(mid 0.249642 -0.249642)
							(end 0.1778 -0.2794)
						)
					)
					(width 0)
					(fill yes)
				)
			)
		)
	)
	(footprint ""
		(layer "F.Cu")
		(at 36.068 -378.333 180)
		(property "Reference" "PR26"
			(at 0 0 180)
			(layer "F.SilkS")
			(hide yes)
			(effects
				(font
					(size 1.27 1.27)
				)
			)
		)
		(property "Value" "10R2F-L-GP"
			(at 0.064008 -3.993896 180)
			(unlocked yes)
			(layer "F.Fab")
			(hide yes)
			(effects
				(font
					(size 1.016 1.016)
					(thickness 0.1524)
				)
			)
		)
		(property "Device Type" "R402H14"
			(at 0.064008 -5.517896 180)
			(unlocked yes)
			(layer "F.Fab")
			(hide yes)
			(effects
				(font
					(size 1.016 1.016)
					(thickness 0.1524)
				)
			)
		)
		(duplicate_pad_numbers_are_jumpers no)
		(fp_line
			(start 0.508 -0.9398)
			(end -0.508 -0.9398)
			(stroke
				(width 0.1524)
				(type default)
			)
			(layer "F.SilkS")
		)
		(fp_line
			(start -0.508 -0.9398)
			(end -0.508 0.9398)
			(stroke
				(width 0.1524)
				(type default)
			)
			(layer "F.SilkS")
		)
		(fp_rect
			(start -0.508 0.9398)
			(end 0.508 -0.9398)
			(stroke
				(width 0)
				(type default)
			)
			(fill no)
			(layer "F.CrtYd")
		)
		(fp_rect
			(start -0.508 0.9398)
			(end 0.508 -0.9398)
			(stroke
				(width 0)
				(type default)
			)
			(fill no)
			(layer "F.Fab")
		)
		(pad "1" smd custom
			(at 0 -0.4445 180)
			(size 0.1397 0.1397)
			(layers "F.Cu" "F.Mask" "F.Paste")
			(net "ADM1276_GATE")
			(options
				(clearance outline)
				(anchor circle)
			)
			(primitives
				(gr_poly
					(pts
						(arc
							(start -0.1778 -0.2794)
							(mid -0.249642 -0.249642)
							(end -0.2794 -0.1778)
						)
						(arc
							(start -0.2794 0.1778)
							(mid -0.249642 0.249642)
							(end -0.1778 0.2794)
						)
						(arc
							(start 0.1778 0.2794)
							(mid 0.249642 0.249642)
							(end 0.2794 0.1778)
						)
						(arc
							(start 0.2794 -0.1778)
							(mid 0.249642 -0.249642)
							(end 0.1778 -0.2794)
						)
					)
					(width 0)
					(fill yes)
				)
			)
		)
		(pad "2" smd custom
			(at 0 0.4445 180)
			(size 0.1397 0.1397)
			(layers "F.Cu" "F.Mask" "F.Paste")
			(net "ADM1276_GATE_DRV1")
			(options
				(clearance outline)
				(anchor circle)
			)
			(primitives
				(gr_poly
					(pts
						(arc
							(start -0.1778 -0.2794)
							(mid -0.249642 -0.249642)
							(end -0.2794 -0.1778)
						)
						(arc
							(start -0.2794 0.1778)
							(mid -0.249642 0.249642)
							(end -0.1778 0.2794)
						)
						(arc
							(start 0.1778 0.2794)
							(mid 0.249642 0.249642)
							(end 0.2794 0.1778)
						)
						(arc
							(start 0.2794 -0.1778)
							(mid 0.249642 -0.249642)
							(end 0.1778 -0.2794)
						)
					)
					(width 0)
					(fill yes)
				)
			)
		)
	)
	(footprint ""
		(layer "F.Cu")
		(at 40.513 -252.984)
		(property "Reference" "R129"
			(at 0 0 0)
			(layer "F.SilkS")
			(hide yes)
			(effects
				(font
					(size 1.27 1.27)
				)
			)
		)
		(property "Value" "330R2J-3-GP"
			(at 0.064008 -3.993896 0)
			(unlocked yes)
			(layer "F.Fab")
			(hide yes)
			(effects
				(font
					(size 1.016 1.016)
					(thickness 0.1524)
				)
			)
		)
		(property "Device Type" "R402H16"
			(at 0.064008 -5.517896 0)
			(unlocked yes)
			(layer "F.Fab")
			(hide yes)
			(effects
				(font
					(size 1.016 1.016)
					(thickness 0.1524)
				)
			)
		)
		(duplicate_pad_numbers_are_jumpers no)
		(fp_line
			(start -0.508 -0.9398)
			(end -0.508 0.9398)
			(stroke
				(width 0.1524)
				(type default)
			)
			(layer "F.SilkS")
		)
		(fp_line
			(start 0.508 -0.9398)
			(end -0.508 -0.9398)
			(stroke
				(width 0.1524)
				(type default)
			)
			(layer "F.SilkS")
		)
		(fp_rect
			(start -0.508 0.9398)
			(end 0.508 -0.9398)
			(stroke
				(width 0)
				(type default)
			)
			(fill no)
			(layer "F.CrtYd")
		)
		(fp_rect
			(start -0.508 0.9398)
			(end 0.508 -0.9398)
			(stroke
				(width 0)
				(type default)
			)
			(fill no)
			(layer "F.Fab")
		)
		(pad "1" smd custom
			(at 0 -0.4445)
			(size 0.1397 0.1397)
			(layers "F.Cu" "F.Mask" "F.Paste")
			(net "P3V3")
			(options
				(clearance outline)
				(anchor circle)
			)
			(primitives
				(gr_poly
					(pts
						(arc
							(start -0.1778 -0.2794)
							(mid -0.249642 -0.249642)
							(end -0.2794 -0.1778)
						)
						(arc
							(start -0.2794 0.1778)
							(mid -0.249642 0.249642)
							(end -0.1778 0.2794)
						)
						(arc
							(start 0.1778 0.2794)
							(mid 0.249642 0.249642)
							(end 0.2794 0.1778)
						)
						(arc
							(start 0.2794 -0.1778)
							(mid 0.249642 -0.249642)
							(end 0.1778 -0.2794)
						)
					)
					(width 0)
					(fill yes)
				)
			)
		)
		(pad "2" smd custom
			(at 0 0.4445)
			(size 0.1397 0.1397)
			(layers "F.Cu" "F.Mask" "F.Paste")
			(net "LED_DR_LED5")
			(options
				(clearance outline)
				(anchor circle)
			)
			(primitives
				(gr_poly
					(pts
						(arc
							(start -0.1778 -0.2794)
							(mid -0.249642 -0.249642)
							(end -0.2794 -0.1778)
						)
						(arc
							(start -0.2794 0.1778)
							(mid -0.249642 0.249642)
							(end -0.1778 0.2794)
						)
						(arc
							(start 0.1778 0.2794)
							(mid 0.249642 0.249642)
							(end 0.2794 0.1778)
						)
						(arc
							(start 0.2794 -0.1778)
							(mid 0.249642 -0.249642)
							(end 0.1778 -0.2794)
						)
					)
					(width 0)
					(fill yes)
				)
			)
		)
	)
	(footprint ""
		(layer "F.Cu")
		(at 26.3906 -121.7676)
		(property "Reference" "C258"
			(at 0 0 0)
			(layer "F.SilkS")
			(hide yes)
			(effects
				(font
					(size 1.27 1.27)
				)
			)
		)
		(property "Value" "SC1U25V3KX-1-GP"
			(at 0 -2.8194 0)
			(unlocked yes)
			(layer "F.Fab")
			(hide yes)
			(effects
				(font
					(size 1.016 1.016)
					(thickness 0.1524)
				)
			)
		)
		(property "Device Type" "C603H36"
			(at 0 -4.3434 0)
			(unlocked yes)
			(layer "F.Fab")
			(hide yes)
			(effects
				(font
					(size 1.016 1.016)
					(thickness 0.1524)
				)
			)
		)
		(duplicate_pad_numbers_are_jumpers no)
		(fp_line
			(start 0.508 0)
			(end -0.508 0)
			(stroke
				(width 0.2032)
				(type default)
			)
			(layer "F.SilkS")
		)
		(fp_rect
			(start -0.5842 1.3335)
			(end 0.5842 -1.3335)
			(stroke
				(width 0)
				(type default)
			)
			(fill no)
			(layer "F.CrtYd")
		)
		(fp_rect
			(start -0.5842 1.3335)
			(end 0.5842 -1.3335)
			(stroke
				(width 0)
				(type default)
			)
			(fill no)
			(layer "F.Fab")
		)
		(pad "1" smd custom
			(at 0 -0.762)
			(size 0.2159 0.2159)
			(layers "F.Cu" "F.Mask" "F.Paste")
			(net "P12V")
			(options
				(clearance outline)
				(anchor circle)
			)
			(primitives
				(gr_poly
					(pts
						(arc
							(start -0.3302 -0.4318)
							(mid -0.402042 -0.402042)
							(end -0.4318 -0.3302)
						)
						(arc
							(start -0.4318 0.3302)
							(mid -0.402042 0.402042)
							(end -0.3302 0.4318)
						)
						(arc
							(start 0.3302 0.4318)
							(mid 0.402042 0.402042)
							(end 0.4318 0.3302)
						)
						(arc
							(start 0.4318 -0.3302)
							(mid 0.402042 -0.402042)
							(end 0.3302 -0.4318)
						)
					)
					(width 0)
					(fill yes)
				)
			)
		)
		(pad "2" smd custom
			(at 0 0.762)
			(size 0.2159 0.2159)
			(layers "F.Cu" "F.Mask" "F.Paste")
			(net "GND")
			(options
				(clearance outline)
				(anchor circle)
			)
			(primitives
				(gr_poly
					(pts
						(arc
							(start -0.3302 -0.4318)
							(mid -0.402042 -0.402042)
							(end -0.4318 -0.3302)
						)
						(arc
							(start -0.4318 0.3302)
							(mid -0.402042 0.402042)
							(end -0.3302 0.4318)
						)
						(arc
							(start 0.3302 0.4318)
							(mid 0.402042 0.402042)
							(end 0.4318 0.3302)
						)
						(arc
							(start 0.4318 -0.3302)
							(mid 0.402042 -0.402042)
							(end 0.3302 -0.4318)
						)
					)
					(width 0)
					(fill yes)
				)
			)
		)
	)
	(footprint ""
		(layer "F.Cu")
		(at 5.1562 -416.6108 -90)
		(property "Reference" "R28"
			(at 0 0 270)
			(layer "F.SilkS")
			(hide yes)
			(effects
				(font
					(size 1.27 1.27)
				)
			)
		)
		(property "Value" "0R2J-2-GP"
			(at 0.064008 -3.993896 270)
			(unlocked yes)
			(layer "F.Fab")
			(hide yes)
			(effects
				(font
					(size 1.016 1.016)
					(thickness 0.1524)
				)
			)
		)
		(property "Device Type" "R402H16"
			(at 0.064008 -5.517896 270)
			(unlocked yes)
			(layer "F.Fab")
			(hide yes)
			(effects
				(font
					(size 1.016 1.016)
					(thickness 0.1524)
				)
			)
		)
		(duplicate_pad_numbers_are_jumpers no)
		(fp_line
			(start -0.508 -0.9398)
			(end -0.508 0.9398)
			(stroke
				(width 0.1524)
				(type default)
			)
			(layer "F.SilkS")
		)
		(fp_line
			(start 0.508 -0.9398)
			(end -0.508 -0.9398)
			(stroke
				(width 0.1524)
				(type default)
			)
			(layer "F.SilkS")
		)
		(fp_rect
			(start -0.508 0.9398)
			(end 0.508 -0.9398)
			(stroke
				(width 0)
				(type default)
			)
			(fill no)
			(layer "F.CrtYd")
		)
		(fp_rect
			(start -0.508 0.9398)
			(end 0.508 -0.9398)
			(stroke
				(width 0)
				(type default)
			)
			(fill no)
			(layer "F.Fab")
		)
		(pad "1" smd custom
			(at 0 -0.4445 270)
			(size 0.1397 0.1397)
			(layers "F.Cu" "F.Mask" "F.Paste")
			(net "LED_DR_LED1_K")
			(options
				(clearance outline)
				(anchor circle)
			)
			(primitives
				(gr_poly
					(pts
						(arc
							(start -0.1778 -0.2794)
							(mid -0.249642 -0.249642)
							(end -0.2794 -0.1778)
						)
						(arc
							(start -0.2794 0.1778)
							(mid -0.249642 0.249642)
							(end -0.1778 0.2794)
						)
						(arc
							(start 0.1778 0.2794)
							(mid 0.249642 0.249642)
							(end 0.2794 0.1778)
						)
						(arc
							(start 0.2794 -0.1778)
							(mid 0.249642 -0.249642)
							(end 0.1778 -0.2794)
						)
					)
					(width 0)
					(fill yes)
				)
			)
		)
		(pad "2" smd custom
			(at 0 0.4445 270)
			(size 0.1397 0.1397)
			(layers "F.Cu" "F.Mask" "F.Paste")
			(net "GND")
			(options
				(clearance outline)
				(anchor circle)
			)
			(primitives
				(gr_poly
					(pts
						(arc
							(start -0.1778 -0.2794)
							(mid -0.249642 -0.249642)
							(end -0.2794 -0.1778)
						)
						(arc
							(start -0.2794 0.1778)
							(mid -0.249642 0.249642)
							(end -0.1778 0.2794)
						)
						(arc
							(start 0.1778 0.2794)
							(mid 0.249642 0.249642)
							(end 0.2794 0.1778)
						)
						(arc
							(start 0.2794 -0.1778)
							(mid 0.249642 -0.249642)
							(end 0.1778 -0.2794)
						)
					)
					(width 0)
					(fill yes)
				)
			)
		)
	)
	(footprint ""
		(layer "F.Cu")
		(at 30.734 -381 180)
		(property "Reference" "PR20"
			(at 0 0 180)
			(layer "F.SilkS")
			(hide yes)
			(effects
				(font
					(size 1.27 1.27)
				)
			)
		)
		(property "Value" "10R2F-L-GP"
			(at 0.064008 -3.993896 180)
			(unlocked yes)
			(layer "F.Fab")
			(hide yes)
			(effects
				(font
					(size 1.016 1.016)
					(thickness 0.1524)
				)
			)
		)
		(property "Device Type" "R402H14"
			(at 0.064008 -5.517896 180)
			(unlocked yes)
			(layer "F.Fab")
			(hide yes)
			(effects
				(font
					(size 1.016 1.016)
					(thickness 0.1524)
				)
			)
		)
		(duplicate_pad_numbers_are_jumpers no)
		(fp_line
			(start 0.508 -0.9398)
			(end -0.508 -0.9398)
			(stroke
				(width 0.1524)
				(type default)
			)
			(layer "F.SilkS")
		)
		(fp_line
			(start -0.508 -0.9398)
			(end -0.508 0.9398)
			(stroke
				(width 0.1524)
				(type default)
			)
			(layer "F.SilkS")
		)
		(fp_rect
			(start -0.508 0.9398)
			(end 0.508 -0.9398)
			(stroke
				(width 0)
				(type default)
			)
			(fill no)
			(layer "F.CrtYd")
		)
		(fp_rect
			(start -0.508 0.9398)
			(end 0.508 -0.9398)
			(stroke
				(width 0)
				(type default)
			)
			(fill no)
			(layer "F.Fab")
		)
		(pad "1" smd custom
			(at 0 -0.4445 180)
			(size 0.1397 0.1397)
			(layers "F.Cu" "F.Mask" "F.Paste")
			(net "ADM1276_SENSE+")
			(options
				(clearance outline)
				(anchor circle)
			)
			(primitives
				(gr_poly
					(pts
						(arc
							(start -0.1778 -0.2794)
							(mid -0.249642 -0.249642)
							(end -0.2794 -0.1778)
						)
						(arc
							(start -0.2794 0.1778)
							(mid -0.249642 0.249642)
							(end -0.1778 0.2794)
						)
						(arc
							(start 0.1778 0.2794)
							(mid 0.249642 0.249642)
							(end 0.2794 0.1778)
						)
						(arc
							(start 0.2794 -0.1778)
							(mid 0.249642 -0.249642)
							(end 0.1778 -0.2794)
						)
					)
					(width 0)
					(fill yes)
				)
			)
		)
		(pad "2" smd custom
			(at 0 0.4445 180)
			(size 0.1397 0.1397)
			(layers "F.Cu" "F.Mask" "F.Paste")
			(net "SENSE+_R1")
			(options
				(clearance outline)
				(anchor circle)
			)
			(primitives
				(gr_poly
					(pts
						(arc
							(start -0.1778 -0.2794)
							(mid -0.249642 -0.249642)
							(end -0.2794 -0.1778)
						)
						(arc
							(start -0.2794 0.1778)
							(mid -0.249642 0.249642)
							(end -0.1778 0.2794)
						)
						(arc
							(start 0.1778 0.2794)
							(mid 0.249642 0.249642)
							(end 0.2794 0.1778)
						)
						(arc
							(start 0.2794 -0.1778)
							(mid 0.249642 -0.249642)
							(end 0.1778 -0.2794)
						)
					)
					(width 0)
					(fill yes)
				)
			)
		)
	)
	(footprint ""
		(layer "F.Cu")
		(at 37.8968 -139.9794 180)
		(property "Reference" "PU7"
			(at 0 0 180)
			(layer "F.SilkS")
			(hide yes)
			(effects
				(font
					(size 1.27 1.27)
				)
			)
		)
		(property "Value" "TPS2490DGSR-GP"
			(at 0 -11.1252 180)
			(unlocked yes)
			(layer "F.Fab")
			(hide yes)
			(effects
				(font
					(size 1.016 1.016)
					(thickness 0.1524)
				)
			)
		)
		(property "Device Type" "MSOP10H44"
			(at 0 -12.6492 180)
			(unlocked yes)
			(layer "F.Fab")
			(hide yes)
			(effects
				(font
					(size 1.016 1.016)
					(thickness 0.1524)
				)
			)
		)
		(duplicate_pad_numbers_are_jumpers no)
		(fp_line
			(start 1.143 1.016)
			(end -2.0066 1.016)
			(stroke
				(width 0.1524)
				(type default)
			)
			(layer "F.SilkS")
		)
		(fp_line
			(start 1.143 -1.016)
			(end 1.143 1.016)
			(stroke
				(width 0.1524)
				(type default)
			)
			(layer "F.SilkS")
		)
		(fp_line
			(start -1.5748 0)
			(end -1.9558 0.381)
			(stroke
				(width 0.1524)
				(type default)
			)
			(layer "F.SilkS")
		)
		(fp_line
			(start -1.5748 0)
			(end -1.9558 -0.381)
			(stroke
				(width 0.1524)
				(type default)
			)
			(layer "F.SilkS")
		)
		(fp_line
			(start -1.8288 1.016)
			(end -1.8288 3.048)
			(stroke
				(width 0.508)
				(type default)
			)
			(layer "F.SilkS")
		)
		(fp_line
			(start -2.0066 1.016)
			(end -2.0066 -1.016)
			(stroke
				(width 0.1524)
				(type default)
			)
			(layer "F.SilkS")
		)
		(fp_line
			(start -2.0066 -1.016)
			(end 1.143 -1.016)
			(stroke
				(width 0.1524)
				(type default)
			)
			(layer "F.SilkS")
		)
		(fp_poly
			(pts
				(xy -2.0828 3.3401) (xy 2.0828 3.3401) (xy 2.0828 -3.3401) (xy -2.0828 -3.3401)
			)
			(stroke
				(width 0)
				(type default)
			)
			(fill no)
			(layer "F.CrtYd")
		)
		(fp_poly
			(pts
				(xy -2.0828 3.3401) (xy 2.0828 3.3401) (xy 2.0828 -3.3401) (xy -2.0828 -3.3401)
			)
			(stroke
				(width 0)
				(type default)
			)
			(fill no)
			(layer "F.Fab")
		)
		(pad "1" smd rect
			(at -0.99949 2.0701 180)
			(size 0.3048 1.524)
			(layers "F.Cu" "F.Mask" "F.Paste")
			(net "P12VL_2490_EN_2")
		)
		(pad "2" smd rect
			(at -0.50038 2.0701 180)
			(size 0.3048 1.524)
			(layers "F.Cu" "F.Mask" "F.Paste")
			(net "P12VL_2490_VREF")
		)
		(pad "3" smd rect
			(at 0 2.0701 180)
			(size 0.3048 1.524)
			(layers "F.Cu" "F.Mask" "F.Paste")
			(net "P12VL_2490_PROG")
		)
		(pad "4" smd rect
			(at 0.50038 2.0701 180)
			(size 0.3048 1.524)
			(layers "F.Cu" "F.Mask" "F.Paste")
			(net "P12VL_2490_TIMER")
		)
		(pad "5" smd rect
			(at 0.99949 2.0701 180)
			(size 0.3048 1.524)
			(layers "F.Cu" "F.Mask" "F.Paste")
			(net "GND")
		)
		(pad "6" smd rect
			(at 0.99949 -2.0701 180)
			(size 0.3048 1.524)
			(layers "F.Cu" "F.Mask" "F.Paste")
			(net "P12VL_2490_PG")
		)
		(pad "7" smd rect
			(at 0.50038 -2.0701 180)
			(size 0.3048 1.524)
			(layers "F.Cu" "F.Mask" "F.Paste")
			(net "P12VL")
		)
		(pad "8" smd rect
			(at 0 -2.0701 180)
			(size 0.3048 1.524)
			(layers "F.Cu" "F.Mask" "F.Paste")
			(net "P12VL_2490_GATE")
		)
		(pad "9" smd rect
			(at -0.50038 -2.0701 180)
			(size 0.3048 1.524)
			(layers "F.Cu" "F.Mask" "F.Paste")
			(net "P12VL_2490_SENSE")
		)
		(pad "10" smd rect
			(at -0.99949 -2.0701 180)
			(size 0.3048 1.524)
			(layers "F.Cu" "F.Mask" "F.Paste")
			(net "P12VL_2490_VCC")
		)
	)
	(footprint ""
		(layer "F.Cu")
		(at 33.51149 -152.889966 180)
		(property "Reference" "TP10"
			(at 0 0 180)
			(layer "F.SilkS")
			(hide yes)
			(effects
				(font
					(size 1.27 1.27)
				)
			)
		)
		(property "Value" "TPAD32-GP"
			(at 0 -3.166364 180)
			(unlocked yes)
			(layer "F.Fab")
			(hide yes)
			(effects
				(font
					(size 1.016 1.016)
					(thickness 0.1524)
				)
			)
		)
		(property "Device Type" "TPAD32"
			(at 0 -4.690618 180)
			(unlocked yes)
			(layer "F.Fab")
			(hide yes)
			(effects
				(font
					(size 1.016 1.016)
					(thickness 0.1524)
				)
			)
		)
		(duplicate_pad_numbers_are_jumpers no)
		(fp_poly
			(pts
				(arc
					(start 0.7112 0)
					(mid -0.7112 0)
					(end 0.7112 0)
				)
			)
			(stroke
				(width 0)
				(type default)
			)
			(fill no)
			(layer "F.CrtYd")
		)
		(fp_poly
			(pts
				(arc
					(start 0.7112 0)
					(mid -0.7112 0)
					(end 0.7112 0)
				)
			)
			(stroke
				(width 0)
				(type default)
			)
			(fill no)
			(layer "F.Fab")
		)
		(pad "1" smd circle
			(at 0 0 180)
			(size 0.8128 0.8128)
			(layers "F.Cu" "F.Mask" "F.Paste")
			(net "NCT7904_VSEN11")
		)
	)
	(footprint ""
		(layer "F.Cu")
		(at 20.675092 -285.598362 180)
		(property "Reference" "R94"
			(at 0 0 180)
			(layer "F.SilkS")
			(hide yes)
			(effects
				(font
					(size 1.27 1.27)
				)
			)
		)
		(property "Value" "4K7R2F-GP"
			(at 0.064008 -3.993896 180)
			(unlocked yes)
			(layer "F.Fab")
			(hide yes)
			(effects
				(font
					(size 1.016 1.016)
					(thickness 0.1524)
				)
			)
		)
		(property "Device Type" "R402H16"
			(at 0.064008 -5.517896 180)
			(unlocked yes)
			(layer "F.Fab")
			(hide yes)
			(effects
				(font
					(size 1.016 1.016)
					(thickness 0.1524)
				)
			)
		)
		(duplicate_pad_numbers_are_jumpers no)
		(fp_line
			(start 0.508 -0.9398)
			(end -0.508 -0.9398)
			(stroke
				(width 0.1524)
				(type default)
			)
			(layer "F.SilkS")
		)
		(fp_line
			(start -0.508 -0.9398)
			(end -0.508 0.9398)
			(stroke
				(width 0.1524)
				(type default)
			)
			(layer "F.SilkS")
		)
		(fp_rect
			(start -0.508 0.9398)
			(end 0.508 -0.9398)
			(stroke
				(width 0)
				(type default)
			)
			(fill no)
			(layer "F.CrtYd")
		)
		(fp_rect
			(start -0.508 0.9398)
			(end 0.508 -0.9398)
			(stroke
				(width 0)
				(type default)
			)
			(fill no)
			(layer "F.Fab")
		)
		(pad "1" smd custom
			(at 0 -0.4445 180)
			(size 0.1397 0.1397)
			(layers "F.Cu" "F.Mask" "F.Paste")
			(net "P12V")
			(options
				(clearance outline)
				(anchor circle)
			)
			(primitives
				(gr_poly
					(pts
						(arc
							(start -0.1778 -0.2794)
							(mid -0.249642 -0.249642)
							(end -0.2794 -0.1778)
						)
						(arc
							(start -0.2794 0.1778)
							(mid -0.249642 0.249642)
							(end -0.1778 0.2794)
						)
						(arc
							(start 0.1778 0.2794)
							(mid 0.249642 0.249642)
							(end 0.2794 0.1778)
						)
						(arc
							(start 0.2794 -0.1778)
							(mid 0.249642 -0.249642)
							(end 0.1778 -0.2794)
						)
					)
					(width 0)
					(fill yes)
				)
			)
		)
		(pad "2" smd custom
			(at 0 0.4445 180)
			(size 0.1397 0.1397)
			(layers "F.Cu" "F.Mask" "F.Paste")
			(net "FAN_TACH4")
			(options
				(clearance outline)
				(anchor circle)
			)
			(primitives
				(gr_poly
					(pts
						(arc
							(start -0.1778 -0.2794)
							(mid -0.249642 -0.249642)
							(end -0.2794 -0.1778)
						)
						(arc
							(start -0.2794 0.1778)
							(mid -0.249642 0.249642)
							(end -0.1778 0.2794)
						)
						(arc
							(start 0.1778 0.2794)
							(mid 0.249642 0.249642)
							(end 0.2794 0.1778)
						)
						(arc
							(start 0.2794 -0.1778)
							(mid 0.249642 -0.249642)
							(end 0.1778 -0.2794)
						)
					)
					(width 0)
					(fill yes)
				)
			)
		)
	)
	(footprint ""
		(layer "F.Cu")
		(at 37.719 -352.425 90)
		(property "Reference" "C261"
			(at 0 0 90)
			(layer "F.SilkS")
			(hide yes)
			(effects
				(font
					(size 1.27 1.27)
				)
			)
		)
		(property "Value" "SC10U25V6KX-1GP"
			(at -0.0762 -5.1308 90)
			(unlocked yes)
			(layer "F.Fab")
			(hide yes)
			(effects
				(font
					(size 1.016 1.016)
					(thickness 0.1524)
				)
			)
		)
		(property "Device Type" "C1206H71"
			(at -0.127 -6.6548 90)
			(unlocked yes)
			(layer "F.Fab")
			(hide yes)
			(effects
				(font
					(size 1.016 1.016)
					(thickness 0.1524)
				)
			)
		)
		(duplicate_pad_numbers_are_jumpers no)
		(fp_line
			(start 1.016 -2.2352)
			(end 1.016 -0.8382)
			(stroke
				(width 0.1524)
				(type default)
			)
			(layer "F.SilkS")
		)
		(fp_line
			(start -1.016 -2.2352)
			(end 1.016 -2.2352)
			(stroke
				(width 0.1524)
				(type default)
			)
			(layer "F.SilkS")
		)
		(fp_line
			(start -1.016 -0.8382)
			(end -1.016 -2.2352)
			(stroke
				(width 0.1524)
				(type default)
			)
			(layer "F.SilkS")
		)
		(fp_line
			(start 1.016 0.8382)
			(end 1.016 2.2352)
			(stroke
				(width 0.1524)
				(type default)
			)
			(layer "F.SilkS")
		)
		(fp_line
			(start 1.016 2.2352)
			(end -1.016 2.2352)
			(stroke
				(width 0.1524)
				(type default)
			)
			(layer "F.SilkS")
		)
		(fp_line
			(start -1.016 2.2352)
			(end -1.016 0.8382)
			(stroke
				(width 0.1524)
				(type default)
			)
			(layer "F.SilkS")
		)
		(fp_rect
			(start -1.0922 2.3114)
			(end 1.0922 -2.3114)
			(stroke
				(width 0)
				(type default)
			)
			(fill no)
			(layer "F.CrtYd")
		)
		(fp_poly
			(pts
				(xy 1.0922 -2.3114) (xy 1.0922 2.3114) (xy -1.0922 2.3114) (xy -1.0922 -2.3114)
			)
			(stroke
				(width 0)
				(type default)
			)
			(fill no)
			(layer "F.Fab")
		)
		(pad "1" smd rect
			(at 0 -1.397 90)
			(size 1.651 1.27)
			(layers "F.Cu" "F.Mask" "F.Paste")
			(net "OTP_RETRY_G")
		)
		(pad "2" smd rect
			(at 0 1.397 90)
			(size 1.651 1.27)
			(layers "F.Cu" "F.Mask" "F.Paste")
			(net "GND")
		)
	)
	(footprint ""
		(layer "F.Cu")
		(at 16.3068 -254.3302 180)
		(property "Reference" "R86"
			(at 0 0 180)
			(layer "F.SilkS")
			(hide yes)
			(effects
				(font
					(size 1.27 1.27)
				)
			)
		)
		(property "Value" "27KR3F-GP"
			(at -0.0254 -2.5146 180)
			(unlocked yes)
			(layer "F.Fab")
			(hide yes)
			(effects
				(font
					(size 1.016 1.016)
					(thickness 0.1524)
				)
			)
		)
		(property "Device Type" "R603H22"
			(at -0.0254 -4.0386 180)
			(unlocked yes)
			(layer "F.Fab")
			(hide yes)
			(effects
				(font
					(size 1.016 1.016)
					(thickness 0.1524)
				)
			)
		)
		(duplicate_pad_numbers_are_jumpers no)
		(fp_line
			(start 0.2032 0)
			(end 0.4826 0)
			(stroke
				(width 0.2032)
				(type default)
			)
			(layer "F.SilkS")
		)
		(fp_line
			(start -0.4826 0)
			(end -0.2032 0)
			(stroke
				(width 0.2032)
				(type default)
			)
			(layer "F.SilkS")
		)
		(fp_rect
			(start -0.5842 1.3335)
			(end 0.5842 -1.3335)
			(stroke
				(width 0)
				(type default)
			)
			(fill no)
			(layer "F.CrtYd")
		)
		(fp_rect
			(start -0.5842 1.3335)
			(end 0.5842 -1.3335)
			(stroke
				(width 0)
				(type default)
			)
			(fill no)
			(layer "F.Fab")
		)
		(pad "1" smd custom
			(at 0 -0.762 180)
			(size 0.2159 0.2159)
			(layers "F.Cu" "F.Mask" "F.Paste")
			(net "FANIN_5")
			(options
				(clearance outline)
				(anchor circle)
			)
			(primitives
				(gr_poly
					(pts
						(arc
							(start -0.3302 -0.4318)
							(mid -0.402042 -0.402042)
							(end -0.4318 -0.3302)
						)
						(arc
							(start -0.4318 0.3302)
							(mid -0.402042 0.402042)
							(end -0.3302 0.4318)
						)
						(arc
							(start 0.3302 0.4318)
							(mid 0.402042 0.402042)
							(end 0.4318 0.3302)
						)
						(arc
							(start 0.4318 -0.3302)
							(mid 0.402042 -0.402042)
							(end 0.3302 -0.4318)
						)
					)
					(width 0)
					(fill yes)
				)
			)
		)
		(pad "2" smd custom
			(at 0 0.762 180)
			(size 0.2159 0.2159)
			(layers "F.Cu" "F.Mask" "F.Paste")
			(net "FAN_TACH5")
			(options
				(clearance outline)
				(anchor circle)
			)
			(primitives
				(gr_poly
					(pts
						(arc
							(start -0.3302 -0.4318)
							(mid -0.402042 -0.402042)
							(end -0.4318 -0.3302)
						)
						(arc
							(start -0.4318 0.3302)
							(mid -0.402042 0.402042)
							(end -0.3302 0.4318)
						)
						(arc
							(start 0.3302 0.4318)
							(mid 0.402042 0.402042)
							(end 0.4318 0.3302)
						)
						(arc
							(start 0.4318 -0.3302)
							(mid 0.402042 -0.402042)
							(end 0.3302 -0.4318)
						)
					)
					(width 0)
					(fill yes)
				)
			)
		)
	)
	(footprint ""
		(layer "F.Cu")
		(at 31.7246 -149.073616)
		(property "Reference" "R128"
			(at 0 0 0)
			(layer "F.SilkS")
			(hide yes)
			(effects
				(font
					(size 1.27 1.27)
				)
			)
		)
		(property "Value" "10KR2F-2-GP"
			(at 0.064008 -3.993896 0)
			(unlocked yes)
			(layer "F.Fab")
			(hide yes)
			(effects
				(font
					(size 1.016 1.016)
					(thickness 0.1524)
				)
			)
		)
		(property "Device Type" "R402H16"
			(at 0.064008 -5.517896 0)
			(unlocked yes)
			(layer "F.Fab")
			(hide yes)
			(effects
				(font
					(size 1.016 1.016)
					(thickness 0.1524)
				)
			)
		)
		(duplicate_pad_numbers_are_jumpers no)
		(fp_line
			(start -0.508 -0.9398)
			(end -0.508 0.9398)
			(stroke
				(width 0.1524)
				(type default)
			)
			(layer "F.SilkS")
		)
		(fp_line
			(start 0.508 -0.9398)
			(end -0.508 -0.9398)
			(stroke
				(width 0.1524)
				(type default)
			)
			(layer "F.SilkS")
		)
		(fp_rect
			(start -0.508 0.9398)
			(end 0.508 -0.9398)
			(stroke
				(width 0)
				(type default)
			)
			(fill no)
			(layer "F.CrtYd")
		)
		(fp_rect
			(start -0.508 0.9398)
			(end 0.508 -0.9398)
			(stroke
				(width 0)
				(type default)
			)
			(fill no)
			(layer "F.Fab")
		)
		(pad "1" smd custom
			(at 0 -0.4445)
			(size 0.1397 0.1397)
			(layers "F.Cu" "F.Mask" "F.Paste")
			(net "NCT7904_VSEN7")
			(options
				(clearance outline)
				(anchor circle)
			)
			(primitives
				(gr_poly
					(pts
						(arc
							(start -0.1778 -0.2794)
							(mid -0.249642 -0.249642)
							(end -0.2794 -0.1778)
						)
						(arc
							(start -0.2794 0.1778)
							(mid -0.249642 0.249642)
							(end -0.1778 0.2794)
						)
						(arc
							(start 0.1778 0.2794)
							(mid 0.249642 0.249642)
							(end 0.2794 0.1778)
						)
						(arc
							(start 0.2794 -0.1778)
							(mid 0.249642 -0.249642)
							(end 0.1778 -0.2794)
						)
					)
					(width 0)
					(fill yes)
				)
			)
		)
		(pad "2" smd custom
			(at 0 0.4445)
			(size 0.1397 0.1397)
			(layers "F.Cu" "F.Mask" "F.Paste")
			(net "GND")
			(options
				(clearance outline)
				(anchor circle)
			)
			(primitives
				(gr_poly
					(pts
						(arc
							(start -0.1778 -0.2794)
							(mid -0.249642 -0.249642)
							(end -0.2794 -0.1778)
						)
						(arc
							(start -0.2794 0.1778)
							(mid -0.249642 0.249642)
							(end -0.1778 0.2794)
						)
						(arc
							(start 0.1778 0.2794)
							(mid 0.249642 0.249642)
							(end 0.2794 0.1778)
						)
						(arc
							(start 0.2794 -0.1778)
							(mid 0.249642 -0.249642)
							(end 0.1778 -0.2794)
						)
					)
					(width 0)
					(fill yes)
				)
			)
		)
	)
	(footprint ""
		(layer "F.Cu")
		(at 33.655 -410.591)
		(property "Reference" "PR31"
			(at 0 0 0)
			(layer "F.SilkS")
			(hide yes)
			(effects
				(font
					(size 1.27 1.27)
				)
			)
		)
		(property "Value" "D0005RL1632F-GP-U"
			(at 3.2258 1.2954 0)
			(unlocked yes)
			(layer "F.Fab")
			(hide yes)
			(effects
				(font
					(size 1.016 1.016)
					(thickness 0.1524)
				)
			)
		)
		(property "Device Type" "RL3115-4PH45"
			(at 3.2258 -0.2286 0)
			(unlocked yes)
			(layer "F.Fab")
			(hide yes)
			(effects
				(font
					(size 1.016 1.016)
					(thickness 0.1524)
				)
			)
		)
		(duplicate_pad_numbers_are_jumpers no)
		(fp_line
			(start -2.0574 -1.7653)
			(end -2.0574 -0.4064)
			(stroke
				(width 0.3302)
				(type default)
			)
			(layer "F.SilkS")
		)
		(fp_line
			(start -1.9685 -1.651)
			(end 1.9685 -1.651)
			(stroke
				(width 0.1524)
				(type default)
			)
			(layer "F.SilkS")
		)
		(fp_line
			(start -1.9685 1.651)
			(end -1.9685 -1.651)
			(stroke
				(width 0.1524)
				(type default)
			)
			(layer "F.SilkS")
		)
		(fp_line
			(start -0.5334 -1.7653)
			(end -2.0574 -1.7653)
			(stroke
				(width 0.3302)
				(type default)
			)
			(layer "F.SilkS")
		)
		(fp_line
			(start 1.9685 -1.651)
			(end 1.9685 1.651)
			(stroke
				(width 0.1524)
				(type default)
			)
			(layer "F.SilkS")
		)
		(fp_line
			(start 1.9685 1.651)
			(end -1.9685 1.651)
			(stroke
				(width 0.1524)
				(type default)
			)
			(layer "F.SilkS")
		)
		(fp_poly
			(pts
				(xy -0.561594 -1.726946) (xy -0.053594 -2.234946) (xy -1.069594 -2.234946)
			)
			(stroke
				(width 0)
				(type default)
			)
			(fill yes)
			(layer "F.SilkS")
		)
		(fp_rect
			(start -1.524 0.7493)
			(end 1.524 -0.7493)
			(stroke
				(width 0)
				(type default)
			)
			(fill no)
			(layer "F.CrtYd")
		)
		(fp_poly
			(pts
				(xy -2.2225 1.905) (xy -2.2225 -1.905) (xy 2.2225 -1.905) (xy 2.2225 -0.7493) (xy -1.524 -0.7493)
				(xy -1.524 0.7493) (xy 1.524 0.7493) (xy 1.524 -0.7366) (xy 2.2225 -0.7366) (xy 2.2225 1.905)
			)
			(stroke
				(width 0)
				(type default)
			)
			(fill no)
			(layer "F.CrtYd")
		)
		(pad "1" smd rect
			(at -0.5715 -0.813562)
			(size 2.286 1.143)
			(layers "F.Cu" "F.Mask" "F.Paste")
			(net "P12V_AUX")
		)
		(pad "2" smd rect
			(at -0.5715 0.813562)
			(size 2.286 1.143)
			(layers "F.Cu" "F.Mask" "F.Paste")
			(net "P12V_SENSE_TRACE")
		)
		(pad "3" smd rect
			(at 1.334008 -0.813562)
			(size 0.762 1.143)
			(layers "F.Cu" "F.Mask" "F.Paste")
			(net "SENSE+_R3")
		)
		(pad "4" smd rect
			(at 1.334008 0.813562)
			(size 0.762 1.143)
			(layers "F.Cu" "F.Mask" "F.Paste")
			(net "SENSE-_R3")
		)
		(zone
			(layer "F.Cu")
			(hatch none 0.5)
			(connect_pads
				(clearance 0)
			)
			(min_thickness 0.25)
			(keepout
				(tracks allowed)
				(vias not_allowed)
				(pads allowed)
				(copperpour not_allowed)
				(footprints allowed)
			)
			(placement
				(enabled no)
				(sheetname "")
			)
			(fill
				(thermal_gap 0.5)
				(thermal_bridge_width 0.5)
				(island_removal_mode 0)
			)
			(polygon
				(pts
					(xy 34.2265 -410.833062) (xy 34.608008 -410.833062) (xy 34.608008 -411.3403) (xy 34.2265 -411.3403)
				)
			)
		)
		(zone
			(layer "F.Cu")
			(hatch none 0.5)
			(connect_pads
				(clearance 0)
			)
			(min_thickness 0.25)
			(keepout
				(tracks not_allowed)
				(vias allowed)
				(pads allowed)
				(copperpour not_allowed)
				(footprints allowed)
			)
			(placement
				(enabled no)
				(sheetname "")
			)
			(fill
				(thermal_gap 0.5)
				(thermal_bridge_width 0.5)
				(island_removal_mode 0)
			)
			(polygon
				(pts
					(xy 34.2265 -410.833062) (xy 34.608008 -410.833062) (xy 34.608008 -411.3403) (xy 34.2265 -411.3403)
				)
			)
		)
		(zone
			(layer "F.Cu")
			(hatch none 0.5)
			(connect_pads
				(clearance 0)
			)
			(min_thickness 0.25)
			(keepout
				(tracks not_allowed)
				(vias allowed)
				(pads allowed)
				(copperpour not_allowed)
				(footprints allowed)
			)
			(placement
				(enabled no)
				(sheetname "")
			)
			(fill
				(thermal_gap 0.5)
				(thermal_bridge_width 0.5)
				(island_removal_mode 0)
			)
			(polygon
				(pts
					(xy 34.2265 -409.8417) (xy 34.608008 -409.8417) (xy 34.608008 -410.348938) (xy 34.2265 -410.348938)
				)
			)
		)
		(zone
			(layer "F.Cu")
			(hatch none 0.5)
			(connect_pads
				(clearance 0)
			)
			(min_thickness 0.25)
			(keepout
				(tracks allowed)
				(vias not_allowed)
				(pads allowed)
				(copperpour not_allowed)
				(footprints allowed)
			)
			(placement
				(enabled no)
				(sheetname "")
			)
			(fill
				(thermal_gap 0.5)
				(thermal_bridge_width 0.5)
				(island_removal_mode 0)
			)
			(polygon
				(pts
					(xy 34.2265 -409.8417) (xy 34.608008 -409.8417) (xy 34.608008 -410.348938) (xy 34.2265 -410.348938)
				)
			)
		)
	)
	(footprint ""
		(layer "F.Cu")
		(at 24.257 -371.475 180)
		(property "Reference" "PR36"
			(at 0 0 180)
			(layer "F.SilkS")
			(hide yes)
			(effects
				(font
					(size 1.27 1.27)
				)
			)
		)
		(property "Value" "4K02R2F-GP"
			(at 0.064008 -3.993896 180)
			(unlocked yes)
			(layer "F.Fab")
			(hide yes)
			(effects
				(font
					(size 1.016 1.016)
					(thickness 0.1524)
				)
			)
		)
		(property "Device Type" "R402H16"
			(at 0.064008 -5.517896 180)
			(unlocked yes)
			(layer "F.Fab")
			(hide yes)
			(effects
				(font
					(size 1.016 1.016)
					(thickness 0.1524)
				)
			)
		)
		(duplicate_pad_numbers_are_jumpers no)
		(fp_line
			(start 0.508 -0.9398)
			(end -0.508 -0.9398)
			(stroke
				(width 0.1524)
				(type default)
			)
			(layer "F.SilkS")
		)
		(fp_line
			(start -0.508 -0.9398)
			(end -0.508 0.9398)
			(stroke
				(width 0.1524)
				(type default)
			)
			(layer "F.SilkS")
		)
		(fp_rect
			(start -0.508 0.9398)
			(end 0.508 -0.9398)
			(stroke
				(width 0)
				(type default)
			)
			(fill no)
			(layer "F.CrtYd")
		)
		(fp_rect
			(start -0.508 0.9398)
			(end 0.508 -0.9398)
			(stroke
				(width 0)
				(type default)
			)
			(fill no)
			(layer "F.Fab")
		)
		(pad "1" smd custom
			(at 0 -0.4445 180)
			(size 0.1397 0.1397)
			(layers "F.Cu" "F.Mask" "F.Paste")
			(net "ADM1276_OV")
			(options
				(clearance outline)
				(anchor circle)
			)
			(primitives
				(gr_poly
					(pts
						(arc
							(start -0.1778 -0.2794)
							(mid -0.249642 -0.249642)
							(end -0.2794 -0.1778)
						)
						(arc
							(start -0.2794 0.1778)
							(mid -0.249642 0.249642)
							(end -0.1778 0.2794)
						)
						(arc
							(start 0.1778 0.2794)
							(mid 0.249642 0.249642)
							(end 0.2794 0.1778)
						)
						(arc
							(start 0.2794 -0.1778)
							(mid 0.249642 -0.249642)
							(end 0.1778 -0.2794)
						)
					)
					(width 0)
					(fill yes)
				)
			)
		)
		(pad "2" smd custom
			(at 0 0.4445 180)
			(size 0.1397 0.1397)
			(layers "F.Cu" "F.Mask" "F.Paste")
			(net "GND")
			(options
				(clearance outline)
				(anchor circle)
			)
			(primitives
				(gr_poly
					(pts
						(arc
							(start -0.1778 -0.2794)
							(mid -0.249642 -0.249642)
							(end -0.2794 -0.1778)
						)
						(arc
							(start -0.2794 0.1778)
							(mid -0.249642 0.249642)
							(end -0.1778 0.2794)
						)
						(arc
							(start 0.1778 0.2794)
							(mid 0.249642 0.249642)
							(end 0.2794 0.1778)
						)
						(arc
							(start 0.2794 -0.1778)
							(mid 0.249642 -0.249642)
							(end 0.1778 -0.2794)
						)
					)
					(width 0)
					(fill yes)
				)
			)
		)
	)
	(footprint ""
		(layer "F.Cu")
		(at 34.544 -400.177)
		(property "Reference" "PQ2"
			(at 0 0 0)
			(layer "F.SilkS")
			(hide yes)
			(effects
				(font
					(size 1.27 1.27)
				)
			)
		)
		(property "Value" "PH0925CL-GP"
			(at -4.2799 -0.4572 0)
			(unlocked yes)
			(layer "F.Fab")
			(hide yes)
			(effects
				(font
					(size 1.016 1.016)
					(thickness 0.1524)
				)
			)
		)
		(property "Device Type" "LFPAK-5PH48-U"
			(at -4.2799 -1.9812 0)
			(unlocked yes)
			(layer "F.Fab")
			(hide yes)
			(effects
				(font
					(size 1.016 1.016)
					(thickness 0.1524)
				)
			)
		)
		(duplicate_pad_numbers_are_jumpers no)
		(fp_line
			(start -2.7559 -6.5532)
			(end -2.7559 1.0668)
			(stroke
				(width 0.1524)
				(type default)
			)
			(layer "F.SilkS")
		)
		(fp_line
			(start -2.7559 1.0668)
			(end 2.7559 1.0668)
			(stroke
				(width 0.1524)
				(type default)
			)
			(layer "F.SilkS")
		)
		(fp_line
			(start -1.7272 1.1684)
			(end -2.1082 1.1684)
			(stroke
				(width 0.3302)
				(type default)
			)
			(layer "F.SilkS")
		)
		(fp_line
			(start 2.7559 -6.5532)
			(end -2.7559 -6.5532)
			(stroke
				(width 0.1524)
				(type default)
			)
			(layer "F.SilkS")
		)
		(fp_line
			(start 2.7559 1.0668)
			(end 2.7559 -6.5532)
			(stroke
				(width 0.1524)
				(type default)
			)
			(layer "F.SilkS")
		)
		(fp_poly
			(pts
				(xy -2.3368 1.5748) (xy -1.905 1.143) (xy -1.4732 1.5748)
			)
			(stroke
				(width 0)
				(type default)
			)
			(fill yes)
			(layer "F.SilkS")
		)
		(fp_poly
			(pts
				(xy -2.5019 -4.02971) (xy -0.3302 -4.02971) (xy -0.3302 -6.30301) (xy -2.5019 -6.30301)
			)
			(stroke
				(width 0)
				(type default)
			)
			(fill yes)
			(layer "F.Paste")
		)
		(fp_poly
			(pts
				(xy -2.5019 -1.09601) (xy -0.3302 -1.09601) (xy -0.3302 -3.36931) (xy -2.5019 -3.36931)
			)
			(stroke
				(width 0)
				(type default)
			)
			(fill yes)
			(layer "F.Paste")
		)
		(fp_poly
			(pts
				(xy 0.3302 -4.02971) (xy 2.5019 -4.02971) (xy 2.5019 -6.30301) (xy 0.3302 -6.30301)
			)
			(stroke
				(width 0)
				(type default)
			)
			(fill yes)
			(layer "F.Paste")
		)
		(fp_poly
			(pts
				(xy 0.3302 -1.09601) (xy 2.5019 -1.09601) (xy 2.5019 -3.36931) (xy 0.3302 -3.36931)
			)
			(stroke
				(width 0)
				(type default)
			)
			(fill yes)
			(layer "F.Paste")
		)
		(fp_rect
			(start -2.4511 0.3048)
			(end 2.4511 -5.6896)
			(stroke
				(width 0)
				(type default)
			)
			(fill no)
			(layer "F.CrtYd")
		)
		(fp_poly
			(pts
				(xy -3.0099 1.3208) (xy -3.0099 -6.8072) (xy 3.0099 -6.8072) (xy 3.0099 -1.016) (xy 2.4511 -1.016)
				(xy 2.4511 -5.6896) (xy -2.4511 -5.6896) (xy -2.4511 0.3048) (xy 2.4511 0.3048) (xy 2.4511 -1.0033)
				(xy 3.0099 -1.0033) (xy 3.0099 1.3208)
			)
			(stroke
				(width 0)
				(type default)
			)
			(fill no)
			(layer "F.CrtYd")
		)
		(fp_rect
			(start -3.0099 1.3208)
			(end 3.0099 -6.8072)
			(stroke
				(width 0)
				(type default)
			)
			(fill no)
			(layer "F.Fab")
		)
		(pad "1" smd rect
			(at -1.905 0)
			(size 0.762 1.6256)
			(layers "F.Cu" "F.Mask" "F.Paste")
			(net "P12V")
		)
		(pad "2" smd rect
			(at -0.635 0)
			(size 0.762 1.6256)
			(layers "F.Cu" "F.Mask" "F.Paste")
			(net "P12V")
		)
		(pad "3" smd rect
			(at 0.635 0)
			(size 0.762 1.6256)
			(layers "F.Cu" "F.Mask" "F.Paste")
			(net "P12V")
		)
		(pad "4" smd rect
			(at 1.905 0)
			(size 0.762 1.6256)
			(layers "F.Cu" "F.Mask" "F.Paste")
			(net "ADM1276_GATE_DRV2")
		)
		(pad "5" smd rect
			(at 0 -3.69951)
			(size 5.0038 5.207)
			(layers "F.Cu" "F.Mask" "F.Paste")
			(net "P12V_SENSE_TRACE")
		)
	)
	(footprint ""
		(layer "F.Cu")
		(at 34.544 -240.3094 180)
		(property "Reference" "R55"
			(at 0 0 180)
			(layer "F.SilkS")
			(hide yes)
			(effects
				(font
					(size 1.27 1.27)
				)
			)
		)
		(property "Value" "4K7R2J-2-GP"
			(at 0.064008 -3.993896 180)
			(unlocked yes)
			(layer "F.Fab")
			(hide yes)
			(effects
				(font
					(size 1.016 1.016)
					(thickness 0.1524)
				)
			)
		)
		(property "Device Type" "R402H16"
			(at 0.064008 -5.517896 180)
			(unlocked yes)
			(layer "F.Fab")
			(hide yes)
			(effects
				(font
					(size 1.016 1.016)
					(thickness 0.1524)
				)
			)
		)
		(duplicate_pad_numbers_are_jumpers no)
		(fp_line
			(start 0.508 -0.9398)
			(end -0.508 -0.9398)
			(stroke
				(width 0.1524)
				(type default)
			)
			(layer "F.SilkS")
		)
		(fp_line
			(start -0.508 -0.9398)
			(end -0.508 0.9398)
			(stroke
				(width 0.1524)
				(type default)
			)
			(layer "F.SilkS")
		)
		(fp_rect
			(start -0.508 0.9398)
			(end 0.508 -0.9398)
			(stroke
				(width 0)
				(type default)
			)
			(fill no)
			(layer "F.CrtYd")
		)
		(fp_rect
			(start -0.508 0.9398)
			(end 0.508 -0.9398)
			(stroke
				(width 0)
				(type default)
			)
			(fill no)
			(layer "F.Fab")
		)
		(pad "1" smd custom
			(at 0 -0.4445 180)
			(size 0.1397 0.1397)
			(layers "F.Cu" "F.Mask" "F.Paste")
			(net "GND")
			(options
				(clearance outline)
				(anchor circle)
			)
			(primitives
				(gr_poly
					(pts
						(arc
							(start -0.1778 -0.2794)
							(mid -0.249642 -0.249642)
							(end -0.2794 -0.1778)
						)
						(arc
							(start -0.2794 0.1778)
							(mid -0.249642 0.249642)
							(end -0.1778 0.2794)
						)
						(arc
							(start 0.1778 0.2794)
							(mid 0.249642 0.249642)
							(end 0.2794 0.1778)
						)
						(arc
							(start 0.2794 -0.1778)
							(mid 0.249642 -0.249642)
							(end 0.1778 -0.2794)
						)
					)
					(width 0)
					(fill yes)
				)
			)
		)
		(pad "2" smd custom
			(at 0 0.4445 180)
			(size 0.1397 0.1397)
			(layers "F.Cu" "F.Mask" "F.Paste")
			(net "LED_DRV_A1")
			(options
				(clearance outline)
				(anchor circle)
			)
			(primitives
				(gr_poly
					(pts
						(arc
							(start -0.1778 -0.2794)
							(mid -0.249642 -0.249642)
							(end -0.2794 -0.1778)
						)
						(arc
							(start -0.2794 0.1778)
							(mid -0.249642 0.249642)
							(end -0.1778 0.2794)
						)
						(arc
							(start 0.1778 0.2794)
							(mid 0.249642 0.249642)
							(end 0.2794 0.1778)
						)
						(arc
							(start 0.2794 -0.1778)
							(mid 0.249642 -0.249642)
							(end 0.1778 -0.2794)
						)
					)
					(width 0)
					(fill yes)
				)
			)
		)
	)
	(footprint ""
		(layer "F.Cu")
		(at 8.9662 -101.0412 -90)
		(property "Reference" "TC1"
			(at 0 0 270)
			(layer "F.SilkS")
			(hide yes)
			(effects
				(font
					(size 1.27 1.27)
				)
			)
		)
		(property "Value" "ST68U16VDM-1-GP"
			(at 0 -9.6012 270)
			(unlocked yes)
			(layer "F.Fab")
			(hide yes)
			(effects
				(font
					(size 1.016 1.016)
					(thickness 0.1524)
				)
			)
		)
		(property "Device Type" "CT7343H79"
			(at 0 -11.1252 270)
			(unlocked yes)
			(layer "F.Fab")
			(hide yes)
			(effects
				(font
					(size 1.016 1.016)
					(thickness 0.1524)
				)
			)
		)
		(duplicate_pad_numbers_are_jumpers no)
		(fp_line
			(start -2.286 4.8768)
			(end -2.286 2.032)
			(stroke
				(width 0.1524)
				(type default)
			)
			(layer "F.SilkS")
		)
		(fp_line
			(start 2.286 4.8768)
			(end -2.286 4.8768)
			(stroke
				(width 0.1524)
				(type default)
			)
			(layer "F.SilkS")
		)
		(fp_line
			(start 2.286 2.032)
			(end 2.286 4.8768)
			(stroke
				(width 0.1524)
				(type default)
			)
			(layer "F.SilkS")
		)
		(fp_line
			(start 2.286 -2.032)
			(end 2.286 -4.8768)
			(stroke
				(width 0.1524)
				(type default)
			)
			(layer "F.SilkS")
		)
		(fp_line
			(start 2.1082 -4.699)
			(end -2.1082 -4.699)
			(stroke
				(width 0.508)
				(type default)
			)
			(layer "F.SilkS")
		)
		(fp_line
			(start -2.286 -4.8768)
			(end -2.286 -2.032)
			(stroke
				(width 0.1524)
				(type default)
			)
			(layer "F.SilkS")
		)
		(fp_line
			(start 2.286 -4.8768)
			(end -2.286 -4.8768)
			(stroke
				(width 0.1524)
				(type default)
			)
			(layer "F.SilkS")
		)
		(fp_rect
			(start -2.1463 3.6449)
			(end 2.1463 -3.6449)
			(stroke
				(width 0)
				(type default)
			)
			(fill no)
			(layer "F.CrtYd")
		)
		(fp_poly
			(pts
				(xy -2.54 4.953) (xy -2.54 4.2926) (xy -3.81 4.2926) (xy -3.81 -4.2926) (xy -2.54 -4.2926) (xy -2.54 -4.953)
				(xy 2.54 -4.953) (xy 2.54 -4.2926) (xy 3.81 -4.2926) (xy 3.81 -1.6256) (xy 2.1463 -1.6256) (xy 2.1463 -3.6449)
				(xy -2.1463 -3.6449) (xy -2.1463 3.6449) (xy 2.1463 3.6449) (xy 2.1463 -1.6129) (xy 3.81 -1.6129)
				(xy 3.81 4.2926) (xy 2.54 4.2926) (xy 2.54 4.953)
			)
			(stroke
				(width 0)
				(type default)
			)
			(fill no)
			(layer "F.CrtYd")
		)
		(fp_rect
			(start -2.54 4.953)
			(end 2.54 -4.953)
			(stroke
				(width 0)
				(type default)
			)
			(fill no)
			(layer "F.Fab")
		)
		(fp_rect
			(start -3.81 4.2926)
			(end -2.54 -4.2926)
			(stroke
				(width 0)
				(type default)
			)
			(fill no)
			(layer "F.Fab")
		)
		(fp_rect
			(start 2.54 4.2926)
			(end 3.81 -4.2926)
			(stroke
				(width 0)
				(type default)
			)
			(fill no)
			(layer "F.Fab")
		)
		(pad "1" smd rect
			(at 0 -3.1496 270)
			(size 2.413 2.286)
			(layers "F.Cu" "F.Mask" "F.Paste")
			(net "P12VU")
		)
		(pad "2" smd rect
			(at 0 3.1496 270)
			(size 2.413 2.286)
			(layers "F.Cu" "F.Mask" "F.Paste")
			(net "GND")
		)
		(zone
			(layer "F.Cu")
			(hatch none 0.5)
			(connect_pads
				(clearance 0)
			)
			(min_thickness 0.25)
			(keepout
				(tracks allowed)
				(vias not_allowed)
				(pads allowed)
				(copperpour not_allowed)
				(footprints allowed)
			)
			(placement
				(enabled no)
				(sheetname "")
			)
			(fill
				(thermal_gap 0.5)
				(thermal_bridge_width 0.5)
				(island_removal_mode 0)
			)
			(polygon
				(pts
					(xy 4.3688 -102.5525) (xy 4.3688 -99.5299) (xy 7.2644 -99.5299) (xy 7.5946 -99.5299) (xy 7.5946 -102.5525)
					(xy 7.2644 -102.5525)
				)
			)
		)
		(zone
			(layer "F.Cu")
			(hatch none 0.5)
			(connect_pads
				(clearance 0)
			)
			(min_thickness 0.25)
			(keepout
				(tracks allowed)
				(vias not_allowed)
				(pads allowed)
				(copperpour not_allowed)
				(footprints allowed)
			)
			(placement
				(enabled no)
				(sheetname "")
			)
			(fill
				(thermal_gap 0.5)
				(thermal_bridge_width 0.5)
				(island_removal_mode 0)
			)
			(polygon
				(pts
					(xy 10.6553 -99.5299) (xy 13.5636 -99.5299) (xy 13.5636 -102.5525) (xy 10.668 -102.5525) (xy 10.3378 -102.5525)
					(xy 10.3378 -99.5299)
				)
			)
		)
	)
	(footprint ""
		(layer "F.Cu")
		(at 38.227 -178.054 180)
		(property "Reference" "C254"
			(at 0 0 180)
			(layer "F.SilkS")
			(hide yes)
			(effects
				(font
					(size 1.27 1.27)
				)
			)
		)
		(property "Value" "SCD1U16V2KX-3GP"
			(at 1.1811 -2.7051 180)
			(unlocked yes)
			(layer "F.Fab")
			(hide yes)
			(effects
				(font
					(size 1.016 1.016)
					(thickness 0.1524)
				)
			)
		)
		(property "Device Type" "C402H22"
			(at 1.1811 -4.2291 180)
			(unlocked yes)
			(layer "F.Fab")
			(hide yes)
			(effects
				(font
					(size 1.016 1.016)
					(thickness 0.1524)
				)
			)
		)
		(duplicate_pad_numbers_are_jumpers no)
		(fp_rect
			(start -0.4318 0.9525)
			(end 0.4318 -0.9525)
			(stroke
				(width 0)
				(type default)
			)
			(fill no)
			(layer "F.CrtYd")
		)
		(fp_rect
			(start -0.4318 0.9525)
			(end 0.4318 -0.9525)
			(stroke
				(width 0)
				(type default)
			)
			(fill no)
			(layer "F.Fab")
		)
		(pad "1" smd custom
			(at 0 -0.4445 180)
			(size 0.1524 0.1524)
			(layers "F.Cu" "F.Mask" "F.Paste")
			(net "P3V3_AUX")
			(options
				(clearance outline)
				(anchor circle)
			)
			(primitives
				(gr_poly
					(pts
						(arc
							(start 0.3048 -0.2032)
							(mid 0.275042 -0.275042)
							(end 0.2032 -0.3048)
						)
						(arc
							(start -0.2032 -0.3048)
							(mid -0.275042 -0.275042)
							(end -0.3048 -0.2032)
						)
						(arc
							(start -0.3048 0.2032)
							(mid -0.275042 0.275042)
							(end -0.2032 0.3048)
						)
						(arc
							(start 0.2032 0.3048)
							(mid 0.275042 0.275042)
							(end 0.3048 0.2032)
						)
					)
					(width 0)
					(fill yes)
				)
			)
		)
		(pad "2" smd custom
			(at 0 0.4445 180)
			(size 0.1524 0.1524)
			(layers "F.Cu" "F.Mask" "F.Paste")
			(net "GND")
			(options
				(clearance outline)
				(anchor circle)
			)
			(primitives
				(gr_poly
					(pts
						(arc
							(start 0.3048 -0.2032)
							(mid 0.275042 -0.275042)
							(end 0.2032 -0.3048)
						)
						(arc
							(start -0.2032 -0.3048)
							(mid -0.275042 -0.275042)
							(end -0.3048 -0.2032)
						)
						(arc
							(start -0.3048 0.2032)
							(mid -0.275042 0.275042)
							(end -0.2032 0.3048)
						)
						(arc
							(start 0.2032 0.3048)
							(mid 0.275042 0.275042)
							(end 0.3048 0.2032)
						)
					)
					(width 0)
					(fill yes)
				)
			)
		)
	)
	(footprint ""
		(layer "F.Cu")
		(at 24.1808 -168.656)
		(property "Reference" "R20"
			(at 0 0 0)
			(layer "F.SilkS")
			(hide yes)
			(effects
				(font
					(size 1.27 1.27)
				)
			)
		)
		(property "Value" "4K7R2F-GP"
			(at 0.064008 -3.993896 0)
			(unlocked yes)
			(layer "F.Fab")
			(hide yes)
			(effects
				(font
					(size 1.016 1.016)
					(thickness 0.1524)
				)
			)
		)
		(property "Device Type" "R402H16"
			(at 0.064008 -5.517896 0)
			(unlocked yes)
			(layer "F.Fab")
			(hide yes)
			(effects
				(font
					(size 1.016 1.016)
					(thickness 0.1524)
				)
			)
		)
		(duplicate_pad_numbers_are_jumpers no)
		(fp_line
			(start -0.508 -0.9398)
			(end -0.508 0.9398)
			(stroke
				(width 0.1524)
				(type default)
			)
			(layer "F.SilkS")
		)
		(fp_line
			(start 0.508 -0.9398)
			(end -0.508 -0.9398)
			(stroke
				(width 0.1524)
				(type default)
			)
			(layer "F.SilkS")
		)
		(fp_rect
			(start -0.508 0.9398)
			(end 0.508 -0.9398)
			(stroke
				(width 0)
				(type default)
			)
			(fill no)
			(layer "F.CrtYd")
		)
		(fp_rect
			(start -0.508 0.9398)
			(end 0.508 -0.9398)
			(stroke
				(width 0)
				(type default)
			)
			(fill no)
			(layer "F.Fab")
		)
		(pad "1" smd custom
			(at 0 -0.4445)
			(size 0.1397 0.1397)
			(layers "F.Cu" "F.Mask" "F.Paste")
			(net "P3V3")
			(options
				(clearance outline)
				(anchor circle)
			)
			(primitives
				(gr_poly
					(pts
						(arc
							(start -0.1778 -0.2794)
							(mid -0.249642 -0.249642)
							(end -0.2794 -0.1778)
						)
						(arc
							(start -0.2794 0.1778)
							(mid -0.249642 0.249642)
							(end -0.1778 0.2794)
						)
						(arc
							(start 0.1778 0.2794)
							(mid 0.249642 0.249642)
							(end 0.2794 0.1778)
						)
						(arc
							(start 0.2794 -0.1778)
							(mid 0.249642 -0.249642)
							(end 0.1778 -0.2794)
						)
					)
					(width 0)
					(fill yes)
				)
			)
		)
		(pad "2" smd custom
			(at 0 0.4445)
			(size 0.1397 0.1397)
			(layers "F.Cu" "F.Mask" "F.Paste")
			(net "PWM_BUFFER_IN_FAN5_FAN6")
			(options
				(clearance outline)
				(anchor circle)
			)
			(primitives
				(gr_poly
					(pts
						(arc
							(start -0.1778 -0.2794)
							(mid -0.249642 -0.249642)
							(end -0.2794 -0.1778)
						)
						(arc
							(start -0.2794 0.1778)
							(mid -0.249642 0.249642)
							(end -0.1778 0.2794)
						)
						(arc
							(start 0.1778 0.2794)
							(mid 0.249642 0.249642)
							(end 0.2794 0.1778)
						)
						(arc
							(start 0.2794 -0.1778)
							(mid 0.249642 -0.249642)
							(end 0.1778 -0.2794)
						)
					)
					(width 0)
					(fill yes)
				)
			)
		)
	)
	(footprint ""
		(layer "F.Cu")
		(at 16.51 -148.336 -90)
		(property "Reference" "D4"
			(at 0 0 270)
			(layer "F.SilkS")
			(hide yes)
			(effects
				(font
					(size 1.27 1.27)
				)
			)
		)
		(property "Value" "BAS16H-GP"
			(at 0 -5.5372 270)
			(unlocked yes)
			(layer "F.Fab")
			(hide yes)
			(effects
				(font
					(size 1.016 1.016)
					(thickness 0.1524)
				)
			)
		)
		(property "Device Type" "SOD123AKH48"
			(at 0 -7.0612 270)
			(unlocked yes)
			(layer "F.Fab")
			(hide yes)
			(effects
				(font
					(size 1.016 1.016)
					(thickness 0.1524)
				)
			)
		)
		(duplicate_pad_numbers_are_jumpers no)
		(fp_line
			(start 0.889 2.921)
			(end -0.889 2.921)
			(stroke
				(width 0.508)
				(type default)
			)
			(layer "F.SilkS")
		)
		(fp_line
			(start -1.016 2.667)
			(end 1.016 2.667)
			(stroke
				(width 0.1524)
				(type default)
			)
			(layer "F.SilkS")
		)
		(fp_line
			(start 1.016 2.667)
			(end 1.016 -2.667)
			(stroke
				(width 0.1524)
				(type default)
			)
			(layer "F.SilkS")
		)
		(fp_line
			(start -1.016 -2.667)
			(end -1.016 2.667)
			(stroke
				(width 0.1524)
				(type default)
			)
			(layer "F.SilkS")
		)
		(fp_line
			(start 1.016 -2.667)
			(end -1.016 -2.667)
			(stroke
				(width 0.1524)
				(type default)
			)
			(layer "F.SilkS")
		)
		(fp_rect
			(start -1.143 3.175)
			(end 1.143 -2.794)
			(stroke
				(width 0)
				(type default)
			)
			(fill no)
			(layer "F.CrtYd")
		)
		(fp_poly
			(pts
				(xy -1.143 -2.794) (xy 1.143 -2.794) (xy 1.143 3.175) (xy -1.143 3.175)
			)
			(stroke
				(width 0)
				(type default)
			)
			(fill no)
			(layer "F.Fab")
		)
		(pad "A" smd rect
			(at 0 -1.6891 270)
			(size 0.889 1.397)
			(layers "F.Cu" "F.Mask" "F.Paste")
			(net "FAN_TACH9")
		)
		(pad "K" smd rect
			(at 0 1.6891 270)
			(size 0.889 1.397)
			(layers "F.Cu" "F.Mask" "F.Paste")
			(net "P12V")
		)
	)
	(footprint ""
		(layer "F.Cu")
		(at 36.63569 -165.513766 180)
		(property "Reference" "R1"
			(at 0 0 180)
			(layer "F.SilkS")
			(hide yes)
			(effects
				(font
					(size 1.27 1.27)
				)
			)
		)
		(property "Value" "0R2J-2-GP"
			(at 0.064008 -3.993896 180)
			(unlocked yes)
			(layer "F.Fab")
			(hide yes)
			(effects
				(font
					(size 1.016 1.016)
					(thickness 0.1524)
				)
			)
		)
		(property "Device Type" "R402H16"
			(at 0.064008 -5.517896 180)
			(unlocked yes)
			(layer "F.Fab")
			(hide yes)
			(effects
				(font
					(size 1.016 1.016)
					(thickness 0.1524)
				)
			)
		)
		(duplicate_pad_numbers_are_jumpers no)
		(fp_line
			(start 0.508 -0.9398)
			(end -0.508 -0.9398)
			(stroke
				(width 0.1524)
				(type default)
			)
			(layer "F.SilkS")
		)
		(fp_line
			(start -0.508 -0.9398)
			(end -0.508 0.9398)
			(stroke
				(width 0.1524)
				(type default)
			)
			(layer "F.SilkS")
		)
		(fp_rect
			(start -0.508 0.9398)
			(end 0.508 -0.9398)
			(stroke
				(width 0)
				(type default)
			)
			(fill no)
			(layer "F.CrtYd")
		)
		(fp_rect
			(start -0.508 0.9398)
			(end 0.508 -0.9398)
			(stroke
				(width 0)
				(type default)
			)
			(fill no)
			(layer "F.Fab")
		)
		(pad "1" smd custom
			(at 0 -0.4445 180)
			(size 0.1397 0.1397)
			(layers "F.Cu" "F.Mask" "F.Paste")
			(net "I2C_C_SDA_NCT7904")
			(options
				(clearance outline)
				(anchor circle)
			)
			(primitives
				(gr_poly
					(pts
						(arc
							(start -0.1778 -0.2794)
							(mid -0.249642 -0.249642)
							(end -0.2794 -0.1778)
						)
						(arc
							(start -0.2794 0.1778)
							(mid -0.249642 0.249642)
							(end -0.1778 0.2794)
						)
						(arc
							(start 0.1778 0.2794)
							(mid 0.249642 0.249642)
							(end 0.2794 0.1778)
						)
						(arc
							(start 0.2794 -0.1778)
							(mid 0.249642 -0.249642)
							(end 0.1778 -0.2794)
						)
					)
					(width 0)
					(fill yes)
				)
			)
		)
		(pad "2" smd custom
			(at 0 0.4445 180)
			(size 0.1397 0.1397)
			(layers "F.Cu" "F.Mask" "F.Paste")
			(net "I2C_C_SDA")
			(options
				(clearance outline)
				(anchor circle)
			)
			(primitives
				(gr_poly
					(pts
						(arc
							(start -0.1778 -0.2794)
							(mid -0.249642 -0.249642)
							(end -0.2794 -0.1778)
						)
						(arc
							(start -0.2794 0.1778)
							(mid -0.249642 0.249642)
							(end -0.1778 0.2794)
						)
						(arc
							(start 0.1778 0.2794)
							(mid 0.249642 0.249642)
							(end 0.2794 0.1778)
						)
						(arc
							(start 0.2794 -0.1778)
							(mid 0.249642 -0.249642)
							(end 0.1778 -0.2794)
						)
					)
					(width 0)
					(fill yes)
				)
			)
		)
	)
	(footprint ""
		(layer "F.Cu")
		(at 40.132 -146.5326)
		(property "Reference" "PR109"
			(at 0 0 0)
			(layer "F.SilkS")
			(hide yes)
			(effects
				(font
					(size 1.27 1.27)
				)
			)
		)
		(property "Value" "6K81R2F-1-GP"
			(at 0.064008 -3.993896 0)
			(unlocked yes)
			(layer "F.Fab")
			(hide yes)
			(effects
				(font
					(size 1.016 1.016)
					(thickness 0.1524)
				)
			)
		)
		(property "Device Type" "R402H16"
			(at 0.064008 -5.517896 0)
			(unlocked yes)
			(layer "F.Fab")
			(hide yes)
			(effects
				(font
					(size 1.016 1.016)
					(thickness 0.1524)
				)
			)
		)
		(duplicate_pad_numbers_are_jumpers no)
		(fp_line
			(start -0.508 -0.9398)
			(end -0.508 0.9398)
			(stroke
				(width 0.1524)
				(type default)
			)
			(layer "F.SilkS")
		)
		(fp_line
			(start 0.508 -0.9398)
			(end -0.508 -0.9398)
			(stroke
				(width 0.1524)
				(type default)
			)
			(layer "F.SilkS")
		)
		(fp_rect
			(start -0.508 0.9398)
			(end 0.508 -0.9398)
			(stroke
				(width 0)
				(type default)
			)
			(fill no)
			(layer "F.CrtYd")
		)
		(fp_rect
			(start -0.508 0.9398)
			(end 0.508 -0.9398)
			(stroke
				(width 0)
				(type default)
			)
			(fill no)
			(layer "F.Fab")
		)
		(pad "1" smd custom
			(at 0 -0.4445)
			(size 0.1397 0.1397)
			(layers "F.Cu" "F.Mask" "F.Paste")
			(net "P12V")
			(options
				(clearance outline)
				(anchor circle)
			)
			(primitives
				(gr_poly
					(pts
						(arc
							(start -0.1778 -0.2794)
							(mid -0.249642 -0.249642)
							(end -0.2794 -0.1778)
						)
						(arc
							(start -0.2794 0.1778)
							(mid -0.249642 0.249642)
							(end -0.1778 0.2794)
						)
						(arc
							(start 0.1778 0.2794)
							(mid 0.249642 0.249642)
							(end 0.2794 0.1778)
						)
						(arc
							(start 0.2794 -0.1778)
							(mid 0.249642 -0.249642)
							(end 0.1778 -0.2794)
						)
					)
					(width 0)
					(fill yes)
				)
			)
		)
		(pad "2" smd custom
			(at 0 0.4445)
			(size 0.1397 0.1397)
			(layers "F.Cu" "F.Mask" "F.Paste")
			(net "P12VL_2490_EN_1")
			(options
				(clearance outline)
				(anchor circle)
			)
			(primitives
				(gr_poly
					(pts
						(arc
							(start -0.1778 -0.2794)
							(mid -0.249642 -0.249642)
							(end -0.2794 -0.1778)
						)
						(arc
							(start -0.2794 0.1778)
							(mid -0.249642 0.249642)
							(end -0.1778 0.2794)
						)
						(arc
							(start 0.1778 0.2794)
							(mid 0.249642 0.249642)
							(end 0.2794 0.1778)
						)
						(arc
							(start 0.2794 -0.1778)
							(mid 0.249642 -0.249642)
							(end 0.1778 -0.2794)
						)
					)
					(width 0)
					(fill yes)
				)
			)
		)
	)
	(footprint ""
		(layer "F.Cu")
		(at 9.3218 -454.2028 -90)
		(property "Reference" "R96"
			(at 0 0 270)
			(layer "F.SilkS")
			(hide yes)
			(effects
				(font
					(size 1.27 1.27)
				)
			)
		)
		(property "Value" "4K7R2F-GP"
			(at 0.064008 -3.993896 270)
			(unlocked yes)
			(layer "F.Fab")
			(hide yes)
			(effects
				(font
					(size 1.016 1.016)
					(thickness 0.1524)
				)
			)
		)
		(property "Device Type" "R402H16"
			(at 0.064008 -5.517896 270)
			(unlocked yes)
			(layer "F.Fab")
			(hide yes)
			(effects
				(font
					(size 1.016 1.016)
					(thickness 0.1524)
				)
			)
		)
		(duplicate_pad_numbers_are_jumpers no)
		(fp_line
			(start -0.508 -0.9398)
			(end -0.508 0.9398)
			(stroke
				(width 0.1524)
				(type default)
			)
			(layer "F.SilkS")
		)
		(fp_line
			(start 0.508 -0.9398)
			(end -0.508 -0.9398)
			(stroke
				(width 0.1524)
				(type default)
			)
			(layer "F.SilkS")
		)
		(fp_rect
			(start -0.508 0.9398)
			(end 0.508 -0.9398)
			(stroke
				(width 0)
				(type default)
			)
			(fill no)
			(layer "F.CrtYd")
		)
		(fp_rect
			(start -0.508 0.9398)
			(end 0.508 -0.9398)
			(stroke
				(width 0)
				(type default)
			)
			(fill no)
			(layer "F.Fab")
		)
		(pad "1" smd custom
			(at 0 -0.4445 270)
			(size 0.1397 0.1397)
			(layers "F.Cu" "F.Mask" "F.Paste")
			(net "P12V")
			(options
				(clearance outline)
				(anchor circle)
			)
			(primitives
				(gr_poly
					(pts
						(arc
							(start -0.1778 -0.2794)
							(mid -0.249642 -0.249642)
							(end -0.2794 -0.1778)
						)
						(arc
							(start -0.2794 0.1778)
							(mid -0.249642 0.249642)
							(end -0.1778 0.2794)
						)
						(arc
							(start 0.1778 0.2794)
							(mid 0.249642 0.249642)
							(end 0.2794 0.1778)
						)
						(arc
							(start 0.2794 -0.1778)
							(mid 0.249642 -0.249642)
							(end 0.1778 -0.2794)
						)
					)
					(width 0)
					(fill yes)
				)
			)
		)
		(pad "2" smd custom
			(at 0 0.4445 270)
			(size 0.1397 0.1397)
			(layers "F.Cu" "F.Mask" "F.Paste")
			(net "PWM_OUT_FAN1_NET")
			(options
				(clearance outline)
				(anchor circle)
			)
			(primitives
				(gr_poly
					(pts
						(arc
							(start -0.1778 -0.2794)
							(mid -0.249642 -0.249642)
							(end -0.2794 -0.1778)
						)
						(arc
							(start -0.2794 0.1778)
							(mid -0.249642 0.249642)
							(end -0.1778 0.2794)
						)
						(arc
							(start 0.1778 0.2794)
							(mid 0.249642 0.249642)
							(end 0.2794 0.1778)
						)
						(arc
							(start 0.2794 -0.1778)
							(mid 0.249642 -0.249642)
							(end 0.1778 -0.2794)
						)
					)
					(width 0)
					(fill yes)
				)
			)
		)
	)
	(footprint ""
		(layer "F.Cu")
		(at 16.053308 -287.311338)
		(property "Reference" "R98"
			(at 0 0 0)
			(layer "F.SilkS")
			(hide yes)
			(effects
				(font
					(size 1.27 1.27)
				)
			)
		)
		(property "Value" "27KR3F-GP"
			(at -0.0254 -2.5146 0)
			(unlocked yes)
			(layer "F.Fab")
			(hide yes)
			(effects
				(font
					(size 1.016 1.016)
					(thickness 0.1524)
				)
			)
		)
		(property "Device Type" "R603H22"
			(at -0.0254 -4.0386 0)
			(unlocked yes)
			(layer "F.Fab")
			(hide yes)
			(effects
				(font
					(size 1.016 1.016)
					(thickness 0.1524)
				)
			)
		)
		(duplicate_pad_numbers_are_jumpers no)
		(fp_line
			(start -0.4826 0)
			(end -0.2032 0)
			(stroke
				(width 0.2032)
				(type default)
			)
			(layer "F.SilkS")
		)
		(fp_line
			(start 0.2032 0)
			(end 0.4826 0)
			(stroke
				(width 0.2032)
				(type default)
			)
			(layer "F.SilkS")
		)
		(fp_rect
			(start -0.5842 1.3335)
			(end 0.5842 -1.3335)
			(stroke
				(width 0)
				(type default)
			)
			(fill no)
			(layer "F.CrtYd")
		)
		(fp_rect
			(start -0.5842 1.3335)
			(end 0.5842 -1.3335)
			(stroke
				(width 0)
				(type default)
			)
			(fill no)
			(layer "F.Fab")
		)
		(pad "1" smd custom
			(at 0 -0.762)
			(size 0.2159 0.2159)
			(layers "F.Cu" "F.Mask" "F.Paste")
			(net "FANIN_3")
			(options
				(clearance outline)
				(anchor circle)
			)
			(primitives
				(gr_poly
					(pts
						(arc
							(start -0.3302 -0.4318)
							(mid -0.402042 -0.402042)
							(end -0.4318 -0.3302)
						)
						(arc
							(start -0.4318 0.3302)
							(mid -0.402042 0.402042)
							(end -0.3302 0.4318)
						)
						(arc
							(start 0.3302 0.4318)
							(mid 0.402042 0.402042)
							(end 0.4318 0.3302)
						)
						(arc
							(start 0.4318 -0.3302)
							(mid 0.402042 -0.402042)
							(end 0.3302 -0.4318)
						)
					)
					(width 0)
					(fill yes)
				)
			)
		)
		(pad "2" smd custom
			(at 0 0.762)
			(size 0.2159 0.2159)
			(layers "F.Cu" "F.Mask" "F.Paste")
			(net "FAN_TACH3")
			(options
				(clearance outline)
				(anchor circle)
			)
			(primitives
				(gr_poly
					(pts
						(arc
							(start -0.3302 -0.4318)
							(mid -0.402042 -0.402042)
							(end -0.4318 -0.3302)
						)
						(arc
							(start -0.4318 0.3302)
							(mid -0.402042 0.402042)
							(end -0.3302 0.4318)
						)
						(arc
							(start 0.3302 0.4318)
							(mid 0.402042 0.402042)
							(end 0.4318 0.3302)
						)
						(arc
							(start 0.4318 -0.3302)
							(mid 0.402042 -0.402042)
							(end 0.3302 -0.4318)
						)
					)
					(width 0)
					(fill yes)
				)
			)
		)
	)
	(footprint ""
		(layer "F.Cu")
		(at 26.227024 -173.96841 90)
		(property "Reference" "U2"
			(at 0 0 90)
			(layer "F.SilkS")
			(hide yes)
			(effects
				(font
					(size 1.27 1.27)
				)
			)
		)
		(property "Value" "NCT7368S-GP"
			(at 3.8989 1.5748 90)
			(unlocked yes)
			(layer "F.Fab")
			(hide yes)
			(effects
				(font
					(size 1.016 1.016)
					(thickness 0.1524)
				)
			)
		)
		(property "Device Type" "SOIC8-G3627H69"
			(at 3.8989 0.0508 90)
			(unlocked yes)
			(layer "F.Fab")
			(hide yes)
			(effects
				(font
					(size 1.016 1.016)
					(thickness 0.1524)
				)
			)
		)
		(duplicate_pad_numbers_are_jumpers no)
		(fp_line
			(start 2.7178 -3.6322)
			(end 2.7178 3.6322)
			(stroke
				(width 0.1524)
				(type default)
			)
			(layer "F.SilkS")
		)
		(fp_line
			(start -2.8829 -3.6322)
			(end 2.7178 -3.6322)
			(stroke
				(width 0.1524)
				(type default)
			)
			(layer "F.SilkS")
		)
		(fp_line
			(start -2.8829 -0.6223)
			(end -2.2479 0.0127)
			(stroke
				(width 0.1524)
				(type default)
			)
			(layer "F.SilkS")
		)
		(fp_line
			(start -2.2479 0.0127)
			(end -2.8829 0.6477)
			(stroke
				(width 0.1524)
				(type default)
			)
			(layer "F.SilkS")
		)
		(fp_line
			(start -2.8829 0.6477)
			(end -2.8829 -0.6223)
			(stroke
				(width 0.1524)
				(type default)
			)
			(layer "F.SilkS")
		)
		(fp_line
			(start 2.7178 3.6322)
			(end -2.8829 3.6322)
			(stroke
				(width 0.1524)
				(type default)
			)
			(layer "F.SilkS")
		)
		(fp_line
			(start -2.7051 3.6322)
			(end -2.7051 1.5494)
			(stroke
				(width 0.508)
				(type default)
			)
			(layer "F.SilkS")
		)
		(fp_line
			(start -2.8829 3.6322)
			(end -2.8829 -3.6322)
			(stroke
				(width 0.1524)
				(type default)
			)
			(layer "F.SilkS")
		)
		(fp_poly
			(pts
				(xy 0.2794 -0.2794) (xy 1.8034 -0.2794) (xy 1.8034 -1.3462) (xy 0.2794 -1.3462)
			)
			(stroke
				(width 0)
				(type default)
			)
			(fill yes)
			(layer "F.Paste")
		)
		(fp_poly
			(pts
				(xy -1.8034 -0.2794) (xy -0.2794 -0.2794) (xy -0.2794 -1.3462) (xy -1.8034 -1.3462)
			)
			(stroke
				(width 0)
				(type default)
			)
			(fill yes)
			(layer "F.Paste")
		)
		(fp_poly
			(pts
				(xy 0.2794 1.3462) (xy 1.8034 1.3462) (xy 1.8034 0.2794) (xy 0.2794 0.2794)
			)
			(stroke
				(width 0)
				(type default)
			)
			(fill yes)
			(layer "F.Paste")
		)
		(fp_poly
			(pts
				(xy -1.8034 1.3462) (xy -0.2794 1.3462) (xy -0.2794 0.2794) (xy -1.8034 0.2794)
			)
			(stroke
				(width 0)
				(type default)
			)
			(fill yes)
			(layer "F.Paste")
		)
		(fp_poly
			(pts
				(xy -2.1209 2.9972) (xy -2.1209 1.9558) (xy -2.4511 1.9558) (xy -2.4511 -1.9558) (xy -2.1209 -1.9558)
				(xy -2.1209 -2.9972) (xy 2.1209 -2.9972) (xy 2.1209 -1.9558) (xy 2.4511 -1.9558) (xy 2.4511 1.9558)
				(xy 2.1209 1.9558) (xy 2.1209 2.9972)
			)
			(stroke
				(width 0)
				(type default)
			)
			(fill no)
			(layer "F.CrtYd")
		)
		(fp_poly
			(pts
				(xy -2.9591 3.8862) (xy -2.9591 -3.8862) (xy 2.9591 -3.8862) (xy 2.9591 1.95072) (xy 2.4511 1.95072)
				(xy 2.4511 -1.9558) (xy 2.1209 -1.9558) (xy 2.1209 -2.9972) (xy -2.1209 -2.9972) (xy -2.1209 -1.9558)
				(xy -2.4511 -1.9558) (xy -2.4511 1.9558) (xy -2.1209 1.9558) (xy -2.1209 2.9972) (xy 2.1209 2.9972)
				(xy 2.1209 1.9558) (xy 2.9591 1.9558) (xy 2.9591 3.8862)
			)
			(stroke
				(width 0)
				(type default)
			)
			(fill no)
			(layer "F.CrtYd")
		)
		(fp_rect
			(start -2.9591 3.8862)
			(end 2.9591 -3.8862)
			(stroke
				(width 0)
				(type default)
			)
			(fill no)
			(layer "F.Fab")
		)
		(pad "1" smd rect
			(at -1.905 2.5527 90)
			(size 0.635 1.651)
			(layers "F.Cu" "F.Mask" "F.Paste")
			(net "P3V3")
		)
		(pad "2" smd rect
			(at -0.635 2.5527 90)
			(size 0.635 1.651)
			(layers "F.Cu" "F.Mask" "F.Paste")
			(net "PWM_EXP_1A")
		)
		(pad "3" smd rect
			(at 0.635 2.5527 90)
			(size 0.635 1.651)
			(layers "F.Cu" "F.Mask" "F.Paste")
			(net "PWM_EXP_1B")
		)
		(pad "4" smd rect
			(at 1.905 2.5527 90)
			(size 0.635 1.651)
			(layers "F.Cu" "F.Mask" "F.Paste")
			(net "PWM_EXP_2A")
		)
		(pad "5" smd rect
			(at 1.905 -2.5527 90)
			(size 0.635 1.651)
			(layers "F.Cu" "F.Mask" "F.Paste")
			(net "NCT7368S_SEL")
		)
		(pad "6" smd rect
			(at 0.635 -2.5527 90)
			(size 0.635 1.651)
			(layers "F.Cu" "F.Mask" "F.Paste")
			(net "THERMHOT#")
		)
		(pad "7" smd rect
			(at -0.635 -2.5527 90)
			(size 0.635 1.651)
			(layers "F.Cu" "F.Mask" "F.Paste")
			(net "PWM_OUT")
		)
		(pad "8" smd rect
			(at -1.905 -2.5527 90)
			(size 0.635 1.651)
			(layers "F.Cu" "F.Mask" "F.Paste")
			(net "PWM_EXP_2B")
		)
		(pad "9" smd rect
			(at 0 0 90)
			(size 3.6068 2.6924)
			(layers "F.Cu" "F.Mask" "F.Paste")
			(net "GND")
		)
	)
	(footprint ""
		(layer "F.Cu")
		(at 13.1318 -150.622 90)
		(property "Reference" "D2"
			(at 0 0 90)
			(layer "F.SilkS")
			(hide yes)
			(effects
				(font
					(size 1.27 1.27)
				)
			)
		)
		(property "Value" "BAS16H-GP"
			(at 0 -5.5372 90)
			(unlocked yes)
			(layer "F.Fab")
			(hide yes)
			(effects
				(font
					(size 1.016 1.016)
					(thickness 0.1524)
				)
			)
		)
		(property "Device Type" "SOD123AKH48"
			(at 0 -7.0612 90)
			(unlocked yes)
			(layer "F.Fab")
			(hide yes)
			(effects
				(font
					(size 1.016 1.016)
					(thickness 0.1524)
				)
			)
		)
		(duplicate_pad_numbers_are_jumpers no)
		(fp_line
			(start 1.016 -2.667)
			(end -1.016 -2.667)
			(stroke
				(width 0.1524)
				(type default)
			)
			(layer "F.SilkS")
		)
		(fp_line
			(start -1.016 -2.667)
			(end -1.016 2.667)
			(stroke
				(width 0.1524)
				(type default)
			)
			(layer "F.SilkS")
		)
		(fp_line
			(start 1.016 2.667)
			(end 1.016 -2.667)
			(stroke
				(width 0.1524)
				(type default)
			)
			(layer "F.SilkS")
		)
		(fp_line
			(start -1.016 2.667)
			(end 1.016 2.667)
			(stroke
				(width 0.1524)
				(type default)
			)
			(layer "F.SilkS")
		)
		(fp_line
			(start 0.889 2.921)
			(end -0.889 2.921)
			(stroke
				(width 0.508)
				(type default)
			)
			(layer "F.SilkS")
		)
		(fp_rect
			(start -1.143 3.175)
			(end 1.143 -2.794)
			(stroke
				(width 0)
				(type default)
			)
			(fill no)
			(layer "F.CrtYd")
		)
		(fp_poly
			(pts
				(xy -1.143 -2.794) (xy 1.143 -2.794) (xy 1.143 3.175) (xy -1.143 3.175)
			)
			(stroke
				(width 0)
				(type default)
			)
			(fill no)
			(layer "F.Fab")
		)
		(pad "A" smd rect
			(at 0 -1.6891 90)
			(size 0.889 1.397)
			(layers "F.Cu" "F.Mask" "F.Paste")
			(net "FAN_TACH10")
		)
		(pad "K" smd rect
			(at 0 1.6891 90)
			(size 0.889 1.397)
			(layers "F.Cu" "F.Mask" "F.Paste")
			(net "P12V")
		)
	)
	(footprint ""
		(layer "F.Cu")
		(at 6.604 -280.924 -90)
		(property "Reference" "R37"
			(at 0 0 270)
			(layer "F.SilkS")
			(hide yes)
			(effects
				(font
					(size 1.27 1.27)
				)
			)
		)
		(property "Value" "33R2F-3-GP"
			(at 0.064008 -3.993896 270)
			(unlocked yes)
			(layer "F.Fab")
			(hide yes)
			(effects
				(font
					(size 1.016 1.016)
					(thickness 0.1524)
				)
			)
		)
		(property "Device Type" "R402H16"
			(at 0.064008 -5.517896 270)
			(unlocked yes)
			(layer "F.Fab")
			(hide yes)
			(effects
				(font
					(size 1.016 1.016)
					(thickness 0.1524)
				)
			)
		)
		(duplicate_pad_numbers_are_jumpers no)
		(fp_line
			(start -0.508 -0.9398)
			(end -0.508 0.9398)
			(stroke
				(width 0.1524)
				(type default)
			)
			(layer "F.SilkS")
		)
		(fp_line
			(start 0.508 -0.9398)
			(end -0.508 -0.9398)
			(stroke
				(width 0.1524)
				(type default)
			)
			(layer "F.SilkS")
		)
		(fp_rect
			(start -0.508 0.9398)
			(end 0.508 -0.9398)
			(stroke
				(width 0)
				(type default)
			)
			(fill no)
			(layer "F.CrtYd")
		)
		(fp_rect
			(start -0.508 0.9398)
			(end 0.508 -0.9398)
			(stroke
				(width 0)
				(type default)
			)
			(fill no)
			(layer "F.Fab")
		)
		(pad "1" smd custom
			(at 0 -0.4445 270)
			(size 0.1397 0.1397)
			(layers "F.Cu" "F.Mask" "F.Paste")
			(net "P3V3")
			(options
				(clearance outline)
				(anchor circle)
			)
			(primitives
				(gr_poly
					(pts
						(arc
							(start -0.1778 -0.2794)
							(mid -0.249642 -0.249642)
							(end -0.2794 -0.1778)
						)
						(arc
							(start -0.2794 0.1778)
							(mid -0.249642 0.249642)
							(end -0.1778 0.2794)
						)
						(arc
							(start 0.1778 0.2794)
							(mid 0.249642 0.249642)
							(end 0.2794 0.1778)
						)
						(arc
							(start 0.2794 -0.1778)
							(mid 0.249642 -0.249642)
							(end 0.1778 -0.2794)
						)
					)
					(width 0)
					(fill yes)
				)
			)
		)
		(pad "2" smd custom
			(at 0 0.4445 270)
			(size 0.1397 0.1397)
			(layers "F.Cu" "F.Mask" "F.Paste")
			(net "LED_DR_LED2_BLUE")
			(options
				(clearance outline)
				(anchor circle)
			)
			(primitives
				(gr_poly
					(pts
						(arc
							(start -0.1778 -0.2794)
							(mid -0.249642 -0.249642)
							(end -0.2794 -0.1778)
						)
						(arc
							(start -0.2794 0.1778)
							(mid -0.249642 0.249642)
							(end -0.1778 0.2794)
						)
						(arc
							(start 0.1778 0.2794)
							(mid 0.249642 0.249642)
							(end 0.2794 0.1778)
						)
						(arc
							(start 0.2794 -0.1778)
							(mid 0.249642 -0.249642)
							(end 0.1778 -0.2794)
						)
					)
					(width 0)
					(fill yes)
				)
			)
		)
	)
	(footprint ""
		(layer "F.Cu")
		(at 37.973 -180.34)
		(property "Reference" "R261"
			(at 0 0 0)
			(layer "F.SilkS")
			(hide yes)
			(effects
				(font
					(size 1.27 1.27)
				)
			)
		)
		(property "Value" "10KR2J-3-GP"
			(at 0.064008 -3.993896 0)
			(unlocked yes)
			(layer "F.Fab")
			(hide yes)
			(effects
				(font
					(size 1.016 1.016)
					(thickness 0.1524)
				)
			)
		)
		(property "Device Type" "R402H16"
			(at 0.064008 -5.517896 0)
			(unlocked yes)
			(layer "F.Fab")
			(hide yes)
			(effects
				(font
					(size 1.016 1.016)
					(thickness 0.1524)
				)
			)
		)
		(duplicate_pad_numbers_are_jumpers no)
		(fp_line
			(start -0.508 -0.9398)
			(end -0.508 0.9398)
			(stroke
				(width 0.1524)
				(type default)
			)
			(layer "F.SilkS")
		)
		(fp_line
			(start 0.508 -0.9398)
			(end -0.508 -0.9398)
			(stroke
				(width 0.1524)
				(type default)
			)
			(layer "F.SilkS")
		)
		(fp_rect
			(start -0.508 0.9398)
			(end 0.508 -0.9398)
			(stroke
				(width 0)
				(type default)
			)
			(fill no)
			(layer "F.CrtYd")
		)
		(fp_rect
			(start -0.508 0.9398)
			(end 0.508 -0.9398)
			(stroke
				(width 0)
				(type default)
			)
			(fill no)
			(layer "F.Fab")
		)
		(pad "1" smd custom
			(at 0 -0.4445)
			(size 0.1397 0.1397)
			(layers "F.Cu" "F.Mask" "F.Paste")
			(net "D_LATCH_CLR")
			(options
				(clearance outline)
				(anchor circle)
			)
			(primitives
				(gr_poly
					(pts
						(arc
							(start -0.1778 -0.2794)
							(mid -0.249642 -0.249642)
							(end -0.2794 -0.1778)
						)
						(arc
							(start -0.2794 0.1778)
							(mid -0.249642 0.249642)
							(end -0.1778 0.2794)
						)
						(arc
							(start 0.1778 0.2794)
							(mid 0.249642 0.249642)
							(end 0.2794 0.1778)
						)
						(arc
							(start 0.2794 -0.1778)
							(mid 0.249642 -0.249642)
							(end 0.1778 -0.2794)
						)
					)
					(width 0)
					(fill yes)
				)
			)
		)
		(pad "2" smd custom
			(at 0 0.4445)
			(size 0.1397 0.1397)
			(layers "F.Cu" "F.Mask" "F.Paste")
			(net "P3V3_AUX")
			(options
				(clearance outline)
				(anchor circle)
			)
			(primitives
				(gr_poly
					(pts
						(arc
							(start -0.1778 -0.2794)
							(mid -0.249642 -0.249642)
							(end -0.2794 -0.1778)
						)
						(arc
							(start -0.2794 0.1778)
							(mid -0.249642 0.249642)
							(end -0.1778 0.2794)
						)
						(arc
							(start 0.1778 0.2794)
							(mid 0.249642 0.249642)
							(end 0.2794 0.1778)
						)
						(arc
							(start 0.2794 -0.1778)
							(mid 0.249642 -0.249642)
							(end 0.1778 -0.2794)
						)
					)
					(width 0)
					(fill yes)
				)
			)
		)
	)
	(footprint ""
		(layer "F.Cu")
		(at 26.543 -237.871)
		(property "Reference" "R154"
			(at 0 0 0)
			(layer "F.SilkS")
			(hide yes)
			(effects
				(font
					(size 1.27 1.27)
				)
			)
		)
		(property "Value" "0R0805-PAD-2-GP"
			(at 0.0508 -2.7432 0)
			(unlocked yes)
			(layer "F.Fab")
			(hide yes)
			(effects
				(font
					(size 1.016 1.016)
					(thickness 0.1524)
				)
			)
		)
		(property "Device Type" "0R0805-PAD-1"
			(at 0.0508 -4.2672 0)
			(unlocked yes)
			(layer "F.Fab")
			(hide yes)
			(effects
				(font
					(size 1.016 1.016)
					(thickness 0.1524)
				)
			)
		)
		(duplicate_pad_numbers_are_jumpers no)
		(fp_line
			(start -0.889 -1.7018)
			(end 0.889 -1.7018)
			(stroke
				(width 0.1524)
				(type default)
			)
			(layer "F.SilkS")
		)
		(fp_line
			(start -0.889 1.7018)
			(end -0.889 -1.7018)
			(stroke
				(width 0.1524)
				(type default)
			)
			(layer "F.SilkS")
		)
		(fp_line
			(start 0.889 -1.7018)
			(end 0.889 1.7018)
			(stroke
				(width 0.1524)
				(type default)
			)
			(layer "F.SilkS")
		)
		(fp_line
			(start 0.889 1.7018)
			(end -0.889 1.7018)
			(stroke
				(width 0.1524)
				(type default)
			)
			(layer "F.SilkS")
		)
		(fp_rect
			(start -0.9652 1.778)
			(end 0.9652 -1.778)
			(stroke
				(width 0)
				(type default)
			)
			(fill no)
			(layer "F.CrtYd")
		)
		(fp_rect
			(start -0.9652 1.778)
			(end 0.9652 -1.778)
			(stroke
				(width 0)
				(type default)
			)
			(fill no)
			(layer "F.Fab")
		)
		(pad "1" smd rect
			(at 0 -0.9652)
			(size 1.397 1.5621)
			(drill
				(offset 0 0.20955)
			)
			(layers "F.Cu" "F.Mask" "F.Paste")
			(net "P3V3_LX_COPPER")
		)
		(pad "2" smd rect
			(at 0 0.9652)
			(size 1.397 1.568704)
			(drill
				(offset 0 -0.206248)
			)
			(layers "F.Cu" "F.Mask" "F.Paste")
			(net "P3V3")
		)
	)
	(footprint ""
		(layer "F.Cu")
		(at 18.644362 -157.505908 90)
		(property "Reference" "F2"
			(at 0 0 90)
			(layer "F.SilkS")
			(hide yes)
			(effects
				(font
					(size 1.27 1.27)
				)
			)
		)
		(property "Value" "FUSE-3A15V-GP"
			(at 0.2286 -10.5918 90)
			(unlocked yes)
			(layer "F.Fab")
			(hide yes)
			(effects
				(font
					(size 1.016 1.016)
					(thickness 0.1524)
				)
			)
		)
		(property "Device Type" "FUSE-7452-UH50"
			(at 0.2286 -12.4968 90)
			(unlocked yes)
			(layer "F.Fab")
			(hide yes)
			(effects
				(font
					(size 1.016 1.016)
					(thickness 0.1524)
				)
			)
		)
		(duplicate_pad_numbers_are_jumpers no)
		(fp_line
			(start 4.9276 -2.921)
			(end 4.9276 2.921)
			(stroke
				(width 0.1524)
				(type default)
			)
			(layer "F.SilkS")
		)
		(fp_line
			(start -4.9276 -2.921)
			(end 4.9276 -2.921)
			(stroke
				(width 0.1524)
				(type default)
			)
			(layer "F.SilkS")
		)
		(fp_line
			(start 4.9276 2.921)
			(end -4.9276 2.921)
			(stroke
				(width 0.1524)
				(type default)
			)
			(layer "F.SilkS")
		)
		(fp_line
			(start -4.9276 2.921)
			(end -4.9276 -2.921)
			(stroke
				(width 0.1524)
				(type default)
			)
			(layer "F.SilkS")
		)
		(fp_poly
			(pts
				(xy -5.08 3.0988) (xy 5.08 3.0988) (xy 5.08 -3.0988) (xy -5.08 -3.0988)
			)
			(stroke
				(width 0)
				(type default)
			)
			(fill no)
			(layer "F.CrtYd")
		)
		(fp_poly
			(pts
				(xy -5.08 -3.0988) (xy 5.08 -3.0988) (xy 5.08 3.0988) (xy -5.08 3.0988)
			)
			(stroke
				(width 0)
				(type default)
			)
			(fill no)
			(layer "F.Fab")
		)
		(pad "1" smd rect
			(at -3.4036 0 90)
			(size 2.2098 5.2832)
			(layers "F.Cu" "F.Mask" "F.Paste")
			(net "P12V_FAN5")
		)
		(pad "2" smd rect
			(at 3.4036 0 90)
			(size 2.2098 5.2832)
			(layers "F.Cu" "F.Mask" "F.Paste")
			(net "P12V")
		)
	)
	(footprint ""
		(layer "F.Cu")
		(at 31.75 -381 180)
		(property "Reference" "PR21"
			(at 0 0 180)
			(layer "F.SilkS")
			(hide yes)
			(effects
				(font
					(size 1.27 1.27)
				)
			)
		)
		(property "Value" "10R2F-L-GP"
			(at 0.064008 -3.993896 180)
			(unlocked yes)
			(layer "F.Fab")
			(hide yes)
			(effects
				(font
					(size 1.016 1.016)
					(thickness 0.1524)
				)
			)
		)
		(property "Device Type" "R402H14"
			(at 0.064008 -5.517896 180)
			(unlocked yes)
			(layer "F.Fab")
			(hide yes)
			(effects
				(font
					(size 1.016 1.016)
					(thickness 0.1524)
				)
			)
		)
		(duplicate_pad_numbers_are_jumpers no)
		(fp_line
			(start 0.508 -0.9398)
			(end -0.508 -0.9398)
			(stroke
				(width 0.1524)
				(type default)
			)
			(layer "F.SilkS")
		)
		(fp_line
			(start -0.508 -0.9398)
			(end -0.508 0.9398)
			(stroke
				(width 0.1524)
				(type default)
			)
			(layer "F.SilkS")
		)
		(fp_rect
			(start -0.508 0.9398)
			(end 0.508 -0.9398)
			(stroke
				(width 0)
				(type default)
			)
			(fill no)
			(layer "F.CrtYd")
		)
		(fp_rect
			(start -0.508 0.9398)
			(end 0.508 -0.9398)
			(stroke
				(width 0)
				(type default)
			)
			(fill no)
			(layer "F.Fab")
		)
		(pad "1" smd custom
			(at 0 -0.4445 180)
			(size 0.1397 0.1397)
			(layers "F.Cu" "F.Mask" "F.Paste")
			(net "ADM1276_SENSE-")
			(options
				(clearance outline)
				(anchor circle)
			)
			(primitives
				(gr_poly
					(pts
						(arc
							(start -0.1778 -0.2794)
							(mid -0.249642 -0.249642)
							(end -0.2794 -0.1778)
						)
						(arc
							(start -0.2794 0.1778)
							(mid -0.249642 0.249642)
							(end -0.1778 0.2794)
						)
						(arc
							(start 0.1778 0.2794)
							(mid 0.249642 0.249642)
							(end 0.2794 0.1778)
						)
						(arc
							(start 0.2794 -0.1778)
							(mid 0.249642 -0.249642)
							(end 0.1778 -0.2794)
						)
					)
					(width 0)
					(fill yes)
				)
			)
		)
		(pad "2" smd custom
			(at 0 0.4445 180)
			(size 0.1397 0.1397)
			(layers "F.Cu" "F.Mask" "F.Paste")
			(net "SENSE-_R1")
			(options
				(clearance outline)
				(anchor circle)
			)
			(primitives
				(gr_poly
					(pts
						(arc
							(start -0.1778 -0.2794)
							(mid -0.249642 -0.249642)
							(end -0.2794 -0.1778)
						)
						(arc
							(start -0.2794 0.1778)
							(mid -0.249642 0.249642)
							(end -0.1778 0.2794)
						)
						(arc
							(start 0.1778 0.2794)
							(mid 0.249642 0.249642)
							(end 0.2794 0.1778)
						)
						(arc
							(start 0.2794 -0.1778)
							(mid 0.249642 -0.249642)
							(end 0.1778 -0.2794)
						)
					)
					(width 0)
					(fill yes)
				)
			)
		)
	)
	(footprint ""
		(layer "F.Cu")
		(at 10.033 -174.752 90)
		(property "Reference" "U10"
			(at 0 0 90)
			(layer "F.SilkS")
			(hide yes)
			(effects
				(font
					(size 1.27 1.27)
				)
			)
		)
		(property "Value" "74LVC1G32GW-1GP"
			(at -2.3368 -8.6868 90)
			(unlocked yes)
			(layer "F.Fab")
			(hide yes)
			(effects
				(font
					(size 1.016 1.016)
					(thickness 0.1524)
				)
			)
		)
		(property "Device Type" "SC70-5H44"
			(at -2.3114 -10.414 90)
			(unlocked yes)
			(layer "F.Fab")
			(hide yes)
			(effects
				(font
					(size 1.016 1.016)
					(thickness 0.1524)
				)
			)
		)
		(duplicate_pad_numbers_are_jumpers no)
		(fp_line
			(start 1.3843 -1.8034)
			(end 1.3843 -1.1176)
			(stroke
				(width 0.3302)
				(type default)
			)
			(layer "F.SilkS")
		)
		(fp_line
			(start 0.6604 -1.8034)
			(end 1.3843 -1.8034)
			(stroke
				(width 0.3302)
				(type default)
			)
			(layer "F.SilkS")
		)
		(fp_line
			(start 1.27 -1.7018)
			(end 1.27 1.7018)
			(stroke
				(width 0.1524)
				(type default)
			)
			(layer "F.SilkS")
		)
		(fp_line
			(start -1.27 -1.7018)
			(end 1.27 -1.7018)
			(stroke
				(width 0.1524)
				(type default)
			)
			(layer "F.SilkS")
		)
		(fp_line
			(start 1.27 1.7018)
			(end -1.27 1.7018)
			(stroke
				(width 0.1524)
				(type default)
			)
			(layer "F.SilkS")
		)
		(fp_line
			(start -1.27 1.7018)
			(end -1.27 -1.7018)
			(stroke
				(width 0.1524)
				(type default)
			)
			(layer "F.SilkS")
		)
		(fp_rect
			(start -1.524 1.9558)
			(end 1.524 -1.9558)
			(stroke
				(width 0)
				(type default)
			)
			(fill no)
			(layer "F.CrtYd")
		)
		(fp_poly
			(pts
				(xy -1.524 -1.9558) (xy 1.524 -1.9558) (xy 1.524 1.9558) (xy -1.524 1.9558)
			)
			(stroke
				(width 0)
				(type default)
			)
			(fill no)
			(layer "F.Fab")
		)
		(pad "1" smd rect
			(at 0.65024 -0.8255 90)
			(size 0.4064 1.2192)
			(layers "F.Cu" "F.Mask" "F.Paste")
			(net "SEB_PEER_1A_HB")
		)
		(pad "2" smd rect
			(at 0 -0.8255 90)
			(size 0.4064 1.2192)
			(layers "F.Cu" "F.Mask" "F.Paste")
			(net "SEB_PEER_1B_HB")
		)
		(pad "3" smd rect
			(at -0.65024 -0.8255 90)
			(size 0.4064 1.2192)
			(layers "F.Cu" "F.Mask" "F.Paste")
			(net "GND")
		)
		(pad "4" smd rect
			(at -0.65024 0.8255 90)
			(size 0.4064 1.2192)
			(layers "F.Cu" "F.Mask" "F.Paste")
			(net "SEB_PEER_1A_1B_HB_OUT")
		)
		(pad "5" smd rect
			(at 0.65024 0.8255 90)
			(size 0.4064 1.2192)
			(layers "F.Cu" "F.Mask" "F.Paste")
			(net "P3V3")
		)
	)
	(footprint ""
		(layer "F.Cu")
		(at 27.500072 -320.000122 90)
		(property "Reference" "Q2"
			(at 0 0 90)
			(layer "F.SilkS")
			(hide yes)
			(effects
				(font
					(size 1.27 1.27)
				)
			)
		)
		(property "Value" "PMBS3904-1-GP"
			(at 0 -9.0932 90)
			(unlocked yes)
			(layer "F.Fab")
			(hide yes)
			(effects
				(font
					(size 1.016 1.016)
					(thickness 0.1524)
				)
			)
		)
		(property "Device Type" "SOT-23-10H44"
			(at 0 -10.6172 90)
			(unlocked yes)
			(layer "F.Fab")
			(hide yes)
			(effects
				(font
					(size 1.016 1.016)
					(thickness 0.1524)
				)
			)
		)
		(duplicate_pad_numbers_are_jumpers no)
		(fp_line
			(start 1.651 -1.778)
			(end -1.651 -1.778)
			(stroke
				(width 0.1524)
				(type default)
			)
			(layer "F.SilkS")
		)
		(fp_line
			(start -1.651 -1.778)
			(end -1.651 1.778)
			(stroke
				(width 0.1524)
				(type default)
			)
			(layer "F.SilkS")
		)
		(fp_line
			(start 1.651 1.778)
			(end 1.651 -1.778)
			(stroke
				(width 0.1524)
				(type default)
			)
			(layer "F.SilkS")
		)
		(fp_line
			(start -1.651 1.778)
			(end 1.651 1.778)
			(stroke
				(width 0.1524)
				(type default)
			)
			(layer "F.SilkS")
		)
		(fp_line
			(start -0.9906 1.86309)
			(end -0.701294 2.15265)
			(stroke
				(width 0.0127)
				(type default)
			)
			(layer "F.SilkS")
		)
		(fp_line
			(start -0.994156 1.8669)
			(end -0.987044 1.8669)
			(stroke
				(width 0.0127)
				(type default)
			)
			(layer "F.SilkS")
		)
		(fp_line
			(start -1.003808 1.876552)
			(end -0.977646 1.876552)
			(stroke
				(width 0.0127)
				(type default)
			)
			(layer "F.SilkS")
		)
		(fp_line
			(start -0.635 1.8796)
			(end -1.7526 1.8796)
			(stroke
				(width 0.3302)
				(type default)
			)
			(layer "F.SilkS")
		)
		(fp_line
			(start -1.7526 1.8796)
			(end -1.7526 0.9906)
			(stroke
				(width 0.3302)
				(type default)
			)
			(layer "F.SilkS")
		)
		(fp_line
			(start -1.013206 1.88595)
			(end -0.967994 1.88595)
			(stroke
				(width 0.0127)
				(type default)
			)
			(layer "F.SilkS")
		)
		(fp_line
			(start -1.022858 1.895602)
			(end -0.958596 1.895602)
			(stroke
				(width 0.0127)
				(type default)
			)
			(layer "F.SilkS")
		)
		(fp_line
			(start -1.032256 1.905)
			(end -0.948944 1.905)
			(stroke
				(width 0.0127)
				(type default)
			)
			(layer "F.SilkS")
		)
		(fp_line
			(start -1.041908 1.914652)
			(end -0.939546 1.914652)
			(stroke
				(width 0.0127)
				(type default)
			)
			(layer "F.SilkS")
		)
		(fp_line
			(start -1.051306 1.92405)
			(end -0.929894 1.92405)
			(stroke
				(width 0.0127)
				(type default)
			)
			(layer "F.SilkS")
		)
		(fp_line
			(start -1.060958 1.933702)
			(end -0.920496 1.933702)
			(stroke
				(width 0.0127)
				(type default)
			)
			(layer "F.SilkS")
		)
		(fp_line
			(start -1.070356 1.9431)
			(end -0.910844 1.9431)
			(stroke
				(width 0.0127)
				(type default)
			)
			(layer "F.SilkS")
		)
		(fp_line
			(start -1.080008 1.952752)
			(end -0.901446 1.952752)
			(stroke
				(width 0.0127)
				(type default)
			)
			(layer "F.SilkS")
		)
		(fp_line
			(start -1.089406 1.96215)
			(end -0.891794 1.96215)
			(stroke
				(width 0.0127)
				(type default)
			)
			(layer "F.SilkS")
		)
		(fp_line
			(start -1.099058 1.971802)
			(end -0.882396 1.971802)
			(stroke
				(width 0.0127)
				(type default)
			)
			(layer "F.SilkS")
		)
		(fp_line
			(start -1.108456 1.9812)
			(end -0.872744 1.9812)
			(stroke
				(width 0.0127)
				(type default)
			)
			(layer "F.SilkS")
		)
		(fp_line
			(start -1.118108 1.990852)
			(end -0.863346 1.990852)
			(stroke
				(width 0.0127)
				(type default)
			)
			(layer "F.SilkS")
		)
		(fp_line
			(start -1.127506 2.00025)
			(end -0.853694 2.00025)
			(stroke
				(width 0.0127)
				(type default)
			)
			(layer "F.SilkS")
		)
		(fp_line
			(start -1.137158 2.009902)
			(end -0.844296 2.009902)
			(stroke
				(width 0.0127)
				(type default)
			)
			(layer "F.SilkS")
		)
		(fp_line
			(start -1.146556 2.0193)
			(end -0.834644 2.0193)
			(stroke
				(width 0.0127)
				(type default)
			)
			(layer "F.SilkS")
		)
		(fp_line
			(start -1.156208 2.028952)
			(end -0.825246 2.028952)
			(stroke
				(width 0.0127)
				(type default)
			)
			(layer "F.SilkS")
		)
		(fp_line
			(start -1.165606 2.03835)
			(end -0.815594 2.03835)
			(stroke
				(width 0.0127)
				(type default)
			)
			(layer "F.SilkS")
		)
		(fp_line
			(start -1.175258 2.048002)
			(end -0.806196 2.048002)
			(stroke
				(width 0.0127)
				(type default)
			)
			(layer "F.SilkS")
		)
		(fp_line
			(start -1.184656 2.0574)
			(end -0.796544 2.0574)
			(stroke
				(width 0.0127)
				(type default)
			)
			(layer "F.SilkS")
		)
		(fp_line
			(start -1.194308 2.067052)
			(end -0.787146 2.067052)
			(stroke
				(width 0.0127)
				(type default)
			)
			(layer "F.SilkS")
		)
		(fp_line
			(start -1.203706 2.07645)
			(end -0.777494 2.07645)
			(stroke
				(width 0.0127)
				(type default)
			)
			(layer "F.SilkS")
		)
		(fp_line
			(start -1.213358 2.086102)
			(end -0.768096 2.086102)
			(stroke
				(width 0.0127)
				(type default)
			)
			(layer "F.SilkS")
		)
		(fp_line
			(start -1.222756 2.0955)
			(end -0.758444 2.0955)
			(stroke
				(width 0.0127)
				(type default)
			)
			(layer "F.SilkS")
		)
		(fp_line
			(start -1.232408 2.105152)
			(end -0.749046 2.105152)
			(stroke
				(width 0.0127)
				(type default)
			)
			(layer "F.SilkS")
		)
		(fp_line
			(start -1.241806 2.11455)
			(end -0.739394 2.11455)
			(stroke
				(width 0.0127)
				(type default)
			)
			(layer "F.SilkS")
		)
		(fp_line
			(start -1.251458 2.124202)
			(end -0.729996 2.124202)
			(stroke
				(width 0.0127)
				(type default)
			)
			(layer "F.SilkS")
		)
		(fp_line
			(start -1.260856 2.1336)
			(end -0.720344 2.1336)
			(stroke
				(width 0.0127)
				(type default)
			)
			(layer "F.SilkS")
		)
		(fp_line
			(start -0.719074 2.145538)
			(end -1.265936 2.14122)
			(stroke
				(width 0.0127)
				(type default)
			)
			(layer "F.SilkS")
		)
		(fp_line
			(start -1.279398 2.152142)
			(end -0.9906 1.86309)
			(stroke
				(width 0.0127)
				(type default)
			)
			(layer "F.SilkS")
		)
		(fp_line
			(start -0.71628 2.15265)
			(end -1.26492 2.15265)
			(stroke
				(width 0.0127)
				(type default)
			)
			(layer "F.SilkS")
		)
		(fp_line
			(start -1.279144 2.15265)
			(end -0.701294 2.15265)
			(stroke
				(width 0.0127)
				(type default)
			)
			(layer "F.SilkS")
		)
		(fp_poly
			(pts
				(xy -1.285748 2.159) (xy -1.285748 1.8796) (xy -1.778 1.8796) (xy -1.778 -1.8796) (xy 1.778 -1.8796)
				(xy 1.778 1.8796) (xy -0.694944 1.8796) (xy -0.694944 2.159)
			)
			(stroke
				(width 0)
				(type default)
			)
			(fill no)
			(layer "F.CrtYd")
		)
		(fp_poly
			(pts
				(xy -1.285748 2.159) (xy -1.285748 1.8796) (xy -1.778 1.8796) (xy -1.778 -1.8796) (xy 1.778 -1.8796)
				(xy 1.778 1.8796) (xy -0.694944 1.8796) (xy -0.694944 2.159)
			)
			(stroke
				(width 0)
				(type default)
			)
			(fill no)
			(layer "F.Fab")
		)
		(pad "1" smd rect
			(at -0.98425 0.9525 90)
			(size 0.762 1.143)
			(layers "F.Cu" "F.Mask" "F.Paste")
			(net "NCT7904_D2+")
		)
		(pad "2" smd rect
			(at 0.98425 0.9525 90)
			(size 0.762 1.143)
			(layers "F.Cu" "F.Mask" "F.Paste")
			(net "NCT7904_D2-")
		)
		(pad "3" smd rect
			(at 0 -0.9525 90)
			(size 0.762 1.143)
			(layers "F.Cu" "F.Mask" "F.Paste")
			(net "NCT7904_D2+")
		)
	)
	(footprint ""
		(layer "F.Cu")
		(at 20.701 -185.5216)
		(property "Reference" "R85"
			(at 0 0 0)
			(layer "F.SilkS")
			(hide yes)
			(effects
				(font
					(size 1.27 1.27)
				)
			)
		)
		(property "Value" "27KR3F-GP"
			(at -0.0254 -2.5146 0)
			(unlocked yes)
			(layer "F.Fab")
			(hide yes)
			(effects
				(font
					(size 1.016 1.016)
					(thickness 0.1524)
				)
			)
		)
		(property "Device Type" "R603H22"
			(at -0.0254 -4.0386 0)
			(unlocked yes)
			(layer "F.Fab")
			(hide yes)
			(effects
				(font
					(size 1.016 1.016)
					(thickness 0.1524)
				)
			)
		)
		(duplicate_pad_numbers_are_jumpers no)
		(fp_line
			(start -0.4826 0)
			(end -0.2032 0)
			(stroke
				(width 0.2032)
				(type default)
			)
			(layer "F.SilkS")
		)
		(fp_line
			(start 0.2032 0)
			(end 0.4826 0)
			(stroke
				(width 0.2032)
				(type default)
			)
			(layer "F.SilkS")
		)
		(fp_rect
			(start -0.5842 1.3335)
			(end 0.5842 -1.3335)
			(stroke
				(width 0)
				(type default)
			)
			(fill no)
			(layer "F.CrtYd")
		)
		(fp_rect
			(start -0.5842 1.3335)
			(end 0.5842 -1.3335)
			(stroke
				(width 0)
				(type default)
			)
			(fill no)
			(layer "F.Fab")
		)
		(pad "1" smd custom
			(at 0 -0.762)
			(size 0.2159 0.2159)
			(layers "F.Cu" "F.Mask" "F.Paste")
			(net "FAN_TACH8")
			(options
				(clearance outline)
				(anchor circle)
			)
			(primitives
				(gr_poly
					(pts
						(arc
							(start -0.3302 -0.4318)
							(mid -0.402042 -0.402042)
							(end -0.4318 -0.3302)
						)
						(arc
							(start -0.4318 0.3302)
							(mid -0.402042 0.402042)
							(end -0.3302 0.4318)
						)
						(arc
							(start 0.3302 0.4318)
							(mid 0.402042 0.402042)
							(end 0.4318 0.3302)
						)
						(arc
							(start 0.4318 -0.3302)
							(mid 0.402042 -0.402042)
							(end 0.3302 -0.4318)
						)
					)
					(width 0)
					(fill yes)
				)
			)
		)
		(pad "2" smd custom
			(at 0 0.762)
			(size 0.2159 0.2159)
			(layers "F.Cu" "F.Mask" "F.Paste")
			(net "FANIN_8")
			(options
				(clearance outline)
				(anchor circle)
			)
			(primitives
				(gr_poly
					(pts
						(arc
							(start -0.3302 -0.4318)
							(mid -0.402042 -0.402042)
							(end -0.4318 -0.3302)
						)
						(arc
							(start -0.4318 0.3302)
							(mid -0.402042 0.402042)
							(end -0.3302 0.4318)
						)
						(arc
							(start 0.3302 0.4318)
							(mid 0.402042 0.402042)
							(end 0.4318 0.3302)
						)
						(arc
							(start 0.4318 -0.3302)
							(mid 0.402042 -0.402042)
							(end 0.3302 -0.4318)
						)
					)
					(width 0)
					(fill yes)
				)
			)
		)
	)
	(footprint ""
		(layer "F.Cu")
		(at 29.3624 -167.259 180)
		(property "Reference" "R162"
			(at 0 0 180)
			(layer "F.SilkS")
			(hide yes)
			(effects
				(font
					(size 1.27 1.27)
				)
			)
		)
		(property "Value" "0R2J-2-GP"
			(at 0.064008 -3.993896 180)
			(unlocked yes)
			(layer "F.Fab")
			(hide yes)
			(effects
				(font
					(size 1.016 1.016)
					(thickness 0.1524)
				)
			)
		)
		(property "Device Type" "R402H16"
			(at 0.064008 -5.517896 180)
			(unlocked yes)
			(layer "F.Fab")
			(hide yes)
			(effects
				(font
					(size 1.016 1.016)
					(thickness 0.1524)
				)
			)
		)
		(duplicate_pad_numbers_are_jumpers no)
		(fp_line
			(start 0.508 -0.9398)
			(end -0.508 -0.9398)
			(stroke
				(width 0.1524)
				(type default)
			)
			(layer "F.SilkS")
		)
		(fp_line
			(start -0.508 -0.9398)
			(end -0.508 0.9398)
			(stroke
				(width 0.1524)
				(type default)
			)
			(layer "F.SilkS")
		)
		(fp_rect
			(start -0.508 0.9398)
			(end 0.508 -0.9398)
			(stroke
				(width 0)
				(type default)
			)
			(fill no)
			(layer "F.CrtYd")
		)
		(fp_rect
			(start -0.508 0.9398)
			(end 0.508 -0.9398)
			(stroke
				(width 0)
				(type default)
			)
			(fill no)
			(layer "F.Fab")
		)
		(pad "1" smd custom
			(at 0 -0.4445 180)
			(size 0.1397 0.1397)
			(layers "F.Cu" "F.Mask" "F.Paste")
			(net "NCT7904D_PWM2")
			(options
				(clearance outline)
				(anchor circle)
			)
			(primitives
				(gr_poly
					(pts
						(arc
							(start -0.1778 -0.2794)
							(mid -0.249642 -0.249642)
							(end -0.2794 -0.1778)
						)
						(arc
							(start -0.2794 0.1778)
							(mid -0.249642 0.249642)
							(end -0.1778 0.2794)
						)
						(arc
							(start 0.1778 0.2794)
							(mid 0.249642 0.249642)
							(end 0.2794 0.1778)
						)
						(arc
							(start 0.2794 -0.1778)
							(mid 0.249642 -0.249642)
							(end 0.1778 -0.2794)
						)
					)
					(width 0)
					(fill yes)
				)
			)
		)
		(pad "2" smd custom
			(at 0 0.4445 180)
			(size 0.1397 0.1397)
			(layers "F.Cu" "F.Mask" "F.Paste")
			(net "PWM_BUFFER_IN_FAN3_FAN4")
			(options
				(clearance outline)
				(anchor circle)
			)
			(primitives
				(gr_poly
					(pts
						(arc
							(start -0.1778 -0.2794)
							(mid -0.249642 -0.249642)
							(end -0.2794 -0.1778)
						)
						(arc
							(start -0.2794 0.1778)
							(mid -0.249642 0.249642)
							(end -0.1778 0.2794)
						)
						(arc
							(start 0.1778 0.2794)
							(mid 0.249642 0.249642)
							(end 0.2794 0.1778)
						)
						(arc
							(start 0.2794 -0.1778)
							(mid 0.249642 -0.249642)
							(end 0.1778 -0.2794)
						)
					)
					(width 0)
					(fill yes)
				)
			)
		)
	)
	(footprint ""
		(layer "F.Cu")
		(at 22.225 -18.161 90)
		(property "Reference" "R75"
			(at 0 0 90)
			(layer "F.SilkS")
			(hide yes)
			(effects
				(font
					(size 1.27 1.27)
				)
			)
		)
		(property "Value" "10KR2F-2-GP"
			(at 0.064008 -3.993896 90)
			(unlocked yes)
			(layer "F.Fab")
			(hide yes)
			(effects
				(font
					(size 1.016 1.016)
					(thickness 0.1524)
				)
			)
		)
		(property "Device Type" "R402H16"
			(at 0.064008 -5.517896 90)
			(unlocked yes)
			(layer "F.Fab")
			(hide yes)
			(effects
				(font
					(size 1.016 1.016)
					(thickness 0.1524)
				)
			)
		)
		(duplicate_pad_numbers_are_jumpers no)
		(fp_line
			(start 0.508 -0.9398)
			(end -0.508 -0.9398)
			(stroke
				(width 0.1524)
				(type default)
			)
			(layer "F.SilkS")
		)
		(fp_line
			(start -0.508 -0.9398)
			(end -0.508 0.9398)
			(stroke
				(width 0.1524)
				(type default)
			)
			(layer "F.SilkS")
		)
		(fp_rect
			(start -0.508 0.9398)
			(end 0.508 -0.9398)
			(stroke
				(width 0)
				(type default)
			)
			(fill no)
			(layer "F.CrtYd")
		)
		(fp_rect
			(start -0.508 0.9398)
			(end 0.508 -0.9398)
			(stroke
				(width 0)
				(type default)
			)
			(fill no)
			(layer "F.Fab")
		)
		(pad "1" smd custom
			(at 0 -0.4445 90)
			(size 0.1397 0.1397)
			(layers "F.Cu" "F.Mask" "F.Paste")
			(net "FANIN_12")
			(options
				(clearance outline)
				(anchor circle)
			)
			(primitives
				(gr_poly
					(pts
						(arc
							(start -0.1778 -0.2794)
							(mid -0.249642 -0.249642)
							(end -0.2794 -0.1778)
						)
						(arc
							(start -0.2794 0.1778)
							(mid -0.249642 0.249642)
							(end -0.1778 0.2794)
						)
						(arc
							(start 0.1778 0.2794)
							(mid 0.249642 0.249642)
							(end 0.2794 0.1778)
						)
						(arc
							(start 0.2794 -0.1778)
							(mid 0.249642 -0.249642)
							(end 0.1778 -0.2794)
						)
					)
					(width 0)
					(fill yes)
				)
			)
		)
		(pad "2" smd custom
			(at 0 0.4445 90)
			(size 0.1397 0.1397)
			(layers "F.Cu" "F.Mask" "F.Paste")
			(net "GND")
			(options
				(clearance outline)
				(anchor circle)
			)
			(primitives
				(gr_poly
					(pts
						(arc
							(start -0.1778 -0.2794)
							(mid -0.249642 -0.249642)
							(end -0.2794 -0.1778)
						)
						(arc
							(start -0.2794 0.1778)
							(mid -0.249642 0.249642)
							(end -0.1778 0.2794)
						)
						(arc
							(start 0.1778 0.2794)
							(mid 0.249642 0.249642)
							(end 0.2794 0.1778)
						)
						(arc
							(start 0.2794 -0.1778)
							(mid 0.249642 -0.249642)
							(end 0.1778 -0.2794)
						)
					)
					(width 0)
					(fill yes)
				)
			)
		)
	)
	(footprint ""
		(layer "F.Cu")
		(at 36.1188 -372.4656 -90)
		(property "Reference" "PR7"
			(at 0 0 270)
			(layer "F.SilkS")
			(hide yes)
			(effects
				(font
					(size 1.27 1.27)
				)
			)
		)
		(property "Value" "1KR2F-3-GP"
			(at 0.064008 -3.993896 270)
			(unlocked yes)
			(layer "F.Fab")
			(hide yes)
			(effects
				(font
					(size 1.016 1.016)
					(thickness 0.1524)
				)
			)
		)
		(property "Device Type" "R402H16"
			(at 0.064008 -5.517896 270)
			(unlocked yes)
			(layer "F.Fab")
			(hide yes)
			(effects
				(font
					(size 1.016 1.016)
					(thickness 0.1524)
				)
			)
		)
		(duplicate_pad_numbers_are_jumpers no)
		(fp_line
			(start -0.508 -0.9398)
			(end -0.508 0.9398)
			(stroke
				(width 0.1524)
				(type default)
			)
			(layer "F.SilkS")
		)
		(fp_line
			(start 0.508 -0.9398)
			(end -0.508 -0.9398)
			(stroke
				(width 0.1524)
				(type default)
			)
			(layer "F.SilkS")
		)
		(fp_rect
			(start -0.508 0.9398)
			(end 0.508 -0.9398)
			(stroke
				(width 0)
				(type default)
			)
			(fill no)
			(layer "F.CrtYd")
		)
		(fp_rect
			(start -0.508 0.9398)
			(end 0.508 -0.9398)
			(stroke
				(width 0)
				(type default)
			)
			(fill no)
			(layer "F.Fab")
		)
		(pad "1" smd custom
			(at 0 -0.4445 270)
			(size 0.1397 0.1397)
			(layers "F.Cu" "F.Mask" "F.Paste")
			(net "P12V")
			(options
				(clearance outline)
				(anchor circle)
			)
			(primitives
				(gr_poly
					(pts
						(arc
							(start -0.1778 -0.2794)
							(mid -0.249642 -0.249642)
							(end -0.2794 -0.1778)
						)
						(arc
							(start -0.2794 0.1778)
							(mid -0.249642 0.249642)
							(end -0.1778 0.2794)
						)
						(arc
							(start 0.1778 0.2794)
							(mid 0.249642 0.249642)
							(end 0.2794 0.1778)
						)
						(arc
							(start 0.2794 -0.1778)
							(mid 0.249642 -0.249642)
							(end 0.1778 -0.2794)
						)
					)
					(width 0)
					(fill yes)
				)
			)
		)
		(pad "2" smd custom
			(at 0 0.4445 270)
			(size 0.1397 0.1397)
			(layers "F.Cu" "F.Mask" "F.Paste")
			(net "ADM1276_VOUT")
			(options
				(clearance outline)
				(anchor circle)
			)
			(primitives
				(gr_poly
					(pts
						(arc
							(start -0.1778 -0.2794)
							(mid -0.249642 -0.249642)
							(end -0.2794 -0.1778)
						)
						(arc
							(start -0.2794 0.1778)
							(mid -0.249642 0.249642)
							(end -0.1778 0.2794)
						)
						(arc
							(start 0.1778 0.2794)
							(mid 0.249642 0.249642)
							(end 0.2794 0.1778)
						)
						(arc
							(start 0.2794 -0.1778)
							(mid 0.249642 -0.249642)
							(end 0.1778 -0.2794)
						)
					)
					(width 0)
					(fill yes)
				)
			)
		)
	)
	(footprint ""
		(layer "F.Cu")
		(at 4.040124 -127.340106 -90)
		(property "Reference" "CN5"
			(at 0 0 270)
			(layer "F.SilkS")
			(hide yes)
			(effects
				(font
					(size 1.27 1.27)
				)
			)
		)
		(property "Value" "JWT-CON5-42-GP"
			(at -7.8105 2.9591 270)
			(unlocked yes)
			(layer "F.Fab")
			(hide yes)
			(effects
				(font
					(size 1.016 1.016)
					(thickness 0.1524)
				)
			)
		)
		(property "Device Type" "A2541WR0-1TX5PA-6T-0E"
			(at -7.8105 1.4351 270)
			(unlocked yes)
			(layer "F.Fab")
			(hide yes)
			(effects
				(font
					(size 1.016 1.016)
					(thickness 0.1524)
				)
			)
		)
		(duplicate_pad_numbers_are_jumpers no)
		(fp_line
			(start -6.604 10.287)
			(end 6.604 10.287)
			(stroke
				(width 0.1524)
				(type default)
			)
			(layer "F.SilkS")
		)
		(fp_line
			(start 6.604 10.287)
			(end 6.604 -0.9652)
			(stroke
				(width 0.1524)
				(type default)
			)
			(layer "F.SilkS")
		)
		(fp_line
			(start -6.604 -0.9652)
			(end -6.604 10.287)
			(stroke
				(width 0.1524)
				(type default)
			)
			(layer "F.SilkS")
		)
		(fp_line
			(start 6.604 -0.9652)
			(end -6.604 -0.9652)
			(stroke
				(width 0.1524)
				(type default)
			)
			(layer "F.SilkS")
		)
		(fp_line
			(start -6.731 -1.0922)
			(end -6.731 0.1778)
			(stroke
				(width 0.4064)
				(type default)
			)
			(layer "F.SilkS")
		)
		(fp_line
			(start -5.461 -1.0922)
			(end -6.731 -1.0922)
			(stroke
				(width 0.4064)
				(type default)
			)
			(layer "F.SilkS")
		)
		(fp_circle
			(center -5.08 0)
			(end -5.08 -1.0668)
			(stroke
				(width 0.3048)
				(type default)
			)
			(fill no)
			(layer "F.SilkS")
		)
		(fp_circle
			(center -2.54 0)
			(end -2.54 -1.0668)
			(stroke
				(width 0.3048)
				(type default)
			)
			(fill no)
			(layer "F.SilkS")
		)
		(fp_circle
			(center 0 0)
			(end 0 -1.0668)
			(stroke
				(width 0.3048)
				(type default)
			)
			(fill no)
			(layer "F.SilkS")
		)
		(fp_circle
			(center 2.54 0)
			(end 2.54 -1.0668)
			(stroke
				(width 0.3048)
				(type default)
			)
			(fill no)
			(layer "F.SilkS")
		)
		(fp_circle
			(center 5.08 0)
			(end 5.08 -1.0668)
			(stroke
				(width 0.3048)
				(type default)
			)
			(fill no)
			(layer "F.SilkS")
		)
		(fp_rect
			(start -6.35 10.033)
			(end 6.35 -0.3302)
			(stroke
				(width 0)
				(type default)
			)
			(fill no)
			(layer "F.CrtYd")
		)
		(fp_poly
			(pts
				(xy -6.35 -0.3302) (xy 6.858 -0.3302) (xy 6.858 -1.2192) (xy -6.858 -1.2192) (xy -6.858 10.541)
				(xy 6.858 10.541) (xy 6.858 -0.3175) (xy 6.35 -0.3175) (xy 6.35 10.033) (xy -6.35 10.033)
			)
			(stroke
				(width 0)
				(type default)
			)
			(fill no)
			(layer "F.CrtYd")
		)
		(fp_rect
			(start -6.858 10.541)
			(end 6.858 -1.2192)
			(stroke
				(width 0)
				(type default)
			)
			(fill no)
			(layer "F.Fab")
		)
		(pad "1" thru_hole circle
			(at -5.08 0 270)
			(size 1.4224 1.4224)
			(drill 1.016)
			(layers "*.Cu" "*.Mask")
			(remove_unused_layers no)
			(net "GND")
			(clearance 0.1524)
			(thermal_gap 0.1524)
		)
		(pad "2" thru_hole circle
			(at -2.54 0 270)
			(size 1.4224 1.4224)
			(drill 1.016)
			(layers "*.Cu" "*.Mask")
			(remove_unused_layers no)
			(net "P12V_FAN5")
			(clearance 0.1524)
			(thermal_gap 0.1524)
		)
		(pad "3" thru_hole circle
			(at 0 0 270)
			(size 1.4224 1.4224)
			(drill 1.016)
			(layers "*.Cu" "*.Mask")
			(remove_unused_layers no)
			(net "FAN_TACH10")
			(clearance 0.1524)
			(thermal_gap 0.1524)
		)
		(pad "4" thru_hole circle
			(at 2.54 0 270)
			(size 1.4224 1.4224)
			(drill 1.016)
			(layers "*.Cu" "*.Mask")
			(remove_unused_layers no)
			(net "PWM_OUT_FAN5_NET")
			(clearance 0.1524)
			(thermal_gap 0.1524)
		)
		(pad "5" thru_hole circle
			(at 5.08 0 270)
			(size 1.4224 1.4224)
			(drill 1.016)
			(layers "*.Cu" "*.Mask")
			(remove_unused_layers no)
			(net "FAN_TACH9")
			(clearance 0.1524)
			(thermal_gap 0.1524)
		)
	)
	(footprint ""
		(layer "F.Cu")
		(at 14.8844 -50.6222 90)
		(property "Reference" "R175"
			(at 0 0 90)
			(layer "F.SilkS")
			(hide yes)
			(effects
				(font
					(size 1.27 1.27)
				)
			)
		)
		(property "Value" "0R2J-2-GP"
			(at 0.064008 -3.993896 90)
			(unlocked yes)
			(layer "F.Fab")
			(hide yes)
			(effects
				(font
					(size 1.016 1.016)
					(thickness 0.1524)
				)
			)
		)
		(property "Device Type" "R402H16"
			(at 0.064008 -5.517896 90)
			(unlocked yes)
			(layer "F.Fab")
			(hide yes)
			(effects
				(font
					(size 1.016 1.016)
					(thickness 0.1524)
				)
			)
		)
		(duplicate_pad_numbers_are_jumpers no)
		(fp_line
			(start 0.508 -0.9398)
			(end -0.508 -0.9398)
			(stroke
				(width 0.1524)
				(type default)
			)
			(layer "F.SilkS")
		)
		(fp_line
			(start -0.508 -0.9398)
			(end -0.508 0.9398)
			(stroke
				(width 0.1524)
				(type default)
			)
			(layer "F.SilkS")
		)
		(fp_rect
			(start -0.508 0.9398)
			(end 0.508 -0.9398)
			(stroke
				(width 0)
				(type default)
			)
			(fill no)
			(layer "F.CrtYd")
		)
		(fp_rect
			(start -0.508 0.9398)
			(end 0.508 -0.9398)
			(stroke
				(width 0)
				(type default)
			)
			(fill no)
			(layer "F.Fab")
		)
		(pad "1" smd custom
			(at 0 -0.4445 90)
			(size 0.1397 0.1397)
			(layers "F.Cu" "F.Mask" "F.Paste")
			(net "SD_LATCH_RELEASE_U")
			(options
				(clearance outline)
				(anchor circle)
			)
			(primitives
				(gr_poly
					(pts
						(arc
							(start -0.1778 -0.2794)
							(mid -0.249642 -0.249642)
							(end -0.2794 -0.1778)
						)
						(arc
							(start -0.2794 0.1778)
							(mid -0.249642 0.249642)
							(end -0.1778 0.2794)
						)
						(arc
							(start 0.1778 0.2794)
							(mid 0.249642 0.249642)
							(end 0.2794 0.1778)
						)
						(arc
							(start 0.2794 -0.1778)
							(mid 0.249642 -0.249642)
							(end 0.1778 -0.2794)
						)
					)
					(width 0)
					(fill yes)
				)
			)
		)
		(pad "2" smd custom
			(at 0 0.4445 90)
			(size 0.1397 0.1397)
			(layers "F.Cu" "F.Mask" "F.Paste")
			(net "TEMP_ALM#_REVERSE_R")
			(options
				(clearance outline)
				(anchor circle)
			)
			(primitives
				(gr_poly
					(pts
						(arc
							(start -0.1778 -0.2794)
							(mid -0.249642 -0.249642)
							(end -0.2794 -0.1778)
						)
						(arc
							(start -0.2794 0.1778)
							(mid -0.249642 0.249642)
							(end -0.1778 0.2794)
						)
						(arc
							(start 0.1778 0.2794)
							(mid 0.249642 0.249642)
							(end 0.2794 0.1778)
						)
						(arc
							(start 0.2794 -0.1778)
							(mid 0.249642 -0.249642)
							(end 0.1778 -0.2794)
						)
					)
					(width 0)
					(fill yes)
				)
			)
		)
	)
	(footprint ""
		(layer "F.Cu")
		(at 37.5666 -254.3556)
		(property "Reference" "R59"
			(at 0 0 0)
			(layer "F.SilkS")
			(hide yes)
			(effects
				(font
					(size 1.27 1.27)
				)
			)
		)
		(property "Value" "330R2J-3-GP"
			(at 0.064008 -3.993896 0)
			(unlocked yes)
			(layer "F.Fab")
			(hide yes)
			(effects
				(font
					(size 1.016 1.016)
					(thickness 0.1524)
				)
			)
		)
		(property "Device Type" "R402H16"
			(at 0.064008 -5.517896 0)
			(unlocked yes)
			(layer "F.Fab")
			(hide yes)
			(effects
				(font
					(size 1.016 1.016)
					(thickness 0.1524)
				)
			)
		)
		(duplicate_pad_numbers_are_jumpers no)
		(fp_line
			(start -0.508 -0.9398)
			(end -0.508 0.9398)
			(stroke
				(width 0.1524)
				(type default)
			)
			(layer "F.SilkS")
		)
		(fp_line
			(start 0.508 -0.9398)
			(end -0.508 -0.9398)
			(stroke
				(width 0.1524)
				(type default)
			)
			(layer "F.SilkS")
		)
		(fp_rect
			(start -0.508 0.9398)
			(end 0.508 -0.9398)
			(stroke
				(width 0)
				(type default)
			)
			(fill no)
			(layer "F.CrtYd")
		)
		(fp_rect
			(start -0.508 0.9398)
			(end 0.508 -0.9398)
			(stroke
				(width 0)
				(type default)
			)
			(fill no)
			(layer "F.Fab")
		)
		(pad "1" smd custom
			(at 0 -0.4445)
			(size 0.1397 0.1397)
			(layers "F.Cu" "F.Mask" "F.Paste")
			(net "P3V3")
			(options
				(clearance outline)
				(anchor circle)
			)
			(primitives
				(gr_poly
					(pts
						(arc
							(start -0.1778 -0.2794)
							(mid -0.249642 -0.249642)
							(end -0.2794 -0.1778)
						)
						(arc
							(start -0.2794 0.1778)
							(mid -0.249642 0.249642)
							(end -0.1778 0.2794)
						)
						(arc
							(start 0.1778 0.2794)
							(mid 0.249642 0.249642)
							(end 0.2794 0.1778)
						)
						(arc
							(start 0.2794 -0.1778)
							(mid 0.249642 -0.249642)
							(end 0.1778 -0.2794)
						)
					)
					(width 0)
					(fill yes)
				)
			)
		)
		(pad "2" smd custom
			(at 0 0.4445)
			(size 0.1397 0.1397)
			(layers "F.Cu" "F.Mask" "F.Paste")
			(net "LED_DR_LED7_RESERVE")
			(options
				(clearance outline)
				(anchor circle)
			)
			(primitives
				(gr_poly
					(pts
						(arc
							(start -0.1778 -0.2794)
							(mid -0.249642 -0.249642)
							(end -0.2794 -0.1778)
						)
						(arc
							(start -0.2794 0.1778)
							(mid -0.249642 0.249642)
							(end -0.1778 0.2794)
						)
						(arc
							(start 0.1778 0.2794)
							(mid 0.249642 0.249642)
							(end 0.2794 0.1778)
						)
						(arc
							(start 0.2794 -0.1778)
							(mid 0.249642 -0.249642)
							(end 0.1778 -0.2794)
						)
					)
					(width 0)
					(fill yes)
				)
			)
		)
	)
	(footprint ""
		(layer "F.Cu")
		(at 5.4102 -431.5968 90)
		(property "Reference" "R127"
			(at 0 0 90)
			(layer "F.SilkS")
			(hide yes)
			(effects
				(font
					(size 1.27 1.27)
				)
			)
		)
		(property "Value" "1K8R6J-GP"
			(at -0.0508 -4.8514 90)
			(unlocked yes)
			(layer "F.Fab")
			(hide yes)
			(effects
				(font
					(size 1.016 1.016)
					(thickness 0.1524)
				)
			)
		)
		(property "Device Type" "R1206H28"
			(at 0 -6.3754 90)
			(unlocked yes)
			(layer "F.Fab")
			(hide yes)
			(effects
				(font
					(size 1.016 1.016)
					(thickness 0.1524)
				)
			)
		)
		(duplicate_pad_numbers_are_jumpers no)
		(fp_line
			(start 1.016 -2.2352)
			(end 1.016 2.2352)
			(stroke
				(width 0.1524)
				(type default)
			)
			(layer "F.SilkS")
		)
		(fp_line
			(start -1.016 -2.2352)
			(end 1.016 -2.2352)
			(stroke
				(width 0.1524)
				(type default)
			)
			(layer "F.SilkS")
		)
		(fp_line
			(start 1.016 2.2352)
			(end -1.016 2.2352)
			(stroke
				(width 0.1524)
				(type default)
			)
			(layer "F.SilkS")
		)
		(fp_line
			(start -1.016 2.2352)
			(end -1.016 -2.2352)
			(stroke
				(width 0.1524)
				(type default)
			)
			(layer "F.SilkS")
		)
		(fp_rect
			(start -1.0922 2.3114)
			(end 1.0922 -2.3114)
			(stroke
				(width 0)
				(type default)
			)
			(fill no)
			(layer "F.CrtYd")
		)
		(fp_poly
			(pts
				(xy -1.0922 -2.3114) (xy 1.0922 -2.3114) (xy 1.0922 2.3114) (xy -1.0922 2.3114)
			)
			(stroke
				(width 0)
				(type default)
			)
			(fill no)
			(layer "F.Fab")
		)
		(pad "1" smd rect
			(at 0 -1.397 90)
			(size 1.651 1.27)
			(layers "F.Cu" "F.Mask" "F.Paste")
			(net "P12V")
		)
		(pad "2" smd rect
			(at 0 1.397 90)
			(size 1.651 1.27)
			(layers "F.Cu" "F.Mask" "F.Paste")
			(net "LED_DR_LED0_BLUE")
		)
	)
	(footprint ""
		(layer "F.Cu")
		(at 26.416 -374.523 -90)
		(property "Reference" "PC1"
			(at 0 0 270)
			(layer "F.SilkS")
			(hide yes)
			(effects
				(font
					(size 1.27 1.27)
				)
			)
		)
		(property "Value" "SC1U25V3KX-1-GP"
			(at 0 -2.8194 270)
			(unlocked yes)
			(layer "F.Fab")
			(hide yes)
			(effects
				(font
					(size 1.016 1.016)
					(thickness 0.1524)
				)
			)
		)
		(property "Device Type" "C603H36"
			(at 0 -4.3434 270)
			(unlocked yes)
			(layer "F.Fab")
			(hide yes)
			(effects
				(font
					(size 1.016 1.016)
					(thickness 0.1524)
				)
			)
		)
		(duplicate_pad_numbers_are_jumpers no)
		(fp_line
			(start 0.508 0)
			(end -0.508 0)
			(stroke
				(width 0.2032)
				(type default)
			)
			(layer "F.SilkS")
		)
		(fp_rect
			(start -0.5842 1.3335)
			(end 0.5842 -1.3335)
			(stroke
				(width 0)
				(type default)
			)
			(fill no)
			(layer "F.CrtYd")
		)
		(fp_rect
			(start -0.5842 1.3335)
			(end 0.5842 -1.3335)
			(stroke
				(width 0)
				(type default)
			)
			(fill no)
			(layer "F.Fab")
		)
		(pad "1" smd custom
			(at 0 -0.762 270)
			(size 0.2159 0.2159)
			(layers "F.Cu" "F.Mask" "F.Paste")
			(net "ADM1276_VCC")
			(options
				(clearance outline)
				(anchor circle)
			)
			(primitives
				(gr_poly
					(pts
						(arc
							(start -0.3302 -0.4318)
							(mid -0.402042 -0.402042)
							(end -0.4318 -0.3302)
						)
						(arc
							(start -0.4318 0.3302)
							(mid -0.402042 0.402042)
							(end -0.3302 0.4318)
						)
						(arc
							(start 0.3302 0.4318)
							(mid 0.402042 0.402042)
							(end 0.4318 0.3302)
						)
						(arc
							(start 0.4318 -0.3302)
							(mid 0.402042 -0.402042)
							(end 0.3302 -0.4318)
						)
					)
					(width 0)
					(fill yes)
				)
			)
		)
		(pad "2" smd custom
			(at 0 0.762 270)
			(size 0.2159 0.2159)
			(layers "F.Cu" "F.Mask" "F.Paste")
			(net "GND")
			(options
				(clearance outline)
				(anchor circle)
			)
			(primitives
				(gr_poly
					(pts
						(arc
							(start -0.3302 -0.4318)
							(mid -0.402042 -0.402042)
							(end -0.4318 -0.3302)
						)
						(arc
							(start -0.4318 0.3302)
							(mid -0.402042 0.402042)
							(end -0.3302 0.4318)
						)
						(arc
							(start 0.3302 0.4318)
							(mid 0.402042 0.402042)
							(end 0.4318 0.3302)
						)
						(arc
							(start 0.4318 -0.3302)
							(mid 0.402042 -0.402042)
							(end 0.3302 -0.4318)
						)
					)
					(width 0)
					(fill yes)
				)
			)
		)
	)
	(footprint ""
		(layer "F.Cu")
		(at 12.9794 -449.5292 90)
		(property "Reference" "R105"
			(at 0 0 90)
			(layer "F.SilkS")
			(hide yes)
			(effects
				(font
					(size 1.27 1.27)
				)
			)
		)
		(property "Value" "10KR2F-2-GP"
			(at 0.064008 -3.993896 90)
			(unlocked yes)
			(layer "F.Fab")
			(hide yes)
			(effects
				(font
					(size 1.016 1.016)
					(thickness 0.1524)
				)
			)
		)
		(property "Device Type" "R402H16"
			(at 0.064008 -5.517896 90)
			(unlocked yes)
			(layer "F.Fab")
			(hide yes)
			(effects
				(font
					(size 1.016 1.016)
					(thickness 0.1524)
				)
			)
		)
		(duplicate_pad_numbers_are_jumpers no)
		(fp_line
			(start 0.508 -0.9398)
			(end -0.508 -0.9398)
			(stroke
				(width 0.1524)
				(type default)
			)
			(layer "F.SilkS")
		)
		(fp_line
			(start -0.508 -0.9398)
			(end -0.508 0.9398)
			(stroke
				(width 0.1524)
				(type default)
			)
			(layer "F.SilkS")
		)
		(fp_rect
			(start -0.508 0.9398)
			(end 0.508 -0.9398)
			(stroke
				(width 0)
				(type default)
			)
			(fill no)
			(layer "F.CrtYd")
		)
		(fp_rect
			(start -0.508 0.9398)
			(end 0.508 -0.9398)
			(stroke
				(width 0)
				(type default)
			)
			(fill no)
			(layer "F.Fab")
		)
		(pad "1" smd custom
			(at 0 -0.4445 90)
			(size 0.1397 0.1397)
			(layers "F.Cu" "F.Mask" "F.Paste")
			(net "FANIN_2")
			(options
				(clearance outline)
				(anchor circle)
			)
			(primitives
				(gr_poly
					(pts
						(arc
							(start -0.1778 -0.2794)
							(mid -0.249642 -0.249642)
							(end -0.2794 -0.1778)
						)
						(arc
							(start -0.2794 0.1778)
							(mid -0.249642 0.249642)
							(end -0.1778 0.2794)
						)
						(arc
							(start 0.1778 0.2794)
							(mid 0.249642 0.249642)
							(end 0.2794 0.1778)
						)
						(arc
							(start 0.2794 -0.1778)
							(mid 0.249642 -0.249642)
							(end 0.1778 -0.2794)
						)
					)
					(width 0)
					(fill yes)
				)
			)
		)
		(pad "2" smd custom
			(at 0 0.4445 90)
			(size 0.1397 0.1397)
			(layers "F.Cu" "F.Mask" "F.Paste")
			(net "GND")
			(options
				(clearance outline)
				(anchor circle)
			)
			(primitives
				(gr_poly
					(pts
						(arc
							(start -0.1778 -0.2794)
							(mid -0.249642 -0.249642)
							(end -0.2794 -0.1778)
						)
						(arc
							(start -0.2794 0.1778)
							(mid -0.249642 0.249642)
							(end -0.1778 0.2794)
						)
						(arc
							(start 0.1778 0.2794)
							(mid 0.249642 0.249642)
							(end 0.2794 0.1778)
						)
						(arc
							(start 0.2794 -0.1778)
							(mid 0.249642 -0.249642)
							(end 0.1778 -0.2794)
						)
					)
					(width 0)
					(fill yes)
				)
			)
		)
	)
	(footprint ""
		(layer "F.Cu")
		(at 4.040124 -482.700076 -90)
		(property "Reference" "CN1"
			(at 0 0 270)
			(layer "F.SilkS")
			(hide yes)
			(effects
				(font
					(size 1.27 1.27)
				)
			)
		)
		(property "Value" "JWT-CON5-42-GP"
			(at -7.8105 2.9591 270)
			(unlocked yes)
			(layer "F.Fab")
			(hide yes)
			(effects
				(font
					(size 1.016 1.016)
					(thickness 0.1524)
				)
			)
		)
		(property "Device Type" "A2541WR0-1TX5PA-6T-0E"
			(at -7.8105 1.4351 270)
			(unlocked yes)
			(layer "F.Fab")
			(hide yes)
			(effects
				(font
					(size 1.016 1.016)
					(thickness 0.1524)
				)
			)
		)
		(duplicate_pad_numbers_are_jumpers no)
		(fp_line
			(start -6.604 10.287)
			(end 6.604 10.287)
			(stroke
				(width 0.1524)
				(type default)
			)
			(layer "F.SilkS")
		)
		(fp_line
			(start 6.604 10.287)
			(end 6.604 -0.9652)
			(stroke
				(width 0.1524)
				(type default)
			)
			(layer "F.SilkS")
		)
		(fp_line
			(start -6.604 -0.9652)
			(end -6.604 10.287)
			(stroke
				(width 0.1524)
				(type default)
			)
			(layer "F.SilkS")
		)
		(fp_line
			(start 6.604 -0.9652)
			(end -6.604 -0.9652)
			(stroke
				(width 0.1524)
				(type default)
			)
			(layer "F.SilkS")
		)
		(fp_line
			(start -6.731 -1.0922)
			(end -6.731 0.1778)
			(stroke
				(width 0.4064)
				(type default)
			)
			(layer "F.SilkS")
		)
		(fp_line
			(start -5.461 -1.0922)
			(end -6.731 -1.0922)
			(stroke
				(width 0.4064)
				(type default)
			)
			(layer "F.SilkS")
		)
		(fp_circle
			(center -5.08 0)
			(end -5.08 -1.0668)
			(stroke
				(width 0.3048)
				(type default)
			)
			(fill no)
			(layer "F.SilkS")
		)
		(fp_circle
			(center -2.54 0)
			(end -2.54 -1.0668)
			(stroke
				(width 0.3048)
				(type default)
			)
			(fill no)
			(layer "F.SilkS")
		)
		(fp_circle
			(center 0 0)
			(end 0 -1.0668)
			(stroke
				(width 0.3048)
				(type default)
			)
			(fill no)
			(layer "F.SilkS")
		)
		(fp_circle
			(center 2.54 0)
			(end 2.54 -1.0668)
			(stroke
				(width 0.3048)
				(type default)
			)
			(fill no)
			(layer "F.SilkS")
		)
		(fp_circle
			(center 5.08 0)
			(end 5.08 -1.0668)
			(stroke
				(width 0.3048)
				(type default)
			)
			(fill no)
			(layer "F.SilkS")
		)
		(fp_rect
			(start -6.35 10.033)
			(end 6.35 -0.3302)
			(stroke
				(width 0)
				(type default)
			)
			(fill no)
			(layer "F.CrtYd")
		)
		(fp_poly
			(pts
				(xy -6.35 -0.3302) (xy 6.858 -0.3302) (xy 6.858 -1.2192) (xy -6.858 -1.2192) (xy -6.858 10.541)
				(xy 6.858 10.541) (xy 6.858 -0.3175) (xy 6.35 -0.3175) (xy 6.35 10.033) (xy -6.35 10.033)
			)
			(stroke
				(width 0)
				(type default)
			)
			(fill no)
			(layer "F.CrtYd")
		)
		(fp_rect
			(start -6.858 10.541)
			(end 6.858 -1.2192)
			(stroke
				(width 0)
				(type default)
			)
			(fill no)
			(layer "F.Fab")
		)
		(pad "1" thru_hole circle
			(at -5.08 0 270)
			(size 1.4224 1.4224)
			(drill 1.016)
			(layers "*.Cu" "*.Mask")
			(remove_unused_layers no)
			(net "GND")
			(clearance 0.1524)
			(thermal_gap 0.1524)
		)
		(pad "2" thru_hole circle
			(at -2.54 0 270)
			(size 1.4224 1.4224)
			(drill 1.016)
			(layers "*.Cu" "*.Mask")
			(remove_unused_layers no)
			(net "P12V_FAN1")
			(clearance 0.1524)
			(thermal_gap 0.1524)
		)
		(pad "3" thru_hole circle
			(at 0 0 270)
			(size 1.4224 1.4224)
			(drill 1.016)
			(layers "*.Cu" "*.Mask")
			(remove_unused_layers no)
			(net "FAN_TACH2")
			(clearance 0.1524)
			(thermal_gap 0.1524)
		)
		(pad "4" thru_hole circle
			(at 2.54 0 270)
			(size 1.4224 1.4224)
			(drill 1.016)
			(layers "*.Cu" "*.Mask")
			(remove_unused_layers no)
			(net "PWM_OUT_FAN1_NET")
			(clearance 0.1524)
			(thermal_gap 0.1524)
		)
		(pad "5" thru_hole circle
			(at 5.08 0 270)
			(size 1.4224 1.4224)
			(drill 1.016)
			(layers "*.Cu" "*.Mask")
			(remove_unused_layers no)
			(net "FAN_TACH1")
			(clearance 0.1524)
			(thermal_gap 0.1524)
		)
	)
	(footprint ""
		(layer "F.Cu")
		(at 30.3784 -111.125 90)
		(property "Reference" "PR102"
			(at 0 0 90)
			(layer "F.SilkS")
			(hide yes)
			(effects
				(font
					(size 1.27 1.27)
				)
			)
		)
		(property "Value" "10R2F-L-GP"
			(at 0.064008 -3.993896 90)
			(unlocked yes)
			(layer "F.Fab")
			(hide yes)
			(effects
				(font
					(size 1.016 1.016)
					(thickness 0.1524)
				)
			)
		)
		(property "Device Type" "R402H14"
			(at 0.064008 -5.517896 90)
			(unlocked yes)
			(layer "F.Fab")
			(hide yes)
			(effects
				(font
					(size 1.016 1.016)
					(thickness 0.1524)
				)
			)
		)
		(duplicate_pad_numbers_are_jumpers no)
		(fp_line
			(start 0.508 -0.9398)
			(end -0.508 -0.9398)
			(stroke
				(width 0.1524)
				(type default)
			)
			(layer "F.SilkS")
		)
		(fp_line
			(start -0.508 -0.9398)
			(end -0.508 0.9398)
			(stroke
				(width 0.1524)
				(type default)
			)
			(layer "F.SilkS")
		)
		(fp_rect
			(start -0.508 0.9398)
			(end 0.508 -0.9398)
			(stroke
				(width 0)
				(type default)
			)
			(fill no)
			(layer "F.CrtYd")
		)
		(fp_rect
			(start -0.508 0.9398)
			(end 0.508 -0.9398)
			(stroke
				(width 0)
				(type default)
			)
			(fill no)
			(layer "F.Fab")
		)
		(pad "1" smd custom
			(at 0 -0.4445 90)
			(size 0.1397 0.1397)
			(layers "F.Cu" "F.Mask" "F.Paste")
			(net "P12VU_2490_GATE_DRV")
			(options
				(clearance outline)
				(anchor circle)
			)
			(primitives
				(gr_poly
					(pts
						(arc
							(start -0.1778 -0.2794)
							(mid -0.249642 -0.249642)
							(end -0.2794 -0.1778)
						)
						(arc
							(start -0.2794 0.1778)
							(mid -0.249642 0.249642)
							(end -0.1778 0.2794)
						)
						(arc
							(start 0.1778 0.2794)
							(mid 0.249642 0.249642)
							(end 0.2794 0.1778)
						)
						(arc
							(start 0.2794 -0.1778)
							(mid 0.249642 -0.249642)
							(end 0.1778 -0.2794)
						)
					)
					(width 0)
					(fill yes)
				)
			)
		)
		(pad "2" smd custom
			(at 0 0.4445 90)
			(size 0.1397 0.1397)
			(layers "F.Cu" "F.Mask" "F.Paste")
			(net "P12VU_2490_GATE")
			(options
				(clearance outline)
				(anchor circle)
			)
			(primitives
				(gr_poly
					(pts
						(arc
							(start -0.1778 -0.2794)
							(mid -0.249642 -0.249642)
							(end -0.2794 -0.1778)
						)
						(arc
							(start -0.2794 0.1778)
							(mid -0.249642 0.249642)
							(end -0.1778 0.2794)
						)
						(arc
							(start 0.1778 0.2794)
							(mid 0.249642 0.249642)
							(end 0.2794 0.1778)
						)
						(arc
							(start 0.2794 -0.1778)
							(mid 0.249642 -0.249642)
							(end 0.1778 -0.2794)
						)
					)
					(width 0)
					(fill yes)
				)
			)
		)
	)
	(footprint ""
		(layer "F.Cu")
		(at 33.909 -374.396)
		(property "Reference" "PC6"
			(at 0 0 0)
			(layer "F.SilkS")
			(hide yes)
			(effects
				(font
					(size 1.27 1.27)
				)
			)
		)
		(property "Value" "SCD022U50V3KX-2-GP"
			(at 0 -2.8194 0)
			(unlocked yes)
			(layer "F.Fab")
			(hide yes)
			(effects
				(font
					(size 1.016 1.016)
					(thickness 0.1524)
				)
			)
		)
		(property "Device Type" "C603"
			(at 0 -4.3434 0)
			(unlocked yes)
			(layer "F.Fab")
			(hide yes)
			(effects
				(font
					(size 1.016 1.016)
					(thickness 0.1524)
				)
			)
		)
		(duplicate_pad_numbers_are_jumpers no)
		(fp_line
			(start 0.508 0)
			(end -0.508 0)
			(stroke
				(width 0.2032)
				(type default)
			)
			(layer "F.SilkS")
		)
		(fp_rect
			(start -0.5842 1.3335)
			(end 0.5842 -1.3335)
			(stroke
				(width 0)
				(type default)
			)
			(fill no)
			(layer "F.CrtYd")
		)
		(fp_rect
			(start -0.5842 1.3335)
			(end 0.5842 -1.3335)
			(stroke
				(width 0)
				(type default)
			)
			(fill no)
			(layer "F.Fab")
		)
		(pad "1" smd custom
			(at 0 -0.762)
			(size 0.2159 0.2159)
			(layers "F.Cu" "F.Mask" "F.Paste")
			(net "ADM1276_GATE_RC")
			(options
				(clearance outline)
				(anchor circle)
			)
			(primitives
				(gr_poly
					(pts
						(arc
							(start -0.3302 -0.4318)
							(mid -0.402042 -0.402042)
							(end -0.4318 -0.3302)
						)
						(arc
							(start -0.4318 0.3302)
							(mid -0.402042 0.402042)
							(end -0.3302 0.4318)
						)
						(arc
							(start 0.3302 0.4318)
							(mid 0.402042 0.402042)
							(end 0.4318 0.3302)
						)
						(arc
							(start 0.4318 -0.3302)
							(mid 0.402042 -0.402042)
							(end 0.3302 -0.4318)
						)
					)
					(width 0)
					(fill yes)
				)
			)
		)
		(pad "2" smd custom
			(at 0 0.762)
			(size 0.2159 0.2159)
			(layers "F.Cu" "F.Mask" "F.Paste")
			(net "GND")
			(options
				(clearance outline)
				(anchor circle)
			)
			(primitives
				(gr_poly
					(pts
						(arc
							(start -0.3302 -0.4318)
							(mid -0.402042 -0.402042)
							(end -0.4318 -0.3302)
						)
						(arc
							(start -0.4318 0.3302)
							(mid -0.402042 0.402042)
							(end -0.3302 0.4318)
						)
						(arc
							(start 0.3302 0.4318)
							(mid 0.402042 0.402042)
							(end 0.4318 0.3302)
						)
						(arc
							(start 0.4318 -0.3302)
							(mid 0.402042 -0.402042)
							(end 0.3302 -0.4318)
						)
					)
					(width 0)
					(fill yes)
				)
			)
		)
	)
	(footprint ""
		(layer "F.Cu")
		(at 7.8232 -449.5546 90)
		(property "Reference" "R100"
			(at 0 0 90)
			(layer "F.SilkS")
			(hide yes)
			(effects
				(font
					(size 1.27 1.27)
				)
			)
		)
		(property "Value" "27KR3F-GP"
			(at -0.0254 -2.5146 90)
			(unlocked yes)
			(layer "F.Fab")
			(hide yes)
			(effects
				(font
					(size 1.016 1.016)
					(thickness 0.1524)
				)
			)
		)
		(property "Device Type" "R603H22"
			(at -0.0254 -4.0386 90)
			(unlocked yes)
			(layer "F.Fab")
			(hide yes)
			(effects
				(font
					(size 1.016 1.016)
					(thickness 0.1524)
				)
			)
		)
		(duplicate_pad_numbers_are_jumpers no)
		(fp_line
			(start 0.2032 0)
			(end 0.4826 0)
			(stroke
				(width 0.2032)
				(type default)
			)
			(layer "F.SilkS")
		)
		(fp_line
			(start -0.4826 0)
			(end -0.2032 0)
			(stroke
				(width 0.2032)
				(type default)
			)
			(layer "F.SilkS")
		)
		(fp_rect
			(start -0.5842 1.3335)
			(end 0.5842 -1.3335)
			(stroke
				(width 0)
				(type default)
			)
			(fill no)
			(layer "F.CrtYd")
		)
		(fp_rect
			(start -0.5842 1.3335)
			(end 0.5842 -1.3335)
			(stroke
				(width 0)
				(type default)
			)
			(fill no)
			(layer "F.Fab")
		)
		(pad "1" smd custom
			(at 0 -0.762 90)
			(size 0.2159 0.2159)
			(layers "F.Cu" "F.Mask" "F.Paste")
			(net "FANIN_1")
			(options
				(clearance outline)
				(anchor circle)
			)
			(primitives
				(gr_poly
					(pts
						(arc
							(start -0.3302 -0.4318)
							(mid -0.402042 -0.402042)
							(end -0.4318 -0.3302)
						)
						(arc
							(start -0.4318 0.3302)
							(mid -0.402042 0.402042)
							(end -0.3302 0.4318)
						)
						(arc
							(start 0.3302 0.4318)
							(mid 0.402042 0.402042)
							(end 0.4318 0.3302)
						)
						(arc
							(start 0.4318 -0.3302)
							(mid 0.402042 -0.402042)
							(end 0.3302 -0.4318)
						)
					)
					(width 0)
					(fill yes)
				)
			)
		)
		(pad "2" smd custom
			(at 0 0.762 90)
			(size 0.2159 0.2159)
			(layers "F.Cu" "F.Mask" "F.Paste")
			(net "FAN_TACH1")
			(options
				(clearance outline)
				(anchor circle)
			)
			(primitives
				(gr_poly
					(pts
						(arc
							(start -0.3302 -0.4318)
							(mid -0.402042 -0.402042)
							(end -0.4318 -0.3302)
						)
						(arc
							(start -0.4318 0.3302)
							(mid -0.402042 0.402042)
							(end -0.3302 0.4318)
						)
						(arc
							(start 0.3302 0.4318)
							(mid 0.402042 0.402042)
							(end 0.4318 0.3302)
						)
						(arc
							(start 0.4318 -0.3302)
							(mid 0.402042 -0.402042)
							(end 0.3302 -0.4318)
						)
					)
					(width 0)
					(fill yes)
				)
			)
		)
	)
	(footprint ""
		(layer "F.Cu")
		(at 21.766784 -214.4014 90)
		(property "Reference" "R130"
			(at 0 0 90)
			(layer "F.SilkS")
			(hide yes)
			(effects
				(font
					(size 1.27 1.27)
				)
			)
		)
		(property "Value" "4K7R2F-GP"
			(at 0.064008 -3.993896 90)
			(unlocked yes)
			(layer "F.Fab")
			(hide yes)
			(effects
				(font
					(size 1.016 1.016)
					(thickness 0.1524)
				)
			)
		)
		(property "Device Type" "R402H16"
			(at 0.064008 -5.517896 90)
			(unlocked yes)
			(layer "F.Fab")
			(hide yes)
			(effects
				(font
					(size 1.016 1.016)
					(thickness 0.1524)
				)
			)
		)
		(duplicate_pad_numbers_are_jumpers no)
		(fp_line
			(start 0.508 -0.9398)
			(end -0.508 -0.9398)
			(stroke
				(width 0.1524)
				(type default)
			)
			(layer "F.SilkS")
		)
		(fp_line
			(start -0.508 -0.9398)
			(end -0.508 0.9398)
			(stroke
				(width 0.1524)
				(type default)
			)
			(layer "F.SilkS")
		)
		(fp_rect
			(start -0.508 0.9398)
			(end 0.508 -0.9398)
			(stroke
				(width 0)
				(type default)
			)
			(fill no)
			(layer "F.CrtYd")
		)
		(fp_rect
			(start -0.508 0.9398)
			(end 0.508 -0.9398)
			(stroke
				(width 0)
				(type default)
			)
			(fill no)
			(layer "F.Fab")
		)
		(pad "1" smd custom
			(at 0 -0.4445 90)
			(size 0.1397 0.1397)
			(layers "F.Cu" "F.Mask" "F.Paste")
			(net "P3V3")
			(options
				(clearance outline)
				(anchor circle)
			)
			(primitives
				(gr_poly
					(pts
						(arc
							(start -0.1778 -0.2794)
							(mid -0.249642 -0.249642)
							(end -0.2794 -0.1778)
						)
						(arc
							(start -0.2794 0.1778)
							(mid -0.249642 0.249642)
							(end -0.1778 0.2794)
						)
						(arc
							(start 0.1778 0.2794)
							(mid 0.249642 0.249642)
							(end 0.2794 0.1778)
						)
						(arc
							(start 0.2794 -0.1778)
							(mid 0.249642 -0.249642)
							(end 0.1778 -0.2794)
						)
					)
					(width 0)
					(fill yes)
				)
			)
		)
		(pad "2" smd custom
			(at 0 0.4445 90)
			(size 0.1397 0.1397)
			(layers "F.Cu" "F.Mask" "F.Paste")
			(net "PWM_OUT_FAN6")
			(options
				(clearance outline)
				(anchor circle)
			)
			(primitives
				(gr_poly
					(pts
						(arc
							(start -0.1778 -0.2794)
							(mid -0.249642 -0.249642)
							(end -0.2794 -0.1778)
						)
						(arc
							(start -0.2794 0.1778)
							(mid -0.249642 0.249642)
							(end -0.1778 0.2794)
						)
						(arc
							(start 0.1778 0.2794)
							(mid 0.249642 0.249642)
							(end 0.2794 0.1778)
						)
						(arc
							(start 0.2794 -0.1778)
							(mid 0.249642 -0.249642)
							(end 0.1778 -0.2794)
						)
					)
					(width 0)
					(fill yes)
				)
			)
		)
	)
	(footprint ""
		(layer "F.Cu")
		(at 37.999924 -56.999886 -90)
		(property "Reference" "CN10"
			(at 0 0 270)
			(layer "F.SilkS")
			(hide yes)
			(effects
				(font
					(size 1.27 1.27)
				)
			)
		)
		(property "Value" "FCI-CONN52-4R-1-GP"
			(at -30.89656 -6.096 270)
			(unlocked yes)
			(layer "F.Fab")
			(hide yes)
			(effects
				(font
					(size 1.016 1.016)
					(thickness 0.1524)
				)
			)
		)
		(property "Device Type" "51952-220LF"
			(at -30.89656 -7.62 270)
			(unlocked yes)
			(layer "F.Fab")
			(hide yes)
			(effects
				(font
					(size 1.016 1.016)
					(thickness 0.1524)
				)
			)
		)
		(duplicate_pad_numbers_are_jumpers no)
		(fp_line
			(start -29.464 3.7338)
			(end -29.464 -3.7338)
			(stroke
				(width 0.1524)
				(type default)
			)
			(layer "F.SilkS")
		)
		(fp_line
			(start 29.464 3.7338)
			(end -29.464 3.7338)
			(stroke
				(width 0.1524)
				(type default)
			)
			(layer "F.SilkS")
		)
		(fp_line
			(start -29.464 -3.7338)
			(end -22.225 -3.7338)
			(stroke
				(width 0.1524)
				(type default)
			)
			(layer "F.SilkS")
		)
		(fp_line
			(start -22.225 -3.7338)
			(end -22.225 -11.3538)
			(stroke
				(width 0.1524)
				(type default)
			)
			(layer "F.SilkS")
		)
		(fp_line
			(start 22.225 -3.7338)
			(end 29.464 -3.7338)
			(stroke
				(width 0.1524)
				(type default)
			)
			(layer "F.SilkS")
		)
		(fp_line
			(start 29.464 -3.7338)
			(end 29.464 3.7338)
			(stroke
				(width 0.1524)
				(type default)
			)
			(layer "F.SilkS")
		)
		(fp_line
			(start -22.225 -11.3538)
			(end 22.225 -11.3538)
			(stroke
				(width 0.1524)
				(type default)
			)
			(layer "F.SilkS")
		)
		(fp_line
			(start 22.225 -11.3538)
			(end 22.225 -3.7338)
			(stroke
				(width 0.1524)
				(type default)
			)
			(layer "F.SilkS")
		)
		(fp_circle
			(center -15.88008 0)
			(end -15.88008 -1.0795)
			(stroke
				(width 0.3048)
				(type default)
			)
			(fill no)
			(layer "F.SilkS")
		)
		(fp_circle
			(center -13.34008 0)
			(end -13.34008 -1.0795)
			(stroke
				(width 0.3048)
				(type default)
			)
			(fill no)
			(layer "F.SilkS")
		)
		(fp_circle
			(center -10.80008 0)
			(end -10.80008 -1.0795)
			(stroke
				(width 0.3048)
				(type default)
			)
			(fill no)
			(layer "F.SilkS")
		)
		(fp_circle
			(center -8.26008 0)
			(end -8.26008 -1.0795)
			(stroke
				(width 0.3048)
				(type default)
			)
			(fill no)
			(layer "F.SilkS")
		)
		(fp_circle
			(center -5.08 0)
			(end -5.08 -1.0795)
			(stroke
				(width 0.3048)
				(type default)
			)
			(fill no)
			(layer "F.SilkS")
		)
		(fp_circle
			(center -2.54 0)
			(end -2.54 -1.0795)
			(stroke
				(width 0.3048)
				(type default)
			)
			(fill no)
			(layer "F.SilkS")
		)
		(fp_circle
			(center 0 0)
			(end 0 -1.0795)
			(stroke
				(width 0.3048)
				(type default)
			)
			(fill no)
			(layer "F.SilkS")
		)
		(fp_circle
			(center 2.54 0)
			(end 2.54 -1.0795)
			(stroke
				(width 0.3048)
				(type default)
			)
			(fill no)
			(layer "F.SilkS")
		)
		(fp_circle
			(center 5.08 0)
			(end 5.08 -1.0795)
			(stroke
				(width 0.3048)
				(type default)
			)
			(fill no)
			(layer "F.SilkS")
		)
		(fp_circle
			(center 8.26008 0)
			(end 8.26008 -1.0795)
			(stroke
				(width 0.3048)
				(type default)
			)
			(fill no)
			(layer "F.SilkS")
		)
		(fp_circle
			(center 10.80008 0)
			(end 10.80008 -1.0795)
			(stroke
				(width 0.3048)
				(type default)
			)
			(fill no)
			(layer "F.SilkS")
		)
		(fp_circle
			(center 13.34008 0)
			(end 13.34008 -1.0795)
			(stroke
				(width 0.3048)
				(type default)
			)
			(fill no)
			(layer "F.SilkS")
		)
		(fp_circle
			(center 15.88008 0)
			(end 15.88008 -1.0795)
			(stroke
				(width 0.3048)
				(type default)
			)
			(fill no)
			(layer "F.SilkS")
		)
		(fp_circle
			(center -15.88008 -2.54)
			(end -15.88008 -3.6195)
			(stroke
				(width 0.3048)
				(type default)
			)
			(fill no)
			(layer "F.SilkS")
		)
		(fp_circle
			(center -13.34008 -2.54)
			(end -13.34008 -3.6195)
			(stroke
				(width 0.3048)
				(type default)
			)
			(fill no)
			(layer "F.SilkS")
		)
		(fp_circle
			(center -10.80008 -2.54)
			(end -10.80008 -3.6195)
			(stroke
				(width 0.3048)
				(type default)
			)
			(fill no)
			(layer "F.SilkS")
		)
		(fp_circle
			(center -8.26008 -2.54)
			(end -8.26008 -3.6195)
			(stroke
				(width 0.3048)
				(type default)
			)
			(fill no)
			(layer "F.SilkS")
		)
		(fp_circle
			(center -5.08 -2.54)
			(end -5.08 -3.6195)
			(stroke
				(width 0.3048)
				(type default)
			)
			(fill no)
			(layer "F.SilkS")
		)
		(fp_circle
			(center -2.54 -2.54)
			(end -2.54 -3.6195)
			(stroke
				(width 0.3048)
				(type default)
			)
			(fill no)
			(layer "F.SilkS")
		)
		(fp_circle
			(center 0 -2.54)
			(end 0 -3.6195)
			(stroke
				(width 0.3048)
				(type default)
			)
			(fill no)
			(layer "F.SilkS")
		)
		(fp_circle
			(center 2.54 -2.54)
			(end 2.54 -3.6195)
			(stroke
				(width 0.3048)
				(type default)
			)
			(fill no)
			(layer "F.SilkS")
		)
		(fp_circle
			(center 5.08 -2.54)
			(end 5.08 -3.6195)
			(stroke
				(width 0.3048)
				(type default)
			)
			(fill no)
			(layer "F.SilkS")
		)
		(fp_circle
			(center 8.26008 -2.54)
			(end 8.26008 -3.6195)
			(stroke
				(width 0.3048)
				(type default)
			)
			(fill no)
			(layer "F.SilkS")
		)
		(fp_circle
			(center 10.80008 -2.54)
			(end 10.80008 -3.6195)
			(stroke
				(width 0.3048)
				(type default)
			)
			(fill no)
			(layer "F.SilkS")
		)
		(fp_circle
			(center 13.34008 -2.54)
			(end 13.34008 -3.6195)
			(stroke
				(width 0.3048)
				(type default)
			)
			(fill no)
			(layer "F.SilkS")
		)
		(fp_circle
			(center 15.88008 -2.54)
			(end 15.88008 -3.6195)
			(stroke
				(width 0.3048)
				(type default)
			)
			(fill no)
			(layer "F.SilkS")
		)
		(fp_circle
			(center -15.88008 -5.08)
			(end -15.88008 -6.1595)
			(stroke
				(width 0.3048)
				(type default)
			)
			(fill no)
			(layer "F.SilkS")
		)
		(fp_circle
			(center -13.34008 -5.08)
			(end -13.34008 -6.1595)
			(stroke
				(width 0.3048)
				(type default)
			)
			(fill no)
			(layer "F.SilkS")
		)
		(fp_circle
			(center -10.80008 -5.08)
			(end -10.80008 -6.1595)
			(stroke
				(width 0.3048)
				(type default)
			)
			(fill no)
			(layer "F.SilkS")
		)
		(fp_circle
			(center -8.26008 -5.08)
			(end -8.26008 -6.1595)
			(stroke
				(width 0.3048)
				(type default)
			)
			(fill no)
			(layer "F.SilkS")
		)
		(fp_circle
			(center -5.08 -5.08)
			(end -5.08 -6.1595)
			(stroke
				(width 0.3048)
				(type default)
			)
			(fill no)
			(layer "F.SilkS")
		)
		(fp_circle
			(center -2.54 -5.08)
			(end -2.54 -6.1595)
			(stroke
				(width 0.3048)
				(type default)
			)
			(fill no)
			(layer "F.SilkS")
		)
		(fp_circle
			(center 0 -5.08)
			(end 0 -6.1595)
			(stroke
				(width 0.3048)
				(type default)
			)
			(fill no)
			(layer "F.SilkS")
		)
		(fp_circle
			(center 2.54 -5.08)
			(end 2.54 -6.1595)
			(stroke
				(width 0.3048)
				(type default)
			)
			(fill no)
			(layer "F.SilkS")
		)
		(fp_circle
			(center 5.08 -5.08)
			(end 5.08 -6.1595)
			(stroke
				(width 0.3048)
				(type default)
			)
			(fill no)
			(layer "F.SilkS")
		)
		(fp_circle
			(center 8.26008 -5.08)
			(end 8.26008 -6.1595)
			(stroke
				(width 0.3048)
				(type default)
			)
			(fill no)
			(layer "F.SilkS")
		)
		(fp_circle
			(center 10.80008 -5.08)
			(end 10.80008 -6.1595)
			(stroke
				(width 0.3048)
				(type default)
			)
			(fill no)
			(layer "F.SilkS")
		)
		(fp_circle
			(center 13.34008 -5.08)
			(end 13.34008 -6.1595)
			(stroke
				(width 0.3048)
				(type default)
			)
			(fill no)
			(layer "F.SilkS")
		)
		(fp_circle
			(center 15.88008 -5.08)
			(end 15.88008 -6.1595)
			(stroke
				(width 0.3048)
				(type default)
			)
			(fill no)
			(layer "F.SilkS")
		)
		(fp_circle
			(center -15.88008 -7.62)
			(end -15.88008 -8.6995)
			(stroke
				(width 0.3048)
				(type default)
			)
			(fill no)
			(layer "F.SilkS")
		)
		(fp_circle
			(center -13.34008 -7.62)
			(end -13.34008 -8.6995)
			(stroke
				(width 0.3048)
				(type default)
			)
			(fill no)
			(layer "F.SilkS")
		)
		(fp_circle
			(center -10.80008 -7.62)
			(end -10.80008 -8.6995)
			(stroke
				(width 0.3048)
				(type default)
			)
			(fill no)
			(layer "F.SilkS")
		)
		(fp_circle
			(center -8.26008 -7.62)
			(end -8.26008 -8.6995)
			(stroke
				(width 0.3048)
				(type default)
			)
			(fill no)
			(layer "F.SilkS")
		)
		(fp_circle
			(center -5.08 -7.62)
			(end -5.08 -8.6995)
			(stroke
				(width 0.3048)
				(type default)
			)
			(fill no)
			(layer "F.SilkS")
		)
		(fp_circle
			(center -2.54 -7.62)
			(end -2.54 -8.6995)
			(stroke
				(width 0.3048)
				(type default)
			)
			(fill no)
			(layer "F.SilkS")
		)
		(fp_circle
			(center 0 -7.62)
			(end 0 -8.6995)
			(stroke
				(width 0.3048)
				(type default)
			)
			(fill no)
			(layer "F.SilkS")
		)
		(fp_circle
			(center 2.54 -7.62)
			(end 2.54 -8.6995)
			(stroke
				(width 0.3048)
				(type default)
			)
			(fill no)
			(layer "F.SilkS")
		)
		(fp_circle
			(center 5.08 -7.62)
			(end 5.08 -8.6995)
			(stroke
				(width 0.3048)
				(type default)
			)
			(fill no)
			(layer "F.SilkS")
		)
		(fp_circle
			(center 8.26008 -7.62)
			(end 8.26008 -8.6995)
			(stroke
				(width 0.3048)
				(type default)
			)
			(fill no)
			(layer "F.SilkS")
		)
		(fp_circle
			(center 10.80008 -7.62)
			(end 10.80008 -8.6995)
			(stroke
				(width 0.3048)
				(type default)
			)
			(fill no)
			(layer "F.SilkS")
		)
		(fp_circle
			(center 13.34008 -7.62)
			(end 13.34008 -8.6995)
			(stroke
				(width 0.3048)
				(type default)
			)
			(fill no)
			(layer "F.SilkS")
		)
		(fp_circle
			(center 15.88008 -7.62)
			(end 15.88008 -8.6995)
			(stroke
				(width 0.3048)
				(type default)
			)
			(fill no)
			(layer "F.SilkS")
		)
		(fp_poly
			(pts
				(xy -29.21 3.4798) (xy -29.21 -3.4798) (xy -21.971 -3.4798) (xy -21.971 -11.0998) (xy 21.971 -11.0998)
				(xy 21.971 -3.4798) (xy 29.21 -3.4798) (xy 29.21 3.4798)
			)
			(stroke
				(width 0)
				(type default)
			)
			(fill no)
			(layer "F.CrtYd")
		)
		(fp_poly
			(pts
				(xy -29.718 3.9878) (xy -29.718 -11.6078) (xy 29.718 -11.6078) (xy 29.718 -0.00635) (xy 29.21 -0.00635)
				(xy 29.21 -3.4798) (xy 21.971 -3.4798) (xy 21.971 -11.0998) (xy -21.971 -11.0998) (xy -21.971 -3.4798)
				(xy -29.21 -3.4798) (xy -29.21 3.4798) (xy 29.21 3.4798) (xy 29.21 0.00635) (xy 29.718 0.00635)
				(xy 29.718 3.9878)
			)
			(stroke
				(width 0)
				(type default)
			)
			(fill no)
			(layer "F.CrtYd")
		)
		(fp_poly
			(pts
				(xy -29.718 3.9878) (xy -29.718 -11.6078) (xy 29.718 -11.6078) (xy 29.718 3.9878)
			)
			(stroke
				(width 0)
				(type default)
			)
			(fill no)
			(layer "F.Fab")
		)
		(pad "" np_thru_hole circle
			(at -26.67 0 270)
			(size 0.254 0.254)
			(drill 3.2004)
			(layers "*.Cu" "*.Mask")
			(clearance 1.8288)
			(thermal_gap 1.8288)
		)
		(pad "" np_thru_hole circle
			(at -21.59 0 270)
			(size 0.254 0.254)
			(drill 2.5146)
			(layers "*.Cu" "*.Mask")
			(clearance 1.4859)
			(thermal_gap 1.4859)
		)
		(pad "" np_thru_hole circle
			(at 21.59 0 270)
			(size 0.254 0.254)
			(drill 2.5146)
			(layers "*.Cu" "*.Mask")
			(clearance 1.4859)
			(thermal_gap 1.4859)
		)
		(pad "" np_thru_hole circle
			(at 26.67 0 270)
			(size 0.254 0.254)
			(drill 3.2004)
			(layers "*.Cu" "*.Mask")
			(clearance 1.8288)
			(thermal_gap 1.8288)
		)
		(pad "A1" thru_hole circle
			(at -5.08 0 270)
			(size 1.4478 1.4478)
			(drill 1.0414)
			(layers "*.Cu" "*.Mask")
			(remove_unused_layers no)
			(net "I2C_C_SDA_CONN_R")
			(clearance 0.1524)
			(thermal_gap 0.1524)
		)
		(pad "A2" thru_hole circle
			(at -2.54 0 270)
			(size 1.4478 1.4478)
			(drill 1.0414)
			(layers "*.Cu" "*.Mask")
			(remove_unused_layers no)
			(net "GND")
			(clearance 0.1524)
			(thermal_gap 0.1524)
		)
		(pad "A3" thru_hole circle
			(at 0 0 270)
			(size 1.4478 1.4478)
			(drill 1.0414)
			(layers "*.Cu" "*.Mask")
			(remove_unused_layers no)
			(net "I2C_C_SCL_CONN_R")
			(clearance 0.1524)
			(thermal_gap 0.1524)
		)
		(pad "A4" thru_hole circle
			(at 2.54 0 270)
			(size 1.4478 1.4478)
			(drill 1.0414)
			(layers "*.Cu" "*.Mask")
			(remove_unused_layers no)
			(net "GND")
			(clearance 0.1524)
			(thermal_gap 0.1524)
		)
		(pad "A5" thru_hole circle
			(at 5.08 0 270)
			(size 1.4478 1.4478)
			(drill 1.0414)
			(layers "*.Cu" "*.Mask")
			(remove_unused_layers no)
			(net "PWM_EXP_2B")
			(clearance 0.1524)
			(thermal_gap 0.1524)
		)
		(pad "B1" thru_hole circle
			(at -5.08 -2.54 270)
			(size 1.4478 1.4478)
			(drill 1.0414)
			(layers "*.Cu" "*.Mask")
			(remove_unused_layers no)
			(net "GND")
			(clearance 0.1524)
			(thermal_gap 0.1524)
		)
		(pad "B2" thru_hole circle
			(at -2.54 -2.54 270)
			(size 1.4478 1.4478)
			(drill 1.0414)
			(layers "*.Cu" "*.Mask")
			(remove_unused_layers no)
			(net "PWM_EXP_2A")
			(clearance 0.1524)
			(thermal_gap 0.1524)
		)
		(pad "B3" thru_hole circle
			(at 0 -2.54 270)
			(size 1.4478 1.4478)
			(drill 1.0414)
			(layers "*.Cu" "*.Mask")
			(remove_unused_layers no)
			(net "GND")
			(clearance 0.1524)
			(thermal_gap 0.1524)
		)
		(pad "B4" thru_hole circle
			(at 2.54 -2.54 270)
			(size 1.4478 1.4478)
			(drill 1.0414)
			(layers "*.Cu" "*.Mask")
			(remove_unused_layers no)
			(net "SELF_2B_HB")
			(clearance 0.1524)
			(thermal_gap 0.1524)
		)
		(pad "B5" thru_hole circle
			(at 5.08 -2.54 270)
			(size 1.4478 1.4478)
			(drill 1.0414)
			(layers "*.Cu" "*.Mask")
			(remove_unused_layers no)
			(net "GND")
			(clearance 0.1524)
			(thermal_gap 0.1524)
		)
		(pad "C1" thru_hole circle
			(at -5.08 -5.08 270)
			(size 1.4478 1.4478)
			(drill 1.0414)
			(layers "*.Cu" "*.Mask")
			(remove_unused_layers no)
			(net "P12VL_2490_EN_1")
			(clearance 0.1524)
			(thermal_gap 0.1524)
		)
		(pad "C2" thru_hole circle
			(at -2.54 -5.08 270)
			(size 1.4478 1.4478)
			(drill 1.0414)
			(layers "*.Cu" "*.Mask")
			(remove_unused_layers no)
			(net "P12VL_2490_EN_2")
			(clearance 0.1524)
			(thermal_gap 0.1524)
		)
		(pad "C3" thru_hole circle
			(at 0 -5.08 270)
			(size 1.4478 1.4478)
			(drill 1.0414)
			(layers "*.Cu" "*.Mask")
			(remove_unused_layers no)
			(net "SELF_2A_HB")
			(clearance 0.1524)
			(thermal_gap 0.1524)
		)
		(pad "C4" thru_hole circle
			(at 2.54 -5.08 270)
			(size 1.4478 1.4478)
			(drill 1.0414)
			(layers "*.Cu" "*.Mask")
			(remove_unused_layers no)
			(net "SEB_PEER_2A_HB")
			(clearance 0.1524)
			(thermal_gap 0.1524)
		)
		(pad "C5" thru_hole circle
			(at 5.08 -5.08 270)
			(size 1.4478 1.4478)
			(drill 1.0414)
			(layers "*.Cu" "*.Mask")
			(remove_unused_layers no)
			(net "SEB_PEER_2B_HB")
			(clearance 0.1524)
			(thermal_gap 0.1524)
		)
		(pad "D1" thru_hole circle
			(at -5.08 -7.62 270)
			(size 1.4478 1.4478)
			(drill 1.0414)
			(layers "*.Cu" "*.Mask")
			(remove_unused_layers no)
			(net "PEER_TRAY PRESENT_LOWER")
			(clearance 0.1524)
			(thermal_gap 0.1524)
		)
		(pad "D2" thru_hole circle
			(at -2.54 -7.62 270)
			(size 1.4478 1.4478)
			(drill 1.0414)
			(layers "*.Cu" "*.Mask")
			(remove_unused_layers no)
			(net "LOWER_TRAY_ID")
			(clearance 0.1524)
			(thermal_gap 0.1524)
		)
		(pad "D3" thru_hole circle
			(at 0 -7.62 270)
			(size 1.4478 1.4478)
			(drill 1.0414)
			(layers "*.Cu" "*.Mask")
			(remove_unused_layers no)
			(net "FCB_HW_REVISION")
			(clearance 0.1524)
			(thermal_gap 0.1524)
		)
		(pad "D4" thru_hole circle
			(at 2.54 -7.62 270)
			(size 1.4478 1.4478)
			(drill 1.0414)
			(layers "*.Cu" "*.Mask")
			(remove_unused_layers no)
			(net "SD_LATCH_RELEASE_L")
			(clearance 0.1524)
			(thermal_gap 0.1524)
		)
		(pad "D5" thru_hole circle
			(at 5.08 -7.62 270)
			(size 1.4478 1.4478)
			(drill 1.0414)
			(layers "*.Cu" "*.Mask")
			(remove_unused_layers no)
			(net "SELF_TRAY_PRESENT_LOWER")
			(clearance 0.1524)
			(thermal_gap 0.1524)
		)
		(pad "P1_1" thru_hole circle
			(at -15.88008 0 270)
			(size 1.4478 1.4478)
			(drill 1.0414)
			(layers "*.Cu" "*.Mask")
			(remove_unused_layers no)
			(net "P12VL")
			(clearance 0.1524)
			(thermal_gap 0.1524)
		)
		(pad "P1_2" thru_hole circle
			(at -15.88008 -2.54 270)
			(size 1.4478 1.4478)
			(drill 1.0414)
			(layers "*.Cu" "*.Mask")
			(remove_unused_layers no)
			(net "P12VL")
			(clearance 0.1524)
			(thermal_gap 0.1524)
		)
		(pad "P1_3" thru_hole circle
			(at -15.88008 -5.08 270)
			(size 1.4478 1.4478)
			(drill 1.0414)
			(layers "*.Cu" "*.Mask")
			(remove_unused_layers no)
			(net "P12VL")
			(clearance 0.1524)
			(thermal_gap 0.1524)
		)
		(pad "P1_4" thru_hole circle
			(at -15.88008 -7.62 270)
			(size 1.4478 1.4478)
			(drill 1.0414)
			(layers "*.Cu" "*.Mask")
			(remove_unused_layers no)
			(net "P12VL")
			(clearance 0.1524)
			(thermal_gap 0.1524)
		)
		(pad "P1_5" thru_hole circle
			(at -13.34008 0 270)
			(size 1.4478 1.4478)
			(drill 1.0414)
			(layers "*.Cu" "*.Mask")
			(remove_unused_layers no)
			(net "P12VL")
			(clearance 0.1524)
			(thermal_gap 0.1524)
		)
		(pad "P1_6" thru_hole circle
			(at -13.34008 -2.54 270)
			(size 1.4478 1.4478)
			(drill 1.0414)
			(layers "*.Cu" "*.Mask")
			(remove_unused_layers no)
			(net "P12VL")
			(clearance 0.1524)
			(thermal_gap 0.1524)
		)
		(pad "P1_7" thru_hole circle
			(at -13.34008 -5.08 270)
			(size 1.4478 1.4478)
			(drill 1.0414)
			(layers "*.Cu" "*.Mask")
			(remove_unused_layers no)
			(net "P12VL")
			(clearance 0.1524)
			(thermal_gap 0.1524)
		)
		(pad "P1_8" thru_hole circle
			(at -13.34008 -7.62 270)
			(size 1.4478 1.4478)
			(drill 1.0414)
			(layers "*.Cu" "*.Mask")
			(remove_unused_layers no)
			(net "P12VL")
			(clearance 0.1524)
			(thermal_gap 0.1524)
		)
		(pad "P2_1" thru_hole circle
			(at -10.80008 0 270)
			(size 1.4478 1.4478)
			(drill 1.0414)
			(layers "*.Cu" "*.Mask")
			(remove_unused_layers no)
			(net "P12VL")
			(clearance 0.1524)
			(thermal_gap 0.1524)
		)
		(pad "P2_2" thru_hole circle
			(at -10.80008 -2.54 270)
			(size 1.4478 1.4478)
			(drill 1.0414)
			(layers "*.Cu" "*.Mask")
			(remove_unused_layers no)
			(net "P12VL")
			(clearance 0.1524)
			(thermal_gap 0.1524)
		)
		(pad "P2_3" thru_hole circle
			(at -10.80008 -5.08 270)
			(size 1.4478 1.4478)
			(drill 1.0414)
			(layers "*.Cu" "*.Mask")
			(remove_unused_layers no)
			(net "P12VL")
			(clearance 0.1524)
			(thermal_gap 0.1524)
		)
		(pad "P2_4" thru_hole circle
			(at -10.80008 -7.62 270)
			(size 1.4478 1.4478)
			(drill 1.0414)
			(layers "*.Cu" "*.Mask")
			(remove_unused_layers no)
			(net "P12VL")
			(clearance 0.1524)
			(thermal_gap 0.1524)
		)
		(pad "P2_5" thru_hole circle
			(at -8.26008 0 270)
			(size 1.4478 1.4478)
			(drill 1.0414)
			(layers "*.Cu" "*.Mask")
			(remove_unused_layers no)
			(net "P12VL")
			(clearance 0.1524)
			(thermal_gap 0.1524)
		)
		(pad "P2_6" thru_hole circle
			(at -8.26008 -2.54 270)
			(size 1.4478 1.4478)
			(drill 1.0414)
			(layers "*.Cu" "*.Mask")
			(remove_unused_layers no)
			(net "P12VL")
			(clearance 0.1524)
			(thermal_gap 0.1524)
		)
		(pad "P2_7" thru_hole circle
			(at -8.26008 -5.08 270)
			(size 1.4478 1.4478)
			(drill 1.0414)
			(layers "*.Cu" "*.Mask")
			(remove_unused_layers no)
			(net "P12VL")
			(clearance 0.1524)
			(thermal_gap 0.1524)
		)
		(pad "P2_8" thru_hole circle
			(at -8.26008 -7.62 270)
			(size 1.4478 1.4478)
			(drill 1.0414)
			(layers "*.Cu" "*.Mask")
			(remove_unused_layers no)
			(net "P12VL")
			(clearance 0.1524)
			(thermal_gap 0.1524)
		)
		(pad "P3_1" thru_hole circle
			(at 8.26008 0 270)
			(size 1.4478 1.4478)
			(drill 1.0414)
			(layers "*.Cu" "*.Mask")
			(remove_unused_layers no)
			(net "GND")
			(clearance 0.1524)
			(thermal_gap 0.1524)
		)
		(pad "P3_2" thru_hole circle
			(at 8.26008 -2.54 270)
			(size 1.4478 1.4478)
			(drill 1.0414)
			(layers "*.Cu" "*.Mask")
			(remove_unused_layers no)
			(net "GND")
			(clearance 0.1524)
			(thermal_gap 0.1524)
		)
		(pad "P3_3" thru_hole circle
			(at 8.26008 -5.08 270)
			(size 1.4478 1.4478)
			(drill 1.0414)
			(layers "*.Cu" "*.Mask")
			(remove_unused_layers no)
			(net "GND")
			(clearance 0.1524)
			(thermal_gap 0.1524)
		)
		(pad "P3_4" thru_hole circle
			(at 8.26008 -7.62 270)
			(size 1.4478 1.4478)
			(drill 1.0414)
			(layers "*.Cu" "*.Mask")
			(remove_unused_layers no)
			(net "GND")
			(clearance 0.1524)
			(thermal_gap 0.1524)
		)
		(pad "P3_5" thru_hole circle
			(at 10.80008 0 270)
			(size 1.4478 1.4478)
			(drill 1.0414)
			(layers "*.Cu" "*.Mask")
			(remove_unused_layers no)
			(net "GND")
			(clearance 0.1524)
			(thermal_gap 0.1524)
		)
		(pad "P3_6" thru_hole circle
			(at 10.80008 -2.54 270)
			(size 1.4478 1.4478)
			(drill 1.0414)
			(layers "*.Cu" "*.Mask")
			(remove_unused_layers no)
			(net "GND")
			(clearance 0.1524)
			(thermal_gap 0.1524)
		)
		(pad "P3_7" thru_hole circle
			(at 10.80008 -5.08 270)
			(size 1.4478 1.4478)
			(drill 1.0414)
			(layers "*.Cu" "*.Mask")
			(remove_unused_layers no)
			(net "GND")
			(clearance 0.1524)
			(thermal_gap 0.1524)
		)
		(pad "P3_8" thru_hole circle
			(at 10.80008 -7.62 270)
			(size 1.4478 1.4478)
			(drill 1.0414)
			(layers "*.Cu" "*.Mask")
			(remove_unused_layers no)
			(net "GND")
			(clearance 0.1524)
			(thermal_gap 0.1524)
		)
		(pad "P4_1" thru_hole circle
			(at 13.34008 0 270)
			(size 1.4478 1.4478)
			(drill 1.0414)
			(layers "*.Cu" "*.Mask")
			(remove_unused_layers no)
			(net "GND")
			(clearance 0.1524)
			(thermal_gap 0.1524)
		)
		(pad "P4_2" thru_hole circle
			(at 13.34008 -2.54 270)
			(size 1.4478 1.4478)
			(drill 1.0414)
			(layers "*.Cu" "*.Mask")
			(remove_unused_layers no)
			(net "GND")
			(clearance 0.1524)
			(thermal_gap 0.1524)
		)
		(pad "P4_3" thru_hole circle
			(at 13.34008 -5.08 270)
			(size 1.4478 1.4478)
			(drill 1.0414)
			(layers "*.Cu" "*.Mask")
			(remove_unused_layers no)
			(net "GND")
			(clearance 0.1524)
			(thermal_gap 0.1524)
		)
		(pad "P4_4" thru_hole circle
			(at 13.34008 -7.62 270)
			(size 1.4478 1.4478)
			(drill 1.0414)
			(layers "*.Cu" "*.Mask")
			(remove_unused_layers no)
			(net "GND")
			(clearance 0.1524)
			(thermal_gap 0.1524)
		)
		(pad "P4_5" thru_hole circle
			(at 15.88008 0 270)
			(size 1.4478 1.4478)
			(drill 1.0414)
			(layers "*.Cu" "*.Mask")
			(remove_unused_layers no)
			(net "GND")
			(clearance 0.1524)
			(thermal_gap 0.1524)
		)
		(pad "P4_6" thru_hole circle
			(at 15.88008 -2.54 270)
			(size 1.4478 1.4478)
			(drill 1.0414)
			(layers "*.Cu" "*.Mask")
			(remove_unused_layers no)
			(net "GND")
			(clearance 0.1524)
			(thermal_gap 0.1524)
		)
		(pad "P4_7" thru_hole circle
			(at 15.88008 -5.08 270)
			(size 1.4478 1.4478)
			(drill 1.0414)
			(layers "*.Cu" "*.Mask")
			(remove_unused_layers no)
			(net "GND")
			(clearance 0.1524)
			(thermal_gap 0.1524)
		)
		(pad "P4_8" thru_hole circle
			(at 15.88008 -7.62 270)
			(size 1.4478 1.4478)
			(drill 1.0414)
			(layers "*.Cu" "*.Mask")
			(remove_unused_layers no)
			(net "GND")
			(clearance 0.1524)
			(thermal_gap 0.1524)
		)
		(zone
			(layers "F.Cu" "B.Cu" "In1.Cu" "In2.Cu")
			(hatch none 0.5)
			(connect_pads
				(clearance 0)
			)
			(min_thickness 0.25)
			(keepout
				(tracks not_allowed)
				(vias allowed)
				(pads allowed)
				(copperpour not_allowed)
				(footprints allowed)
			)
			(placement
				(enabled no)
				(sheetname "")
			)
			(fill
				(thermal_gap 0.5)
				(thermal_bridge_width 0.5)
				(island_removal_mode 0)
			)
			(polygon
				(pts
					(arc
						(start 39.562024 -78.589886)
						(mid 36.437824 -78.589886)
						(end 39.562024 -78.589886)
					)
				)
			)
		)
		(zone
			(layers "F.Cu" "B.Cu" "In1.Cu" "In2.Cu")
			(hatch none 0.5)
			(connect_pads
				(clearance 0)
			)
			(min_thickness 0.25)
			(keepout
				(tracks not_allowed)
				(vias allowed)
				(pads allowed)
				(copperpour not_allowed)
				(footprints allowed)
			)
			(placement
				(enabled no)
				(sheetname "")
			)
			(fill
				(thermal_gap 0.5)
				(thermal_bridge_width 0.5)
				(island_removal_mode 0)
			)
			(polygon
				(pts
					(arc
						(start 39.562024 -35.409886)
						(mid 36.437824 -35.409886)
						(end 39.562024 -35.409886)
					)
				)
			)
		)
		(zone
			(layers "F.Cu" "B.Cu" "In1.Cu" "In2.Cu")
			(hatch none 0.5)
			(connect_pads
				(clearance 0)
			)
			(min_thickness 0.25)
			(keepout
				(tracks not_allowed)
				(vias allowed)
				(pads allowed)
				(copperpour not_allowed)
				(footprints allowed)
			)
			(placement
				(enabled no)
				(sheetname "")
			)
			(fill
				(thermal_gap 0.5)
				(thermal_bridge_width 0.5)
				(island_removal_mode 0)
			)
			(polygon
				(pts
					(arc
						(start 39.904924 -83.669886)
						(mid 36.094924 -83.669886)
						(end 39.904924 -83.669886)
					)
				)
			)
		)
		(zone
			(layers "F.Cu" "B.Cu" "In1.Cu" "In2.Cu")
			(hatch none 0.5)
			(connect_pads
				(clearance 0)
			)
			(min_thickness 0.25)
			(keepout
				(tracks not_allowed)
				(vias allowed)
				(pads allowed)
				(copperpour not_allowed)
				(footprints allowed)
			)
			(placement
				(enabled no)
				(sheetname "")
			)
			(fill
				(thermal_gap 0.5)
				(thermal_bridge_width 0.5)
				(island_removal_mode 0)
			)
			(polygon
				(pts
					(arc
						(start 39.904924 -30.329886)
						(mid 36.094924 -30.329886)
						(end 39.904924 -30.329886)
					)
				)
			)
		)
	)
	(footprint ""
		(layer "F.Cu")
		(at 43.7896 -136.2456 90)
		(property "Reference" "PC90"
			(at 0 0 90)
			(layer "F.SilkS")
			(hide yes)
			(effects
				(font
					(size 1.27 1.27)
				)
			)
		)
		(property "Value" "SCD1U25V2KX-GP"
			(at 1.1811 -2.7051 90)
			(unlocked yes)
			(layer "F.Fab")
			(hide yes)
			(effects
				(font
					(size 1.016 1.016)
					(thickness 0.1524)
				)
			)
		)
		(property "Device Type" "C402H22"
			(at 1.1811 -4.2291 90)
			(unlocked yes)
			(layer "F.Fab")
			(hide yes)
			(effects
				(font
					(size 1.016 1.016)
					(thickness 0.1524)
				)
			)
		)
		(duplicate_pad_numbers_are_jumpers no)
		(fp_rect
			(start -0.4318 0.9525)
			(end 0.4318 -0.9525)
			(stroke
				(width 0)
				(type default)
			)
			(fill no)
			(layer "F.CrtYd")
		)
		(fp_rect
			(start -0.4318 0.9525)
			(end 0.4318 -0.9525)
			(stroke
				(width 0)
				(type default)
			)
			(fill no)
			(layer "F.Fab")
		)
		(pad "1" smd custom
			(at 0 -0.4445 90)
			(size 0.1524 0.1524)
			(layers "F.Cu" "F.Mask" "F.Paste")
			(net "P12VL_2490_VCC")
			(options
				(clearance outline)
				(anchor circle)
			)
			(primitives
				(gr_poly
					(pts
						(arc
							(start 0.3048 -0.2032)
							(mid 0.275042 -0.275042)
							(end 0.2032 -0.3048)
						)
						(arc
							(start -0.2032 -0.3048)
							(mid -0.275042 -0.275042)
							(end -0.3048 -0.2032)
						)
						(arc
							(start -0.3048 0.2032)
							(mid -0.275042 0.275042)
							(end -0.2032 0.3048)
						)
						(arc
							(start 0.2032 0.3048)
							(mid 0.275042 0.275042)
							(end 0.3048 0.2032)
						)
					)
					(width 0)
					(fill yes)
				)
			)
		)
		(pad "2" smd custom
			(at 0 0.4445 90)
			(size 0.1524 0.1524)
			(layers "F.Cu" "F.Mask" "F.Paste")
			(net "GND")
			(options
				(clearance outline)
				(anchor circle)
			)
			(primitives
				(gr_poly
					(pts
						(arc
							(start 0.3048 -0.2032)
							(mid 0.275042 -0.275042)
							(end 0.2032 -0.3048)
						)
						(arc
							(start -0.2032 -0.3048)
							(mid -0.275042 -0.275042)
							(end -0.3048 -0.2032)
						)
						(arc
							(start -0.3048 0.2032)
							(mid -0.275042 0.275042)
							(end -0.2032 0.3048)
						)
						(arc
							(start 0.2032 0.3048)
							(mid 0.275042 0.275042)
							(end 0.3048 0.2032)
						)
					)
					(width 0)
					(fill yes)
				)
			)
		)
	)
	(footprint ""
		(layer "F.Cu")
		(at 15.9258 -65.278)
		(property "Reference" "C57"
			(at 0 0 0)
			(layer "F.SilkS")
			(hide yes)
			(effects
				(font
					(size 1.27 1.27)
				)
			)
		)
		(property "Value" "SC220P50V3JN-GP"
			(at 0 -2.8194 0)
			(unlocked yes)
			(layer "F.Fab")
			(hide yes)
			(effects
				(font
					(size 1.016 1.016)
					(thickness 0.1524)
				)
			)
		)
		(property "Device Type" "C603H36"
			(at 0 -4.3434 0)
			(unlocked yes)
			(layer "F.Fab")
			(hide yes)
			(effects
				(font
					(size 1.016 1.016)
					(thickness 0.1524)
				)
			)
		)
		(duplicate_pad_numbers_are_jumpers no)
		(fp_line
			(start 0.508 0)
			(end -0.508 0)
			(stroke
				(width 0.2032)
				(type default)
			)
			(layer "F.SilkS")
		)
		(fp_rect
			(start -0.5842 1.3335)
			(end 0.5842 -1.3335)
			(stroke
				(width 0)
				(type default)
			)
			(fill no)
			(layer "F.CrtYd")
		)
		(fp_rect
			(start -0.5842 1.3335)
			(end 0.5842 -1.3335)
			(stroke
				(width 0)
				(type default)
			)
			(fill no)
			(layer "F.Fab")
		)
		(pad "1" smd custom
			(at 0 -0.762)
			(size 0.2159 0.2159)
			(layers "F.Cu" "F.Mask" "F.Paste")
			(net "I2C_C_SDA_CONN_R")
			(options
				(clearance outline)
				(anchor circle)
			)
			(primitives
				(gr_poly
					(pts
						(arc
							(start -0.3302 -0.4318)
							(mid -0.402042 -0.402042)
							(end -0.4318 -0.3302)
						)
						(arc
							(start -0.4318 0.3302)
							(mid -0.402042 0.402042)
							(end -0.3302 0.4318)
						)
						(arc
							(start 0.3302 0.4318)
							(mid 0.402042 0.402042)
							(end 0.4318 0.3302)
						)
						(arc
							(start 0.4318 -0.3302)
							(mid 0.402042 -0.402042)
							(end 0.3302 -0.4318)
						)
					)
					(width 0)
					(fill yes)
				)
			)
		)
		(pad "2" smd custom
			(at 0 0.762)
			(size 0.2159 0.2159)
			(layers "F.Cu" "F.Mask" "F.Paste")
			(net "GND")
			(options
				(clearance outline)
				(anchor circle)
			)
			(primitives
				(gr_poly
					(pts
						(arc
							(start -0.3302 -0.4318)
							(mid -0.402042 -0.402042)
							(end -0.4318 -0.3302)
						)
						(arc
							(start -0.4318 0.3302)
							(mid -0.402042 0.402042)
							(end -0.3302 0.4318)
						)
						(arc
							(start 0.3302 0.4318)
							(mid 0.402042 0.402042)
							(end 0.4318 0.3302)
						)
						(arc
							(start 0.4318 -0.3302)
							(mid 0.402042 -0.402042)
							(end 0.3302 -0.4318)
						)
					)
					(width 0)
					(fill yes)
				)
			)
		)
	)
	(footprint ""
		(layer "F.Cu")
		(at 15.6464 -53.2384 180)
		(property "Reference" "R357"
			(at 0 0 180)
			(layer "F.SilkS")
			(hide yes)
			(effects
				(font
					(size 1.27 1.27)
				)
			)
		)
		(property "Value" "10KR2F-2-GP"
			(at 0.064008 -3.993896 180)
			(unlocked yes)
			(layer "F.Fab")
			(hide yes)
			(effects
				(font
					(size 1.016 1.016)
					(thickness 0.1524)
				)
			)
		)
		(property "Device Type" "R402H16"
			(at 0.064008 -5.517896 180)
			(unlocked yes)
			(layer "F.Fab")
			(hide yes)
			(effects
				(font
					(size 1.016 1.016)
					(thickness 0.1524)
				)
			)
		)
		(duplicate_pad_numbers_are_jumpers no)
		(fp_line
			(start 0.508 -0.9398)
			(end -0.508 -0.9398)
			(stroke
				(width 0.1524)
				(type default)
			)
			(layer "F.SilkS")
		)
		(fp_line
			(start -0.508 -0.9398)
			(end -0.508 0.9398)
			(stroke
				(width 0.1524)
				(type default)
			)
			(layer "F.SilkS")
		)
		(fp_rect
			(start -0.508 0.9398)
			(end 0.508 -0.9398)
			(stroke
				(width 0)
				(type default)
			)
			(fill no)
			(layer "F.CrtYd")
		)
		(fp_rect
			(start -0.508 0.9398)
			(end 0.508 -0.9398)
			(stroke
				(width 0)
				(type default)
			)
			(fill no)
			(layer "F.Fab")
		)
		(pad "1" smd custom
			(at 0 -0.4445 180)
			(size 0.1397 0.1397)
			(layers "F.Cu" "F.Mask" "F.Paste")
			(net "P3V3")
			(options
				(clearance outline)
				(anchor circle)
			)
			(primitives
				(gr_poly
					(pts
						(arc
							(start -0.1778 -0.2794)
							(mid -0.249642 -0.249642)
							(end -0.2794 -0.1778)
						)
						(arc
							(start -0.2794 0.1778)
							(mid -0.249642 0.249642)
							(end -0.1778 0.2794)
						)
						(arc
							(start 0.1778 0.2794)
							(mid 0.249642 0.249642)
							(end 0.2794 0.1778)
						)
						(arc
							(start 0.2794 -0.1778)
							(mid 0.249642 -0.249642)
							(end 0.1778 -0.2794)
						)
					)
					(width 0)
					(fill yes)
				)
			)
		)
		(pad "2" smd custom
			(at 0 0.4445 180)
			(size 0.1397 0.1397)
			(layers "F.Cu" "F.Mask" "F.Paste")
			(net "FCB_HW_REVISION")
			(options
				(clearance outline)
				(anchor circle)
			)
			(primitives
				(gr_poly
					(pts
						(arc
							(start -0.1778 -0.2794)
							(mid -0.249642 -0.249642)
							(end -0.2794 -0.1778)
						)
						(arc
							(start -0.2794 0.1778)
							(mid -0.249642 0.249642)
							(end -0.1778 0.2794)
						)
						(arc
							(start 0.1778 0.2794)
							(mid 0.249642 0.249642)
							(end 0.2794 0.1778)
						)
						(arc
							(start 0.2794 -0.1778)
							(mid 0.249642 -0.249642)
							(end 0.1778 -0.2794)
						)
					)
					(width 0)
					(fill yes)
				)
			)
		)
	)
	(footprint ""
		(layer "F.Cu")
		(at 21.844508 -192.505838)
		(property "Reference" "F3"
			(at 0 0 0)
			(layer "F.SilkS")
			(hide yes)
			(effects
				(font
					(size 1.27 1.27)
				)
			)
		)
		(property "Value" "FUSE-3A15V-GP"
			(at 0.2286 -10.5918 0)
			(unlocked yes)
			(layer "F.Fab")
			(hide yes)
			(effects
				(font
					(size 1.016 1.016)
					(thickness 0.1524)
				)
			)
		)
		(property "Device Type" "FUSE-7452-UH50"
			(at 0.2286 -12.4968 0)
			(unlocked yes)
			(layer "F.Fab")
			(hide yes)
			(effects
				(font
					(size 1.016 1.016)
					(thickness 0.1524)
				)
			)
		)
		(duplicate_pad_numbers_are_jumpers no)
		(fp_line
			(start -4.9276 -2.921)
			(end 4.9276 -2.921)
			(stroke
				(width 0.1524)
				(type default)
			)
			(layer "F.SilkS")
		)
		(fp_line
			(start -4.9276 2.921)
			(end -4.9276 -2.921)
			(stroke
				(width 0.1524)
				(type default)
			)
			(layer "F.SilkS")
		)
		(fp_line
			(start 4.9276 -2.921)
			(end 4.9276 2.921)
			(stroke
				(width 0.1524)
				(type default)
			)
			(layer "F.SilkS")
		)
		(fp_line
			(start 4.9276 2.921)
			(end -4.9276 2.921)
			(stroke
				(width 0.1524)
				(type default)
			)
			(layer "F.SilkS")
		)
		(fp_poly
			(pts
				(xy -5.08 3.0988) (xy 5.08 3.0988) (xy 5.08 -3.0988) (xy -5.08 -3.0988)
			)
			(stroke
				(width 0)
				(type default)
			)
			(fill no)
			(layer "F.CrtYd")
		)
		(fp_poly
			(pts
				(xy -5.08 -3.0988) (xy 5.08 -3.0988) (xy 5.08 3.0988) (xy -5.08 3.0988)
			)
			(stroke
				(width 0)
				(type default)
			)
			(fill no)
			(layer "F.Fab")
		)
		(pad "1" smd rect
			(at -3.4036 0)
			(size 2.2098 5.2832)
			(layers "F.Cu" "F.Mask" "F.Paste")
			(net "P12V_FAN4")
		)
		(pad "2" smd rect
			(at 3.4036 0)
			(size 2.2098 5.2832)
			(layers "F.Cu" "F.Mask" "F.Paste")
			(net "P12V")
		)
	)
	(footprint ""
		(layer "F.Cu")
		(at 7.949946 -56.099964 -90)
		(property "Reference" "LED6"
			(at 0 0 270)
			(layer "F.SilkS")
			(hide yes)
			(effects
				(font
					(size 1.27 1.27)
				)
			)
		)
		(property "Value" "LED-RB-6-GP"
			(at -4.6736 3.8354 270)
			(unlocked yes)
			(layer "F.Fab")
			(hide yes)
			(effects
				(font
					(size 1.016 1.016)
					(thickness 0.1524)
				)
			)
		)
		(property "Device Type" "LED-100-3P-067106H325"
			(at -4.6736 2.3114 270)
			(unlocked yes)
			(layer "F.Fab")
			(hide yes)
			(effects
				(font
					(size 1.016 1.016)
					(thickness 0.1524)
				)
			)
		)
		(duplicate_pad_numbers_are_jumpers no)
		(fp_line
			(start -1.7526 10.414)
			(end -1.7526 6.6548)
			(stroke
				(width 0.1524)
				(type default)
			)
			(layer "F.SilkS")
		)
		(fp_line
			(start 1.7526 10.414)
			(end -1.7526 10.414)
			(stroke
				(width 0.1524)
				(type default)
			)
			(layer "F.SilkS")
		)
		(fp_line
			(start -3.6068 6.6548)
			(end -3.6068 -0.889)
			(stroke
				(width 0.1524)
				(type default)
			)
			(layer "F.SilkS")
		)
		(fp_line
			(start -1.7526 6.6548)
			(end -3.6068 6.6548)
			(stroke
				(width 0.1524)
				(type default)
			)
			(layer "F.SilkS")
		)
		(fp_line
			(start 1.7526 6.6548)
			(end 1.7526 10.414)
			(stroke
				(width 0.1524)
				(type default)
			)
			(layer "F.SilkS")
		)
		(fp_line
			(start 3.6068 6.6548)
			(end 1.7526 6.6548)
			(stroke
				(width 0.1524)
				(type default)
			)
			(layer "F.SilkS")
		)
		(fp_line
			(start -3.6068 -0.889)
			(end 3.6068 -0.889)
			(stroke
				(width 0.1524)
				(type default)
			)
			(layer "F.SilkS")
		)
		(fp_line
			(start 3.6068 -0.889)
			(end 3.6068 6.6548)
			(stroke
				(width 0.1524)
				(type default)
			)
			(layer "F.SilkS")
		)
		(fp_circle
			(center -2.54 0)
			(end -2.54 -0.9906)
			(stroke
				(width 0.3048)
				(type default)
			)
			(fill no)
			(layer "F.SilkS")
		)
		(fp_circle
			(center 0 0)
			(end 0 -0.9906)
			(stroke
				(width 0.3048)
				(type default)
			)
			(fill no)
			(layer "F.SilkS")
		)
		(fp_circle
			(center 2.54 0)
			(end 2.54 -0.9906)
			(stroke
				(width 0.3048)
				(type default)
			)
			(fill no)
			(layer "F.SilkS")
		)
		(fp_poly
			(pts
				(xy -1.4986 10.1473) (xy -1.4986 6.4008) (xy -3.3528 6.4008) (xy -3.3528 -0.3937) (xy 3.3528 -0.3937)
				(xy 3.3528 6.4008) (xy 1.4986 6.4008) (xy 1.4986 10.1473)
			)
			(stroke
				(width 0)
				(type default)
			)
			(fill no)
			(layer "F.CrtYd")
		)
		(fp_poly
			(pts
				(xy -2.0066 10.668) (xy 2.0066 10.668) (xy 2.0066 6.9088) (xy 3.8608 6.9088) (xy 3.8608 2.2098)
				(xy 3.3528 2.2098) (xy 3.3528 6.4008) (xy 1.4986 6.4008) (xy 1.4986 10.1473) (xy -1.4986 10.1473)
				(xy -1.4986 6.4008) (xy -3.3528 6.4008) (xy -3.3528 -0.3937) (xy 3.3528 -0.3937) (xy 3.3528 2.1971)
				(xy 3.8608 2.1971) (xy 3.8608 -1.143) (xy -3.8608 -1.143) (xy -3.8608 6.9088) (xy -2.0066 6.9088)
			)
			(stroke
				(width 0)
				(type default)
			)
			(fill no)
			(layer "F.CrtYd")
		)
		(fp_poly
			(pts
				(xy -2.0066 10.668) (xy -2.0066 6.9088) (xy -3.8608 6.9088) (xy -3.8608 -1.143) (xy 3.8608 -1.143)
				(xy 3.8608 6.9088) (xy 2.0066 6.9088) (xy 2.0066 10.668)
			)
			(stroke
				(width 0)
				(type default)
			)
			(fill no)
			(layer "F.Fab")
		)
		(pad "1" thru_hole circle
			(at 2.54 0 270)
			(size 1.27 1.27)
			(drill 0.889)
			(layers "*.Cu" "*.Mask")
			(remove_unused_layers no)
			(net "LED_DR_LED5_BLUE")
			(clearance 0.1651)
			(thermal_gap 0.1651)
		)
		(pad "2" thru_hole circle
			(at 0 0 270)
			(size 1.27 1.27)
			(drill 0.889)
			(layers "*.Cu" "*.Mask")
			(remove_unused_layers no)
			(net "LED_DR_LED5_K")
			(clearance 0.1651)
			(thermal_gap 0.1651)
		)
		(pad "3" thru_hole circle
			(at -2.54 0 270)
			(size 1.27 1.27)
			(drill 0.889)
			(layers "*.Cu" "*.Mask")
			(remove_unused_layers no)
			(net "LED_DR_LED5")
			(clearance 0.1651)
			(thermal_gap 0.1651)
		)
	)
	(footprint ""
		(layer "F.Cu")
		(at 31.36011 -171.677076)
		(property "Reference" "C11"
			(at 0 0 0)
			(layer "F.SilkS")
			(hide yes)
			(effects
				(font
					(size 1.27 1.27)
				)
			)
		)
		(property "Value" "SCD1U50V3KX-GP"
			(at 0 -2.8194 0)
			(unlocked yes)
			(layer "F.Fab")
			(hide yes)
			(effects
				(font
					(size 1.016 1.016)
					(thickness 0.1524)
				)
			)
		)
		(property "Device Type" "C603H36"
			(at 0 -4.3434 0)
			(unlocked yes)
			(layer "F.Fab")
			(hide yes)
			(effects
				(font
					(size 1.016 1.016)
					(thickness 0.1524)
				)
			)
		)
		(duplicate_pad_numbers_are_jumpers no)
		(fp_line
			(start 0.508 0)
			(end -0.508 0)
			(stroke
				(width 0.2032)
				(type default)
			)
			(layer "F.SilkS")
		)
		(fp_rect
			(start -0.5842 1.3335)
			(end 0.5842 -1.3335)
			(stroke
				(width 0)
				(type default)
			)
			(fill no)
			(layer "F.CrtYd")
		)
		(fp_rect
			(start -0.5842 1.3335)
			(end 0.5842 -1.3335)
			(stroke
				(width 0)
				(type default)
			)
			(fill no)
			(layer "F.Fab")
		)
		(pad "1" smd custom
			(at 0 -0.762)
			(size 0.2159 0.2159)
			(layers "F.Cu" "F.Mask" "F.Paste")
			(net "P3V3")
			(options
				(clearance outline)
				(anchor circle)
			)
			(primitives
				(gr_poly
					(pts
						(arc
							(start -0.3302 -0.4318)
							(mid -0.402042 -0.402042)
							(end -0.4318 -0.3302)
						)
						(arc
							(start -0.4318 0.3302)
							(mid -0.402042 0.402042)
							(end -0.3302 0.4318)
						)
						(arc
							(start 0.3302 0.4318)
							(mid 0.402042 0.402042)
							(end 0.4318 0.3302)
						)
						(arc
							(start 0.4318 -0.3302)
							(mid 0.402042 -0.402042)
							(end 0.3302 -0.4318)
						)
					)
					(width 0)
					(fill yes)
				)
			)
		)
		(pad "2" smd custom
			(at 0 0.762)
			(size 0.2159 0.2159)
			(layers "F.Cu" "F.Mask" "F.Paste")
			(net "GND")
			(options
				(clearance outline)
				(anchor circle)
			)
			(primitives
				(gr_poly
					(pts
						(arc
							(start -0.3302 -0.4318)
							(mid -0.402042 -0.402042)
							(end -0.4318 -0.3302)
						)
						(arc
							(start -0.4318 0.3302)
							(mid -0.402042 0.402042)
							(end -0.3302 0.4318)
						)
						(arc
							(start 0.3302 0.4318)
							(mid 0.402042 0.402042)
							(end 0.4318 0.3302)
						)
						(arc
							(start 0.4318 -0.3302)
							(mid 0.402042 -0.402042)
							(end 0.3302 -0.4318)
						)
					)
					(width 0)
					(fill yes)
				)
			)
		)
	)
	(footprint ""
		(layer "F.Cu")
		(at 18.1356 -17.768316)
		(property "Reference" "C27"
			(at 0 0 0)
			(layer "F.SilkS")
			(hide yes)
			(effects
				(font
					(size 1.27 1.27)
				)
			)
		)
		(property "Value" "SCD1U16V2KX-3GP"
			(at 1.1811 -2.7051 0)
			(unlocked yes)
			(layer "F.Fab")
			(hide yes)
			(effects
				(font
					(size 1.016 1.016)
					(thickness 0.1524)
				)
			)
		)
		(property "Device Type" "C402H22"
			(at 1.1811 -4.2291 0)
			(unlocked yes)
			(layer "F.Fab")
			(hide yes)
			(effects
				(font
					(size 1.016 1.016)
					(thickness 0.1524)
				)
			)
		)
		(duplicate_pad_numbers_are_jumpers no)
		(fp_rect
			(start -0.4318 0.9525)
			(end 0.4318 -0.9525)
			(stroke
				(width 0)
				(type default)
			)
			(fill no)
			(layer "F.CrtYd")
		)
		(fp_rect
			(start -0.4318 0.9525)
			(end 0.4318 -0.9525)
			(stroke
				(width 0)
				(type default)
			)
			(fill no)
			(layer "F.Fab")
		)
		(pad "1" smd custom
			(at 0 -0.4445)
			(size 0.1524 0.1524)
			(layers "F.Cu" "F.Mask" "F.Paste")
			(net "FAN_TACH12")
			(options
				(clearance outline)
				(anchor circle)
			)
			(primitives
				(gr_poly
					(pts
						(arc
							(start 0.3048 -0.2032)
							(mid 0.275042 -0.275042)
							(end 0.2032 -0.3048)
						)
						(arc
							(start -0.2032 -0.3048)
							(mid -0.275042 -0.275042)
							(end -0.3048 -0.2032)
						)
						(arc
							(start -0.3048 0.2032)
							(mid -0.275042 0.275042)
							(end -0.2032 0.3048)
						)
						(arc
							(start 0.2032 0.3048)
							(mid 0.275042 0.275042)
							(end 0.3048 0.2032)
						)
					)
					(width 0)
					(fill yes)
				)
			)
		)
		(pad "2" smd custom
			(at 0 0.4445)
			(size 0.1524 0.1524)
			(layers "F.Cu" "F.Mask" "F.Paste")
			(net "GND")
			(options
				(clearance outline)
				(anchor circle)
			)
			(primitives
				(gr_poly
					(pts
						(arc
							(start 0.3048 -0.2032)
							(mid 0.275042 -0.275042)
							(end 0.2032 -0.3048)
						)
						(arc
							(start -0.2032 -0.3048)
							(mid -0.275042 -0.275042)
							(end -0.3048 -0.2032)
						)
						(arc
							(start -0.3048 0.2032)
							(mid -0.275042 0.275042)
							(end -0.2032 0.3048)
						)
						(arc
							(start 0.2032 0.3048)
							(mid 0.275042 0.275042)
							(end 0.3048 0.2032)
						)
					)
					(width 0)
					(fill yes)
				)
			)
		)
	)
	(footprint ""
		(layer "F.Cu")
		(at 44.069 -178.0794 90)
		(property "Reference" "R270"
			(at 0 0 90)
			(layer "F.SilkS")
			(hide yes)
			(effects
				(font
					(size 1.27 1.27)
				)
			)
		)
		(property "Value" "0R2J-2-GP"
			(at 0.064008 -3.993896 90)
			(unlocked yes)
			(layer "F.Fab")
			(hide yes)
			(effects
				(font
					(size 1.016 1.016)
					(thickness 0.1524)
				)
			)
		)
		(property "Device Type" "R402H16"
			(at 0.064008 -5.517896 90)
			(unlocked yes)
			(layer "F.Fab")
			(hide yes)
			(effects
				(font
					(size 1.016 1.016)
					(thickness 0.1524)
				)
			)
		)
		(duplicate_pad_numbers_are_jumpers no)
		(fp_line
			(start 0.508 -0.9398)
			(end -0.508 -0.9398)
			(stroke
				(width 0.1524)
				(type default)
			)
			(layer "F.SilkS")
		)
		(fp_line
			(start -0.508 -0.9398)
			(end -0.508 0.9398)
			(stroke
				(width 0.1524)
				(type default)
			)
			(layer "F.SilkS")
		)
		(fp_rect
			(start -0.508 0.9398)
			(end 0.508 -0.9398)
			(stroke
				(width 0)
				(type default)
			)
			(fill no)
			(layer "F.CrtYd")
		)
		(fp_rect
			(start -0.508 0.9398)
			(end 0.508 -0.9398)
			(stroke
				(width 0)
				(type default)
			)
			(fill no)
			(layer "F.Fab")
		)
		(pad "1" smd custom
			(at 0 -0.4445 90)
			(size 0.1397 0.1397)
			(layers "F.Cu" "F.Mask" "F.Paste")
			(net "D_LATCH_Q")
			(options
				(clearance outline)
				(anchor circle)
			)
			(primitives
				(gr_poly
					(pts
						(arc
							(start -0.1778 -0.2794)
							(mid -0.249642 -0.249642)
							(end -0.2794 -0.1778)
						)
						(arc
							(start -0.2794 0.1778)
							(mid -0.249642 0.249642)
							(end -0.1778 0.2794)
						)
						(arc
							(start 0.1778 0.2794)
							(mid 0.249642 0.249642)
							(end 0.2794 0.1778)
						)
						(arc
							(start 0.2794 -0.1778)
							(mid 0.249642 -0.249642)
							(end 0.1778 -0.2794)
						)
					)
					(width 0)
					(fill yes)
				)
			)
		)
		(pad "2" smd custom
			(at 0 0.4445 90)
			(size 0.1397 0.1397)
			(layers "F.Cu" "F.Mask" "F.Paste")
			(net "ADM1276_EN")
			(options
				(clearance outline)
				(anchor circle)
			)
			(primitives
				(gr_poly
					(pts
						(arc
							(start -0.1778 -0.2794)
							(mid -0.249642 -0.249642)
							(end -0.2794 -0.1778)
						)
						(arc
							(start -0.2794 0.1778)
							(mid -0.249642 0.249642)
							(end -0.1778 0.2794)
						)
						(arc
							(start 0.1778 0.2794)
							(mid 0.249642 0.249642)
							(end 0.2794 0.1778)
						)
						(arc
							(start 0.2794 -0.1778)
							(mid 0.249642 -0.249642)
							(end 0.1778 -0.2794)
						)
					)
					(width 0)
					(fill yes)
				)
			)
		)
	)
	(footprint ""
		(layer "F.Cu")
		(at 32.78251 -171.677076)
		(property "Reference" "C12"
			(at 0 0 0)
			(layer "F.SilkS")
			(hide yes)
			(effects
				(font
					(size 1.27 1.27)
				)
			)
		)
		(property "Value" "SC1U16V3KX-5GP"
			(at 0 -2.8194 0)
			(unlocked yes)
			(layer "F.Fab")
			(hide yes)
			(effects
				(font
					(size 1.016 1.016)
					(thickness 0.1524)
				)
			)
		)
		(property "Device Type" "C603H36"
			(at 0 -4.3434 0)
			(unlocked yes)
			(layer "F.Fab")
			(hide yes)
			(effects
				(font
					(size 1.016 1.016)
					(thickness 0.1524)
				)
			)
		)
		(duplicate_pad_numbers_are_jumpers no)
		(fp_line
			(start 0.508 0)
			(end -0.508 0)
			(stroke
				(width 0.2032)
				(type default)
			)
			(layer "F.SilkS")
		)
		(fp_rect
			(start -0.5842 1.3335)
			(end 0.5842 -1.3335)
			(stroke
				(width 0)
				(type default)
			)
			(fill no)
			(layer "F.CrtYd")
		)
		(fp_rect
			(start -0.5842 1.3335)
			(end 0.5842 -1.3335)
			(stroke
				(width 0)
				(type default)
			)
			(fill no)
			(layer "F.Fab")
		)
		(pad "1" smd custom
			(at 0 -0.762)
			(size 0.2159 0.2159)
			(layers "F.Cu" "F.Mask" "F.Paste")
			(net "P3V3")
			(options
				(clearance outline)
				(anchor circle)
			)
			(primitives
				(gr_poly
					(pts
						(arc
							(start -0.3302 -0.4318)
							(mid -0.402042 -0.402042)
							(end -0.4318 -0.3302)
						)
						(arc
							(start -0.4318 0.3302)
							(mid -0.402042 0.402042)
							(end -0.3302 0.4318)
						)
						(arc
							(start 0.3302 0.4318)
							(mid 0.402042 0.402042)
							(end 0.4318 0.3302)
						)
						(arc
							(start 0.4318 -0.3302)
							(mid 0.402042 -0.402042)
							(end 0.3302 -0.4318)
						)
					)
					(width 0)
					(fill yes)
				)
			)
		)
		(pad "2" smd custom
			(at 0 0.762)
			(size 0.2159 0.2159)
			(layers "F.Cu" "F.Mask" "F.Paste")
			(net "GND")
			(options
				(clearance outline)
				(anchor circle)
			)
			(primitives
				(gr_poly
					(pts
						(arc
							(start -0.3302 -0.4318)
							(mid -0.402042 -0.402042)
							(end -0.4318 -0.3302)
						)
						(arc
							(start -0.4318 0.3302)
							(mid -0.402042 0.402042)
							(end -0.3302 0.4318)
						)
						(arc
							(start 0.3302 0.4318)
							(mid 0.402042 0.402042)
							(end 0.4318 0.3302)
						)
						(arc
							(start 0.4318 -0.3302)
							(mid 0.402042 -0.402042)
							(end 0.3302 -0.4318)
						)
					)
					(width 0)
					(fill yes)
				)
			)
		)
	)
	(footprint ""
		(layer "F.Cu")
		(at 8.001 -169.418 -90)
		(property "Reference" "TC14"
			(at 0 0 270)
			(layer "F.SilkS")
			(hide yes)
			(effects
				(font
					(size 1.27 1.27)
				)
			)
		)
		(property "Value" "ST15U25VDM-1-GP"
			(at 0 -9.6012 270)
			(unlocked yes)
			(layer "F.Fab")
			(hide yes)
			(effects
				(font
					(size 1.016 1.016)
					(thickness 0.1524)
				)
			)
		)
		(property "Device Type" "CT7343H79"
			(at 0 -11.1252 270)
			(unlocked yes)
			(layer "F.Fab")
			(hide yes)
			(effects
				(font
					(size 1.016 1.016)
					(thickness 0.1524)
				)
			)
		)
		(duplicate_pad_numbers_are_jumpers no)
		(fp_line
			(start -2.286 4.8768)
			(end -2.286 2.032)
			(stroke
				(width 0.1524)
				(type default)
			)
			(layer "F.SilkS")
		)
		(fp_line
			(start 2.286 4.8768)
			(end -2.286 4.8768)
			(stroke
				(width 0.1524)
				(type default)
			)
			(layer "F.SilkS")
		)
		(fp_line
			(start 2.286 2.032)
			(end 2.286 4.8768)
			(stroke
				(width 0.1524)
				(type default)
			)
			(layer "F.SilkS")
		)
		(fp_line
			(start 2.286 -2.032)
			(end 2.286 -4.8768)
			(stroke
				(width 0.1524)
				(type default)
			)
			(layer "F.SilkS")
		)
		(fp_line
			(start 2.1082 -4.699)
			(end -2.1082 -4.699)
			(stroke
				(width 0.508)
				(type default)
			)
			(layer "F.SilkS")
		)
		(fp_line
			(start -2.286 -4.8768)
			(end -2.286 -2.032)
			(stroke
				(width 0.1524)
				(type default)
			)
			(layer "F.SilkS")
		)
		(fp_line
			(start 2.286 -4.8768)
			(end -2.286 -4.8768)
			(stroke
				(width 0.1524)
				(type default)
			)
			(layer "F.SilkS")
		)
		(fp_rect
			(start -2.1463 3.6449)
			(end 2.1463 -3.6449)
			(stroke
				(width 0)
				(type default)
			)
			(fill no)
			(layer "F.CrtYd")
		)
		(fp_poly
			(pts
				(xy -2.54 4.953) (xy -2.54 4.2926) (xy -3.81 4.2926) (xy -3.81 -4.2926) (xy -2.54 -4.2926) (xy -2.54 -4.953)
				(xy 2.54 -4.953) (xy 2.54 -4.2926) (xy 3.81 -4.2926) (xy 3.81 -1.6256) (xy 2.1463 -1.6256) (xy 2.1463 -3.6449)
				(xy -2.1463 -3.6449) (xy -2.1463 3.6449) (xy 2.1463 3.6449) (xy 2.1463 -1.6129) (xy 3.81 -1.6129)
				(xy 3.81 4.2926) (xy 2.54 4.2926) (xy 2.54 4.953)
			)
			(stroke
				(width 0)
				(type default)
			)
			(fill no)
			(layer "F.CrtYd")
		)
		(fp_rect
			(start -2.54 4.953)
			(end 2.54 -4.953)
			(stroke
				(width 0)
				(type default)
			)
			(fill no)
			(layer "F.Fab")
		)
		(fp_rect
			(start -3.81 4.2926)
			(end -2.54 -4.2926)
			(stroke
				(width 0)
				(type default)
			)
			(fill no)
			(layer "F.Fab")
		)
		(fp_rect
			(start 2.54 4.2926)
			(end 3.81 -4.2926)
			(stroke
				(width 0)
				(type default)
			)
			(fill no)
			(layer "F.Fab")
		)
		(pad "1" smd rect
			(at 0 -3.1496 270)
			(size 2.413 2.286)
			(layers "F.Cu" "F.Mask" "F.Paste")
			(net "P12V")
		)
		(pad "2" smd rect
			(at 0 3.1496 270)
			(size 2.413 2.286)
			(layers "F.Cu" "F.Mask" "F.Paste")
			(net "GND")
		)
		(zone
			(layer "F.Cu")
			(hatch none 0.5)
			(connect_pads
				(clearance 0)
			)
			(min_thickness 0.25)
			(keepout
				(tracks allowed)
				(vias not_allowed)
				(pads allowed)
				(copperpour not_allowed)
				(footprints allowed)
			)
			(placement
				(enabled no)
				(sheetname "")
			)
			(fill
				(thermal_gap 0.5)
				(thermal_bridge_width 0.5)
				(island_removal_mode 0)
			)
			(polygon
				(pts
					(xy 3.4036 -170.9293) (xy 3.4036 -167.9067) (xy 6.2992 -167.9067) (xy 6.6294 -167.9067) (xy 6.6294 -170.9293)
					(xy 6.2992 -170.9293)
				)
			)
		)
		(zone
			(layer "F.Cu")
			(hatch none 0.5)
			(connect_pads
				(clearance 0)
			)
			(min_thickness 0.25)
			(keepout
				(tracks allowed)
				(vias not_allowed)
				(pads allowed)
				(copperpour not_allowed)
				(footprints allowed)
			)
			(placement
				(enabled no)
				(sheetname "")
			)
			(fill
				(thermal_gap 0.5)
				(thermal_bridge_width 0.5)
				(island_removal_mode 0)
			)
			(polygon
				(pts
					(xy 9.6901 -167.9067) (xy 12.5984 -167.9067) (xy 12.5984 -170.9293) (xy 9.7028 -170.9293) (xy 9.3726 -170.9293)
					(xy 9.3726 -167.9067)
				)
			)
		)
	)
	(footprint ""
		(layer "F.Cu")
		(at 8.89 -148.1074 180)
		(property "Reference" "C28"
			(at 0 0 180)
			(layer "F.SilkS")
			(hide yes)
			(effects
				(font
					(size 1.27 1.27)
				)
			)
		)
		(property "Value" "SCD1U16V2KX-3GP"
			(at 1.1811 -2.7051 180)
			(unlocked yes)
			(layer "F.Fab")
			(hide yes)
			(effects
				(font
					(size 1.016 1.016)
					(thickness 0.1524)
				)
			)
		)
		(property "Device Type" "C402H22"
			(at 1.1811 -4.2291 180)
			(unlocked yes)
			(layer "F.Fab")
			(hide yes)
			(effects
				(font
					(size 1.016 1.016)
					(thickness 0.1524)
				)
			)
		)
		(duplicate_pad_numbers_are_jumpers no)
		(fp_rect
			(start -0.4318 0.9525)
			(end 0.4318 -0.9525)
			(stroke
				(width 0)
				(type default)
			)
			(fill no)
			(layer "F.CrtYd")
		)
		(fp_rect
			(start -0.4318 0.9525)
			(end 0.4318 -0.9525)
			(stroke
				(width 0)
				(type default)
			)
			(fill no)
			(layer "F.Fab")
		)
		(pad "1" smd custom
			(at 0 -0.4445 180)
			(size 0.1524 0.1524)
			(layers "F.Cu" "F.Mask" "F.Paste")
			(net "FAN_TACH10")
			(options
				(clearance outline)
				(anchor circle)
			)
			(primitives
				(gr_poly
					(pts
						(arc
							(start 0.3048 -0.2032)
							(mid 0.275042 -0.275042)
							(end 0.2032 -0.3048)
						)
						(arc
							(start -0.2032 -0.3048)
							(mid -0.275042 -0.275042)
							(end -0.3048 -0.2032)
						)
						(arc
							(start -0.3048 0.2032)
							(mid -0.275042 0.275042)
							(end -0.2032 0.3048)
						)
						(arc
							(start 0.2032 0.3048)
							(mid 0.275042 0.275042)
							(end 0.3048 0.2032)
						)
					)
					(width 0)
					(fill yes)
				)
			)
		)
		(pad "2" smd custom
			(at 0 0.4445 180)
			(size 0.1524 0.1524)
			(layers "F.Cu" "F.Mask" "F.Paste")
			(net "GND")
			(options
				(clearance outline)
				(anchor circle)
			)
			(primitives
				(gr_poly
					(pts
						(arc
							(start 0.3048 -0.2032)
							(mid 0.275042 -0.275042)
							(end 0.2032 -0.3048)
						)
						(arc
							(start -0.2032 -0.3048)
							(mid -0.275042 -0.275042)
							(end -0.3048 -0.2032)
						)
						(arc
							(start -0.3048 0.2032)
							(mid -0.275042 0.275042)
							(end -0.2032 0.3048)
						)
						(arc
							(start 0.2032 0.3048)
							(mid 0.275042 0.275042)
							(end 0.3048 0.2032)
						)
					)
					(width 0)
					(fill yes)
				)
			)
		)
	)
	(footprint ""
		(layer "F.Cu")
		(at 31.122366 -242.327176)
		(property "Reference" "R44"
			(at 0 0 0)
			(layer "F.SilkS")
			(hide yes)
			(effects
				(font
					(size 1.27 1.27)
				)
			)
		)
		(property "Value" "4K7R2J-2-GP"
			(at 0.064008 -3.993896 0)
			(unlocked yes)
			(layer "F.Fab")
			(hide yes)
			(effects
				(font
					(size 1.016 1.016)
					(thickness 0.1524)
				)
			)
		)
		(property "Device Type" "R402H16"
			(at 0.064008 -5.517896 0)
			(unlocked yes)
			(layer "F.Fab")
			(hide yes)
			(effects
				(font
					(size 1.016 1.016)
					(thickness 0.1524)
				)
			)
		)
		(duplicate_pad_numbers_are_jumpers no)
		(fp_line
			(start -0.508 -0.9398)
			(end -0.508 0.9398)
			(stroke
				(width 0.1524)
				(type default)
			)
			(layer "F.SilkS")
		)
		(fp_line
			(start 0.508 -0.9398)
			(end -0.508 -0.9398)
			(stroke
				(width 0.1524)
				(type default)
			)
			(layer "F.SilkS")
		)
		(fp_rect
			(start -0.508 0.9398)
			(end 0.508 -0.9398)
			(stroke
				(width 0)
				(type default)
			)
			(fill no)
			(layer "F.CrtYd")
		)
		(fp_rect
			(start -0.508 0.9398)
			(end 0.508 -0.9398)
			(stroke
				(width 0)
				(type default)
			)
			(fill no)
			(layer "F.Fab")
		)
		(pad "1" smd custom
			(at 0 -0.4445)
			(size 0.1397 0.1397)
			(layers "F.Cu" "F.Mask" "F.Paste")
			(net "FCB_EEPROM_A2")
			(options
				(clearance outline)
				(anchor circle)
			)
			(primitives
				(gr_poly
					(pts
						(arc
							(start -0.1778 -0.2794)
							(mid -0.249642 -0.249642)
							(end -0.2794 -0.1778)
						)
						(arc
							(start -0.2794 0.1778)
							(mid -0.249642 0.249642)
							(end -0.1778 0.2794)
						)
						(arc
							(start 0.1778 0.2794)
							(mid 0.249642 0.249642)
							(end 0.2794 0.1778)
						)
						(arc
							(start 0.2794 -0.1778)
							(mid 0.249642 -0.249642)
							(end 0.1778 -0.2794)
						)
					)
					(width 0)
					(fill yes)
				)
			)
		)
		(pad "2" smd custom
			(at 0 0.4445)
			(size 0.1397 0.1397)
			(layers "F.Cu" "F.Mask" "F.Paste")
			(net "GND")
			(options
				(clearance outline)
				(anchor circle)
			)
			(primitives
				(gr_poly
					(pts
						(arc
							(start -0.1778 -0.2794)
							(mid -0.249642 -0.249642)
							(end -0.2794 -0.1778)
						)
						(arc
							(start -0.2794 0.1778)
							(mid -0.249642 0.249642)
							(end -0.1778 0.2794)
						)
						(arc
							(start 0.1778 0.2794)
							(mid 0.249642 0.249642)
							(end 0.2794 0.1778)
						)
						(arc
							(start 0.2794 -0.1778)
							(mid 0.249642 -0.249642)
							(end 0.1778 -0.2794)
						)
					)
					(width 0)
					(fill yes)
				)
			)
		)
	)
	(footprint ""
		(layer "F.Cu")
		(at 28.067 -238.252 180)
		(property "Reference" "R39"
			(at 0 0 180)
			(layer "F.SilkS")
			(hide yes)
			(effects
				(font
					(size 1.27 1.27)
				)
			)
		)
		(property "Value" "4K7R2J-2-GP"
			(at 0.064008 -3.993896 180)
			(unlocked yes)
			(layer "F.Fab")
			(hide yes)
			(effects
				(font
					(size 1.016 1.016)
					(thickness 0.1524)
				)
			)
		)
		(property "Device Type" "R402H16"
			(at 0.064008 -5.517896 180)
			(unlocked yes)
			(layer "F.Fab")
			(hide yes)
			(effects
				(font
					(size 1.016 1.016)
					(thickness 0.1524)
				)
			)
		)
		(duplicate_pad_numbers_are_jumpers no)
		(fp_line
			(start 0.508 -0.9398)
			(end -0.508 -0.9398)
			(stroke
				(width 0.1524)
				(type default)
			)
			(layer "F.SilkS")
		)
		(fp_line
			(start -0.508 -0.9398)
			(end -0.508 0.9398)
			(stroke
				(width 0.1524)
				(type default)
			)
			(layer "F.SilkS")
		)
		(fp_rect
			(start -0.508 0.9398)
			(end 0.508 -0.9398)
			(stroke
				(width 0)
				(type default)
			)
			(fill no)
			(layer "F.CrtYd")
		)
		(fp_rect
			(start -0.508 0.9398)
			(end 0.508 -0.9398)
			(stroke
				(width 0)
				(type default)
			)
			(fill no)
			(layer "F.Fab")
		)
		(pad "1" smd custom
			(at 0 -0.4445 180)
			(size 0.1397 0.1397)
			(layers "F.Cu" "F.Mask" "F.Paste")
			(net "P3V3")
			(options
				(clearance outline)
				(anchor circle)
			)
			(primitives
				(gr_poly
					(pts
						(arc
							(start -0.1778 -0.2794)
							(mid -0.249642 -0.249642)
							(end -0.2794 -0.1778)
						)
						(arc
							(start -0.2794 0.1778)
							(mid -0.249642 0.249642)
							(end -0.1778 0.2794)
						)
						(arc
							(start 0.1778 0.2794)
							(mid 0.249642 0.249642)
							(end 0.2794 0.1778)
						)
						(arc
							(start 0.2794 -0.1778)
							(mid 0.249642 -0.249642)
							(end 0.1778 -0.2794)
						)
					)
					(width 0)
					(fill yes)
				)
			)
		)
		(pad "2" smd custom
			(at 0 0.4445 180)
			(size 0.1397 0.1397)
			(layers "F.Cu" "F.Mask" "F.Paste")
			(net "FCB_EEPROM_A0")
			(options
				(clearance outline)
				(anchor circle)
			)
			(primitives
				(gr_poly
					(pts
						(arc
							(start -0.1778 -0.2794)
							(mid -0.249642 -0.249642)
							(end -0.2794 -0.1778)
						)
						(arc
							(start -0.2794 0.1778)
							(mid -0.249642 0.249642)
							(end -0.1778 0.2794)
						)
						(arc
							(start 0.1778 0.2794)
							(mid 0.249642 0.249642)
							(end 0.2794 0.1778)
						)
						(arc
							(start 0.2794 -0.1778)
							(mid 0.249642 -0.249642)
							(end 0.1778 -0.2794)
						)
					)
					(width 0)
					(fill yes)
				)
			)
		)
	)
	(footprint ""
		(layer "F.Cu")
		(at 17.8816 -255.0922 -90)
		(property "Reference" "R82"
			(at 0 0 270)
			(layer "F.SilkS")
			(hide yes)
			(effects
				(font
					(size 1.27 1.27)
				)
			)
		)
		(property "Value" "4K7R2F-GP"
			(at 0.064008 -3.993896 270)
			(unlocked yes)
			(layer "F.Fab")
			(hide yes)
			(effects
				(font
					(size 1.016 1.016)
					(thickness 0.1524)
				)
			)
		)
		(property "Device Type" "R402H16"
			(at 0.064008 -5.517896 270)
			(unlocked yes)
			(layer "F.Fab")
			(hide yes)
			(effects
				(font
					(size 1.016 1.016)
					(thickness 0.1524)
				)
			)
		)
		(duplicate_pad_numbers_are_jumpers no)
		(fp_line
			(start -0.508 -0.9398)
			(end -0.508 0.9398)
			(stroke
				(width 0.1524)
				(type default)
			)
			(layer "F.SilkS")
		)
		(fp_line
			(start 0.508 -0.9398)
			(end -0.508 -0.9398)
			(stroke
				(width 0.1524)
				(type default)
			)
			(layer "F.SilkS")
		)
		(fp_rect
			(start -0.508 0.9398)
			(end 0.508 -0.9398)
			(stroke
				(width 0)
				(type default)
			)
			(fill no)
			(layer "F.CrtYd")
		)
		(fp_rect
			(start -0.508 0.9398)
			(end 0.508 -0.9398)
			(stroke
				(width 0)
				(type default)
			)
			(fill no)
			(layer "F.Fab")
		)
		(pad "1" smd custom
			(at 0 -0.4445 270)
			(size 0.1397 0.1397)
			(layers "F.Cu" "F.Mask" "F.Paste")
			(net "P12V")
			(options
				(clearance outline)
				(anchor circle)
			)
			(primitives
				(gr_poly
					(pts
						(arc
							(start -0.1778 -0.2794)
							(mid -0.249642 -0.249642)
							(end -0.2794 -0.1778)
						)
						(arc
							(start -0.2794 0.1778)
							(mid -0.249642 0.249642)
							(end -0.1778 0.2794)
						)
						(arc
							(start 0.1778 0.2794)
							(mid 0.249642 0.249642)
							(end 0.2794 0.1778)
						)
						(arc
							(start 0.2794 -0.1778)
							(mid 0.249642 -0.249642)
							(end 0.1778 -0.2794)
						)
					)
					(width 0)
					(fill yes)
				)
			)
		)
		(pad "2" smd custom
			(at 0 0.4445 270)
			(size 0.1397 0.1397)
			(layers "F.Cu" "F.Mask" "F.Paste")
			(net "FAN_TACH5")
			(options
				(clearance outline)
				(anchor circle)
			)
			(primitives
				(gr_poly
					(pts
						(arc
							(start -0.1778 -0.2794)
							(mid -0.249642 -0.249642)
							(end -0.2794 -0.1778)
						)
						(arc
							(start -0.2794 0.1778)
							(mid -0.249642 0.249642)
							(end -0.1778 0.2794)
						)
						(arc
							(start 0.1778 0.2794)
							(mid 0.249642 0.249642)
							(end 0.2794 0.1778)
						)
						(arc
							(start 0.2794 -0.1778)
							(mid 0.249642 -0.249642)
							(end 0.1778 -0.2794)
						)
					)
					(width 0)
					(fill yes)
				)
			)
		)
	)
	(footprint ""
		(layer "F.Cu")
		(at 28.2956 -362.1786 90)
		(property "Reference" "PR12"
			(at 0 0 90)
			(layer "F.SilkS")
			(hide yes)
			(effects
				(font
					(size 1.27 1.27)
				)
			)
		)
		(property "Value" "0R2J-2-GP"
			(at 0.064008 -3.993896 90)
			(unlocked yes)
			(layer "F.Fab")
			(hide yes)
			(effects
				(font
					(size 1.016 1.016)
					(thickness 0.1524)
				)
			)
		)
		(property "Device Type" "R402H16"
			(at 0.064008 -5.517896 90)
			(unlocked yes)
			(layer "F.Fab")
			(hide yes)
			(effects
				(font
					(size 1.016 1.016)
					(thickness 0.1524)
				)
			)
		)
		(duplicate_pad_numbers_are_jumpers no)
		(fp_line
			(start 0.508 -0.9398)
			(end -0.508 -0.9398)
			(stroke
				(width 0.1524)
				(type default)
			)
			(layer "F.SilkS")
		)
		(fp_line
			(start -0.508 -0.9398)
			(end -0.508 0.9398)
			(stroke
				(width 0.1524)
				(type default)
			)
			(layer "F.SilkS")
		)
		(fp_rect
			(start -0.508 0.9398)
			(end 0.508 -0.9398)
			(stroke
				(width 0)
				(type default)
			)
			(fill no)
			(layer "F.CrtYd")
		)
		(fp_rect
			(start -0.508 0.9398)
			(end 0.508 -0.9398)
			(stroke
				(width 0)
				(type default)
			)
			(fill no)
			(layer "F.Fab")
		)
		(pad "1" smd custom
			(at 0 -0.4445 90)
			(size 0.1397 0.1397)
			(layers "F.Cu" "F.Mask" "F.Paste")
			(net "ADM1276_LATCH#")
			(options
				(clearance outline)
				(anchor circle)
			)
			(primitives
				(gr_poly
					(pts
						(arc
							(start -0.1778 -0.2794)
							(mid -0.249642 -0.249642)
							(end -0.2794 -0.1778)
						)
						(arc
							(start -0.2794 0.1778)
							(mid -0.249642 0.249642)
							(end -0.1778 0.2794)
						)
						(arc
							(start 0.1778 0.2794)
							(mid 0.249642 0.249642)
							(end 0.2794 0.1778)
						)
						(arc
							(start 0.2794 -0.1778)
							(mid 0.249642 -0.249642)
							(end 0.1778 -0.2794)
						)
					)
					(width 0)
					(fill yes)
				)
			)
		)
		(pad "2" smd custom
			(at 0 0.4445 90)
			(size 0.1397 0.1397)
			(layers "F.Cu" "F.Mask" "F.Paste")
			(net "ADM1276_EN")
			(options
				(clearance outline)
				(anchor circle)
			)
			(primitives
				(gr_poly
					(pts
						(arc
							(start -0.1778 -0.2794)
							(mid -0.249642 -0.249642)
							(end -0.2794 -0.1778)
						)
						(arc
							(start -0.2794 0.1778)
							(mid -0.249642 0.249642)
							(end -0.1778 0.2794)
						)
						(arc
							(start 0.1778 0.2794)
							(mid 0.249642 0.249642)
							(end 0.2794 0.1778)
						)
						(arc
							(start 0.2794 -0.1778)
							(mid 0.249642 -0.249642)
							(end 0.1778 -0.2794)
						)
					)
					(width 0)
					(fill yes)
				)
			)
		)
	)
	(footprint ""
		(layer "F.Cu")
		(at 16.2052 -249.1994 180)
		(property "Reference" "PC40"
			(at 0 0 180)
			(layer "F.SilkS")
			(hide yes)
			(effects
				(font
					(size 1.27 1.27)
				)
			)
		)
		(property "Value" "SC4D7U50V6KX-L2-GP"
			(at 0 -6.8072 180)
			(unlocked yes)
			(layer "F.Fab")
			(hide yes)
			(effects
				(font
					(size 1.016 1.016)
					(thickness 0.1524)
				)
			)
		)
		(property "Device Type" "C1206H38"
			(at 0 -8.7122 180)
			(unlocked yes)
			(layer "F.Fab")
			(hide yes)
			(effects
				(font
					(size 1.016 1.016)
					(thickness 0.1524)
				)
			)
		)
		(duplicate_pad_numbers_are_jumpers no)
		(fp_line
			(start 1.016 2.2352)
			(end -1.016 2.2352)
			(stroke
				(width 0.1524)
				(type default)
			)
			(layer "F.SilkS")
		)
		(fp_line
			(start 1.016 0.8382)
			(end 1.016 2.2352)
			(stroke
				(width 0.1524)
				(type default)
			)
			(layer "F.SilkS")
		)
		(fp_line
			(start 1.016 -2.2352)
			(end 1.016 -0.8382)
			(stroke
				(width 0.1524)
				(type default)
			)
			(layer "F.SilkS")
		)
		(fp_line
			(start 1.016 -2.2352)
			(end -1.016 -2.2352)
			(stroke
				(width 0.1524)
				(type default)
			)
			(layer "F.SilkS")
		)
		(fp_line
			(start -1.016 2.2352)
			(end -1.016 0.8128)
			(stroke
				(width 0.1524)
				(type default)
			)
			(layer "F.SilkS")
		)
		(fp_line
			(start -1.016 -2.2352)
			(end -1.016 -0.8382)
			(stroke
				(width 0.1524)
				(type default)
			)
			(layer "F.SilkS")
		)
		(fp_rect
			(start -1.0922 2.3114)
			(end 1.0922 -2.3114)
			(stroke
				(width 0)
				(type default)
			)
			(fill no)
			(layer "F.CrtYd")
		)
		(fp_poly
			(pts
				(xy -1.0922 -2.3114) (xy 1.0922 -2.3114) (xy 1.0922 2.3114) (xy -1.0922 2.3114)
			)
			(stroke
				(width 0)
				(type default)
			)
			(fill no)
			(layer "F.Fab")
		)
		(pad "1" smd rect
			(at 0 -1.397 180)
			(size 1.651 1.27)
			(layers "F.Cu" "F.Mask" "F.Paste")
			(net "P3V3_IN")
		)
		(pad "2" smd rect
			(at 0 1.397 180)
			(size 1.651 1.27)
			(layers "F.Cu" "F.Mask" "F.Paste")
			(net "GND")
		)
	)
	(footprint ""
		(layer "F.Cu")
		(at 15.5956 -171.4754)
		(property "Reference" "R52"
			(at 0 0 0)
			(layer "F.SilkS")
			(hide yes)
			(effects
				(font
					(size 1.27 1.27)
				)
			)
		)
		(property "Value" "4K7R2F-GP"
			(at 0.064008 -3.993896 0)
			(unlocked yes)
			(layer "F.Fab")
			(hide yes)
			(effects
				(font
					(size 1.016 1.016)
					(thickness 0.1524)
				)
			)
		)
		(property "Device Type" "R402H16"
			(at 0.064008 -5.517896 0)
			(unlocked yes)
			(layer "F.Fab")
			(hide yes)
			(effects
				(font
					(size 1.016 1.016)
					(thickness 0.1524)
				)
			)
		)
		(duplicate_pad_numbers_are_jumpers no)
		(fp_line
			(start -0.508 -0.9398)
			(end -0.508 0.9398)
			(stroke
				(width 0.1524)
				(type default)
			)
			(layer "F.SilkS")
		)
		(fp_line
			(start 0.508 -0.9398)
			(end -0.508 -0.9398)
			(stroke
				(width 0.1524)
				(type default)
			)
			(layer "F.SilkS")
		)
		(fp_rect
			(start -0.508 0.9398)
			(end 0.508 -0.9398)
			(stroke
				(width 0)
				(type default)
			)
			(fill no)
			(layer "F.CrtYd")
		)
		(fp_rect
			(start -0.508 0.9398)
			(end 0.508 -0.9398)
			(stroke
				(width 0)
				(type default)
			)
			(fill no)
			(layer "F.Fab")
		)
		(pad "1" smd custom
			(at 0 -0.4445)
			(size 0.1397 0.1397)
			(layers "F.Cu" "F.Mask" "F.Paste")
			(net "P3V3")
			(options
				(clearance outline)
				(anchor circle)
			)
			(primitives
				(gr_poly
					(pts
						(arc
							(start -0.1778 -0.2794)
							(mid -0.249642 -0.249642)
							(end -0.2794 -0.1778)
						)
						(arc
							(start -0.2794 0.1778)
							(mid -0.249642 0.249642)
							(end -0.1778 0.2794)
						)
						(arc
							(start 0.1778 0.2794)
							(mid 0.249642 0.249642)
							(end 0.2794 0.1778)
						)
						(arc
							(start 0.2794 -0.1778)
							(mid 0.249642 -0.249642)
							(end 0.1778 -0.2794)
						)
					)
					(width 0)
					(fill yes)
				)
			)
		)
		(pad "2" smd custom
			(at 0 0.4445)
			(size 0.1397 0.1397)
			(layers "F.Cu" "F.Mask" "F.Paste")
			(net "SEB_PEER_2A_2B_HB_OUT")
			(options
				(clearance outline)
				(anchor circle)
			)
			(primitives
				(gr_poly
					(pts
						(arc
							(start -0.1778 -0.2794)
							(mid -0.249642 -0.249642)
							(end -0.2794 -0.1778)
						)
						(arc
							(start -0.2794 0.1778)
							(mid -0.249642 0.249642)
							(end -0.1778 0.2794)
						)
						(arc
							(start 0.1778 0.2794)
							(mid 0.249642 0.249642)
							(end 0.2794 0.1778)
						)
						(arc
							(start 0.2794 -0.1778)
							(mid 0.249642 -0.249642)
							(end 0.1778 -0.2794)
						)
					)
					(width 0)
					(fill yes)
				)
			)
		)
	)
	(footprint ""
		(layer "F.Cu")
		(at 24.500078 -450.44995 90)
		(property "Reference" "PAD1"
			(at 0 0 90)
			(layer "F.SilkS")
			(hide yes)
			(effects
				(font
					(size 1.27 1.27)
				)
			)
		)
		(property "Value" "PAD-1P-424137-2-OG-GP"
			(at -22.9743 -0.4572 90)
			(unlocked yes)
			(layer "F.Fab")
			(hide yes)
			(effects
				(font
					(size 1.016 1.016)
					(thickness 0.1524)
				)
			)
		)
		(property "Device Type" "PAD-1P-424137-2-OG"
			(at -22.9743 -1.9812 90)
			(unlocked yes)
			(layer "F.Fab")
			(hide yes)
			(effects
				(font
					(size 1.016 1.016)
					(thickness 0.1524)
				)
			)
		)
		(duplicate_pad_numbers_are_jumpers no)
		(fp_line
			(start 21.4503 -7.0993)
			(end 21.4503 7.0993)
			(stroke
				(width 0.1524)
				(type default)
			)
			(layer "F.SilkS")
		)
		(fp_line
			(start -21.4503 -7.0993)
			(end 21.4503 -7.0993)
			(stroke
				(width 0.1524)
				(type default)
			)
			(layer "F.SilkS")
		)
		(fp_line
			(start -0.075946 5.750052)
			(end -0.075946 7.0993)
			(stroke
				(width 0.1524)
				(type default)
			)
			(layer "F.SilkS")
		)
		(fp_line
			(start 21.4503 7.0993)
			(end 2.816098 7.0993)
			(stroke
				(width 0.1524)
				(type default)
			)
			(layer "F.SilkS")
		)
		(fp_line
			(start 2.816098 7.0993)
			(end 2.816098 5.750052)
			(stroke
				(width 0.1524)
				(type default)
			)
			(layer "F.SilkS")
		)
		(fp_line
			(start -0.075946 7.0993)
			(end -21.4503 7.0993)
			(stroke
				(width 0.1524)
				(type default)
			)
			(layer "F.SilkS")
		)
		(fp_line
			(start -21.4503 7.0993)
			(end -21.4503 -7.0993)
			(stroke
				(width 0.1524)
				(type default)
			)
			(layer "F.SilkS")
		)
		(fp_arc
			(start -0.075946 5.750052)
			(mid 1.37008 4.304026)
			(end 2.816098 5.750052)
			(stroke
				(width 0.1524)
				(type default)
			)
			(layer "F.SilkS")
		)
		(fp_poly
			(pts
				(xy -21.7043 7.3533) (xy -21.7043 -7.3533) (xy 21.7043 -7.3533) (xy 21.7043 7.3533) (xy 2.562098 7.3533)
				(arc
					(start 2.562098 5.750052)
					(mid 1.370076 4.55803)
					(end 0.178054 5.750052)
				)
				(xy 0.178054 7.3533)
			)
			(stroke
				(width 0)
				(type default)
			)
			(fill no)
			(layer "F.CrtYd")
		)
		(fp_poly
			(pts
				(xy -21.7043 7.3533) (xy -21.7043 -7.3533) (xy 21.7043 -7.3533) (xy 21.7043 7.3533) (xy 2.562098 7.3533)
				(arc
					(start 2.562098 5.750052)
					(mid 1.370076 4.55803)
					(end 0.178054 5.750052)
				)
				(xy 0.178054 7.3533)
			)
			(stroke
				(width 0)
				(type default)
			)
			(fill no)
			(layer "F.Fab")
		)
		(pad "1" smd custom
			(at 0 0 90)
			(size 3.425063 3.425063)
			(layers "F.Cu" "F.Mask" "F.Paste")
			(net "P12V_AUX")
			(options
				(clearance outline)
				(anchor circle)
			)
			(primitives
				(gr_poly
					(pts
						(xy -0.329946 6.850126) (xy -21.20011 6.850126) (xy -21.20011 -6.850126) (xy 21.20011 -6.850126)
						(xy 21.20011 6.850126) (xy 3.070098 6.850126)
						(arc
							(start 3.070098 5.750052)
							(mid 1.370076 4.05003)
							(end -0.329946 5.750052)
						)
					)
					(width 0)
					(fill yes)
				)
			)
		)
	)
	(footprint ""
		(layer "F.Cu")
		(at 36.1188 -370.4336 90)
		(property "Reference" "PR8"
			(at 0 0 90)
			(layer "F.SilkS")
			(hide yes)
			(effects
				(font
					(size 1.27 1.27)
				)
			)
		)
		(property "Value" "11KR2F-L-GP"
			(at 0.064008 -3.993896 90)
			(unlocked yes)
			(layer "F.Fab")
			(hide yes)
			(effects
				(font
					(size 1.016 1.016)
					(thickness 0.1524)
				)
			)
		)
		(property "Device Type" "R402H16"
			(at 0.064008 -5.517896 90)
			(unlocked yes)
			(layer "F.Fab")
			(hide yes)
			(effects
				(font
					(size 1.016 1.016)
					(thickness 0.1524)
				)
			)
		)
		(duplicate_pad_numbers_are_jumpers no)
		(fp_line
			(start 0.508 -0.9398)
			(end -0.508 -0.9398)
			(stroke
				(width 0.1524)
				(type default)
			)
			(layer "F.SilkS")
		)
		(fp_line
			(start -0.508 -0.9398)
			(end -0.508 0.9398)
			(stroke
				(width 0.1524)
				(type default)
			)
			(layer "F.SilkS")
		)
		(fp_rect
			(start -0.508 0.9398)
			(end 0.508 -0.9398)
			(stroke
				(width 0)
				(type default)
			)
			(fill no)
			(layer "F.CrtYd")
		)
		(fp_rect
			(start -0.508 0.9398)
			(end 0.508 -0.9398)
			(stroke
				(width 0)
				(type default)
			)
			(fill no)
			(layer "F.Fab")
		)
		(pad "1" smd custom
			(at 0 -0.4445 90)
			(size 0.1397 0.1397)
			(layers "F.Cu" "F.Mask" "F.Paste")
			(net "ADM1276_FLB")
			(options
				(clearance outline)
				(anchor circle)
			)
			(primitives
				(gr_poly
					(pts
						(arc
							(start -0.1778 -0.2794)
							(mid -0.249642 -0.249642)
							(end -0.2794 -0.1778)
						)
						(arc
							(start -0.2794 0.1778)
							(mid -0.249642 0.249642)
							(end -0.1778 0.2794)
						)
						(arc
							(start 0.1778 0.2794)
							(mid 0.249642 0.249642)
							(end 0.2794 0.1778)
						)
						(arc
							(start 0.2794 -0.1778)
							(mid 0.249642 -0.249642)
							(end 0.1778 -0.2794)
						)
					)
					(width 0)
					(fill yes)
				)
			)
		)
		(pad "2" smd custom
			(at 0 0.4445 90)
			(size 0.1397 0.1397)
			(layers "F.Cu" "F.Mask" "F.Paste")
			(net "GND")
			(options
				(clearance outline)
				(anchor circle)
			)
			(primitives
				(gr_poly
					(pts
						(arc
							(start -0.1778 -0.2794)
							(mid -0.249642 -0.249642)
							(end -0.2794 -0.1778)
						)
						(arc
							(start -0.2794 0.1778)
							(mid -0.249642 0.249642)
							(end -0.1778 0.2794)
						)
						(arc
							(start 0.1778 0.2794)
							(mid 0.249642 0.249642)
							(end 0.2794 0.1778)
						)
						(arc
							(start 0.2794 -0.1778)
							(mid 0.249642 -0.249642)
							(end 0.1778 -0.2794)
						)
					)
					(width 0)
					(fill yes)
				)
			)
		)
	)
	(footprint ""
		(layer "F.Cu")
		(at 38.024816 -354.076 -90)
		(property "Reference" "R363"
			(at 0 0 270)
			(layer "F.SilkS")
			(hide yes)
			(effects
				(font
					(size 1.27 1.27)
				)
			)
		)
		(property "Value" "5K1R2F-2-GP"
			(at 0.064008 -3.993896 270)
			(unlocked yes)
			(layer "F.Fab")
			(hide yes)
			(effects
				(font
					(size 1.016 1.016)
					(thickness 0.1524)
				)
			)
		)
		(property "Device Type" "R402H16"
			(at 0.064008 -5.517896 270)
			(unlocked yes)
			(layer "F.Fab")
			(hide yes)
			(effects
				(font
					(size 1.016 1.016)
					(thickness 0.1524)
				)
			)
		)
		(duplicate_pad_numbers_are_jumpers no)
		(fp_line
			(start -0.508 -0.9398)
			(end -0.508 0.9398)
			(stroke
				(width 0.1524)
				(type default)
			)
			(layer "F.SilkS")
		)
		(fp_line
			(start 0.508 -0.9398)
			(end -0.508 -0.9398)
			(stroke
				(width 0.1524)
				(type default)
			)
			(layer "F.SilkS")
		)
		(fp_rect
			(start -0.508 0.9398)
			(end 0.508 -0.9398)
			(stroke
				(width 0)
				(type default)
			)
			(fill no)
			(layer "F.CrtYd")
		)
		(fp_rect
			(start -0.508 0.9398)
			(end 0.508 -0.9398)
			(stroke
				(width 0)
				(type default)
			)
			(fill no)
			(layer "F.Fab")
		)
		(pad "1" smd custom
			(at 0 -0.4445 270)
			(size 0.1397 0.1397)
			(layers "F.Cu" "F.Mask" "F.Paste")
			(net "OTP_RETRY_B")
			(options
				(clearance outline)
				(anchor circle)
			)
			(primitives
				(gr_poly
					(pts
						(arc
							(start -0.1778 -0.2794)
							(mid -0.249642 -0.249642)
							(end -0.2794 -0.1778)
						)
						(arc
							(start -0.2794 0.1778)
							(mid -0.249642 0.249642)
							(end -0.1778 0.2794)
						)
						(arc
							(start 0.1778 0.2794)
							(mid 0.249642 0.249642)
							(end 0.2794 0.1778)
						)
						(arc
							(start 0.2794 -0.1778)
							(mid 0.249642 -0.249642)
							(end 0.1778 -0.2794)
						)
					)
					(width 0)
					(fill yes)
				)
			)
		)
		(pad "2" smd custom
			(at 0 0.4445 270)
			(size 0.1397 0.1397)
			(layers "F.Cu" "F.Mask" "F.Paste")
			(net "GND")
			(options
				(clearance outline)
				(anchor circle)
			)
			(primitives
				(gr_poly
					(pts
						(arc
							(start -0.1778 -0.2794)
							(mid -0.249642 -0.249642)
							(end -0.2794 -0.1778)
						)
						(arc
							(start -0.2794 0.1778)
							(mid -0.249642 0.249642)
							(end -0.1778 0.2794)
						)
						(arc
							(start 0.1778 0.2794)
							(mid 0.249642 0.249642)
							(end 0.2794 0.1778)
						)
						(arc
							(start 0.2794 -0.1778)
							(mid 0.249642 -0.249642)
							(end 0.1778 -0.2794)
						)
					)
					(width 0)
					(fill yes)
				)
			)
		)
	)
	(footprint ""
		(layer "F.Cu")
		(at 7.141972 -277.643082 90)
		(property "Reference" "Q6"
			(at 0 0 90)
			(layer "F.SilkS")
			(hide yes)
			(effects
				(font
					(size 1.27 1.27)
				)
			)
		)
		(property "Value" "PMBS3904-1-GP"
			(at 0 -9.0932 90)
			(unlocked yes)
			(layer "F.Fab")
			(hide yes)
			(effects
				(font
					(size 1.016 1.016)
					(thickness 0.1524)
				)
			)
		)
		(property "Device Type" "SOT-23-10H44"
			(at 0 -10.6172 90)
			(unlocked yes)
			(layer "F.Fab")
			(hide yes)
			(effects
				(font
					(size 1.016 1.016)
					(thickness 0.1524)
				)
			)
		)
		(duplicate_pad_numbers_are_jumpers no)
		(fp_line
			(start 1.651 -1.778)
			(end -1.651 -1.778)
			(stroke
				(width 0.1524)
				(type default)
			)
			(layer "F.SilkS")
		)
		(fp_line
			(start -1.651 -1.778)
			(end -1.651 1.778)
			(stroke
				(width 0.1524)
				(type default)
			)
			(layer "F.SilkS")
		)
		(fp_line
			(start 1.651 1.778)
			(end 1.651 -1.778)
			(stroke
				(width 0.1524)
				(type default)
			)
			(layer "F.SilkS")
		)
		(fp_line
			(start -1.651 1.778)
			(end 1.651 1.778)
			(stroke
				(width 0.1524)
				(type default)
			)
			(layer "F.SilkS")
		)
		(fp_line
			(start -0.9906 1.86309)
			(end -0.701294 2.15265)
			(stroke
				(width 0.0127)
				(type default)
			)
			(layer "F.SilkS")
		)
		(fp_line
			(start -0.994156 1.8669)
			(end -0.987044 1.8669)
			(stroke
				(width 0.0127)
				(type default)
			)
			(layer "F.SilkS")
		)
		(fp_line
			(start -1.003808 1.876552)
			(end -0.977646 1.876552)
			(stroke
				(width 0.0127)
				(type default)
			)
			(layer "F.SilkS")
		)
		(fp_line
			(start -0.635 1.8796)
			(end -1.7526 1.8796)
			(stroke
				(width 0.3302)
				(type default)
			)
			(layer "F.SilkS")
		)
		(fp_line
			(start -1.7526 1.8796)
			(end -1.7526 0.9906)
			(stroke
				(width 0.3302)
				(type default)
			)
			(layer "F.SilkS")
		)
		(fp_line
			(start -1.013206 1.88595)
			(end -0.967994 1.88595)
			(stroke
				(width 0.0127)
				(type default)
			)
			(layer "F.SilkS")
		)
		(fp_line
			(start -1.022858 1.895602)
			(end -0.958596 1.895602)
			(stroke
				(width 0.0127)
				(type default)
			)
			(layer "F.SilkS")
		)
		(fp_line
			(start -1.032256 1.905)
			(end -0.948944 1.905)
			(stroke
				(width 0.0127)
				(type default)
			)
			(layer "F.SilkS")
		)
		(fp_line
			(start -1.041908 1.914652)
			(end -0.939546 1.914652)
			(stroke
				(width 0.0127)
				(type default)
			)
			(layer "F.SilkS")
		)
		(fp_line
			(start -1.051306 1.92405)
			(end -0.929894 1.92405)
			(stroke
				(width 0.0127)
				(type default)
			)
			(layer "F.SilkS")
		)
		(fp_line
			(start -1.060958 1.933702)
			(end -0.920496 1.933702)
			(stroke
				(width 0.0127)
				(type default)
			)
			(layer "F.SilkS")
		)
		(fp_line
			(start -1.070356 1.9431)
			(end -0.910844 1.9431)
			(stroke
				(width 0.0127)
				(type default)
			)
			(layer "F.SilkS")
		)
		(fp_line
			(start -1.080008 1.952752)
			(end -0.901446 1.952752)
			(stroke
				(width 0.0127)
				(type default)
			)
			(layer "F.SilkS")
		)
		(fp_line
			(start -1.089406 1.96215)
			(end -0.891794 1.96215)
			(stroke
				(width 0.0127)
				(type default)
			)
			(layer "F.SilkS")
		)
		(fp_line
			(start -1.099058 1.971802)
			(end -0.882396 1.971802)
			(stroke
				(width 0.0127)
				(type default)
			)
			(layer "F.SilkS")
		)
		(fp_line
			(start -1.108456 1.9812)
			(end -0.872744 1.9812)
			(stroke
				(width 0.0127)
				(type default)
			)
			(layer "F.SilkS")
		)
		(fp_line
			(start -1.118108 1.990852)
			(end -0.863346 1.990852)
			(stroke
				(width 0.0127)
				(type default)
			)
			(layer "F.SilkS")
		)
		(fp_line
			(start -1.127506 2.00025)
			(end -0.853694 2.00025)
			(stroke
				(width 0.0127)
				(type default)
			)
			(layer "F.SilkS")
		)
		(fp_line
			(start -1.137158 2.009902)
			(end -0.844296 2.009902)
			(stroke
				(width 0.0127)
				(type default)
			)
			(layer "F.SilkS")
		)
		(fp_line
			(start -1.146556 2.0193)
			(end -0.834644 2.0193)
			(stroke
				(width 0.0127)
				(type default)
			)
			(layer "F.SilkS")
		)
		(fp_line
			(start -1.156208 2.028952)
			(end -0.825246 2.028952)
			(stroke
				(width 0.0127)
				(type default)
			)
			(layer "F.SilkS")
		)
		(fp_line
			(start -1.165606 2.03835)
			(end -0.815594 2.03835)
			(stroke
				(width 0.0127)
				(type default)
			)
			(layer "F.SilkS")
		)
		(fp_line
			(start -1.175258 2.048002)
			(end -0.806196 2.048002)
			(stroke
				(width 0.0127)
				(type default)
			)
			(layer "F.SilkS")
		)
		(fp_line
			(start -1.184656 2.0574)
			(end -0.796544 2.0574)
			(stroke
				(width 0.0127)
				(type default)
			)
			(layer "F.SilkS")
		)
		(fp_line
			(start -1.194308 2.067052)
			(end -0.787146 2.067052)
			(stroke
				(width 0.0127)
				(type default)
			)
			(layer "F.SilkS")
		)
		(fp_line
			(start -1.203706 2.07645)
			(end -0.777494 2.07645)
			(stroke
				(width 0.0127)
				(type default)
			)
			(layer "F.SilkS")
		)
		(fp_line
			(start -1.213358 2.086102)
			(end -0.768096 2.086102)
			(stroke
				(width 0.0127)
				(type default)
			)
			(layer "F.SilkS")
		)
		(fp_line
			(start -1.222756 2.0955)
			(end -0.758444 2.0955)
			(stroke
				(width 0.0127)
				(type default)
			)
			(layer "F.SilkS")
		)
		(fp_line
			(start -1.232408 2.105152)
			(end -0.749046 2.105152)
			(stroke
				(width 0.0127)
				(type default)
			)
			(layer "F.SilkS")
		)
		(fp_line
			(start -1.241806 2.11455)
			(end -0.739394 2.11455)
			(stroke
				(width 0.0127)
				(type default)
			)
			(layer "F.SilkS")
		)
		(fp_line
			(start -1.251458 2.124202)
			(end -0.729996 2.124202)
			(stroke
				(width 0.0127)
				(type default)
			)
			(layer "F.SilkS")
		)
		(fp_line
			(start -1.260856 2.1336)
			(end -0.720344 2.1336)
			(stroke
				(width 0.0127)
				(type default)
			)
			(layer "F.SilkS")
		)
		(fp_line
			(start -0.719074 2.145538)
			(end -1.265936 2.14122)
			(stroke
				(width 0.0127)
				(type default)
			)
			(layer "F.SilkS")
		)
		(fp_line
			(start -1.279398 2.152142)
			(end -0.9906 1.86309)
			(stroke
				(width 0.0127)
				(type default)
			)
			(layer "F.SilkS")
		)
		(fp_line
			(start -0.71628 2.15265)
			(end -1.26492 2.15265)
			(stroke
				(width 0.0127)
				(type default)
			)
			(layer "F.SilkS")
		)
		(fp_line
			(start -1.279144 2.15265)
			(end -0.701294 2.15265)
			(stroke
				(width 0.0127)
				(type default)
			)
			(layer "F.SilkS")
		)
		(fp_poly
			(pts
				(xy -1.285748 2.159) (xy -1.285748 1.8796) (xy -1.778 1.8796) (xy -1.778 -1.8796) (xy 1.778 -1.8796)
				(xy 1.778 1.8796) (xy -0.694944 1.8796) (xy -0.694944 2.159)
			)
			(stroke
				(width 0)
				(type default)
			)
			(fill no)
			(layer "F.CrtYd")
		)
		(fp_poly
			(pts
				(xy -1.285748 2.159) (xy -1.285748 1.8796) (xy -1.778 1.8796) (xy -1.778 -1.8796) (xy 1.778 -1.8796)
				(xy 1.778 1.8796) (xy -0.694944 1.8796) (xy -0.694944 2.159)
			)
			(stroke
				(width 0)
				(type default)
			)
			(fill no)
			(layer "F.Fab")
		)
		(pad "1" smd rect
			(at -0.98425 0.9525 90)
			(size 0.762 1.143)
			(layers "F.Cu" "F.Mask" "F.Paste")
			(net "LED_DR_LED2_B")
		)
		(pad "2" smd rect
			(at 0.98425 0.9525 90)
			(size 0.762 1.143)
			(layers "F.Cu" "F.Mask" "F.Paste")
			(net "GND")
		)
		(pad "3" smd rect
			(at 0 -0.9525 90)
			(size 0.762 1.143)
			(layers "F.Cu" "F.Mask" "F.Paste")
			(net "LED_DR_LED2_BLUE")
		)
	)
	(footprint ""
		(layer "F.Cu")
		(at 33.069784 -353.6442 -90)
		(property "Reference" "C259"
			(at 0 0 270)
			(layer "F.SilkS")
			(hide yes)
			(effects
				(font
					(size 1.27 1.27)
				)
			)
		)
		(property "Value" "SC10U25V6KX-1GP"
			(at -0.0762 -5.1308 270)
			(unlocked yes)
			(layer "F.Fab")
			(hide yes)
			(effects
				(font
					(size 1.016 1.016)
					(thickness 0.1524)
				)
			)
		)
		(property "Device Type" "C1206H71"
			(at -0.127 -6.6548 270)
			(unlocked yes)
			(layer "F.Fab")
			(hide yes)
			(effects
				(font
					(size 1.016 1.016)
					(thickness 0.1524)
				)
			)
		)
		(duplicate_pad_numbers_are_jumpers no)
		(fp_line
			(start -1.016 2.2352)
			(end -1.016 0.8382)
			(stroke
				(width 0.1524)
				(type default)
			)
			(layer "F.SilkS")
		)
		(fp_line
			(start 1.016 2.2352)
			(end -1.016 2.2352)
			(stroke
				(width 0.1524)
				(type default)
			)
			(layer "F.SilkS")
		)
		(fp_line
			(start 1.016 0.8382)
			(end 1.016 2.2352)
			(stroke
				(width 0.1524)
				(type default)
			)
			(layer "F.SilkS")
		)
		(fp_line
			(start -1.016 -0.8382)
			(end -1.016 -2.2352)
			(stroke
				(width 0.1524)
				(type default)
			)
			(layer "F.SilkS")
		)
		(fp_line
			(start -1.016 -2.2352)
			(end 1.016 -2.2352)
			(stroke
				(width 0.1524)
				(type default)
			)
			(layer "F.SilkS")
		)
		(fp_line
			(start 1.016 -2.2352)
			(end 1.016 -0.8382)
			(stroke
				(width 0.1524)
				(type default)
			)
			(layer "F.SilkS")
		)
		(fp_rect
			(start -1.0922 2.3114)
			(end 1.0922 -2.3114)
			(stroke
				(width 0)
				(type default)
			)
			(fill no)
			(layer "F.CrtYd")
		)
		(fp_poly
			(pts
				(xy 1.0922 -2.3114) (xy 1.0922 2.3114) (xy -1.0922 2.3114) (xy -1.0922 -2.3114)
			)
			(stroke
				(width 0)
				(type default)
			)
			(fill no)
			(layer "F.Fab")
		)
		(pad "1" smd rect
			(at 0 -1.397 270)
			(size 1.651 1.27)
			(layers "F.Cu" "F.Mask" "F.Paste")
			(net "OTP_RETRY_G")
		)
		(pad "2" smd rect
			(at 0 1.397 270)
			(size 1.651 1.27)
			(layers "F.Cu" "F.Mask" "F.Paste")
			(net "GND")
		)
	)
	(footprint ""
		(layer "F.Cu")
		(at 29.852366 -242.327176)
		(property "Reference" "R43"
			(at 0 0 0)
			(layer "F.SilkS")
			(hide yes)
			(effects
				(font
					(size 1.27 1.27)
				)
			)
		)
		(property "Value" "4K7R2J-2-GP"
			(at 0.064008 -3.993896 0)
			(unlocked yes)
			(layer "F.Fab")
			(hide yes)
			(effects
				(font
					(size 1.016 1.016)
					(thickness 0.1524)
				)
			)
		)
		(property "Device Type" "R402H16"
			(at 0.064008 -5.517896 0)
			(unlocked yes)
			(layer "F.Fab")
			(hide yes)
			(effects
				(font
					(size 1.016 1.016)
					(thickness 0.1524)
				)
			)
		)
		(duplicate_pad_numbers_are_jumpers no)
		(fp_line
			(start -0.508 -0.9398)
			(end -0.508 0.9398)
			(stroke
				(width 0.1524)
				(type default)
			)
			(layer "F.SilkS")
		)
		(fp_line
			(start 0.508 -0.9398)
			(end -0.508 -0.9398)
			(stroke
				(width 0.1524)
				(type default)
			)
			(layer "F.SilkS")
		)
		(fp_rect
			(start -0.508 0.9398)
			(end 0.508 -0.9398)
			(stroke
				(width 0)
				(type default)
			)
			(fill no)
			(layer "F.CrtYd")
		)
		(fp_rect
			(start -0.508 0.9398)
			(end 0.508 -0.9398)
			(stroke
				(width 0)
				(type default)
			)
			(fill no)
			(layer "F.Fab")
		)
		(pad "1" smd custom
			(at 0 -0.4445)
			(size 0.1397 0.1397)
			(layers "F.Cu" "F.Mask" "F.Paste")
			(net "FCB_EEPROM_A1")
			(options
				(clearance outline)
				(anchor circle)
			)
			(primitives
				(gr_poly
					(pts
						(arc
							(start -0.1778 -0.2794)
							(mid -0.249642 -0.249642)
							(end -0.2794 -0.1778)
						)
						(arc
							(start -0.2794 0.1778)
							(mid -0.249642 0.249642)
							(end -0.1778 0.2794)
						)
						(arc
							(start 0.1778 0.2794)
							(mid 0.249642 0.249642)
							(end 0.2794 0.1778)
						)
						(arc
							(start 0.2794 -0.1778)
							(mid 0.249642 -0.249642)
							(end 0.1778 -0.2794)
						)
					)
					(width 0)
					(fill yes)
				)
			)
		)
		(pad "2" smd custom
			(at 0 0.4445)
			(size 0.1397 0.1397)
			(layers "F.Cu" "F.Mask" "F.Paste")
			(net "GND")
			(options
				(clearance outline)
				(anchor circle)
			)
			(primitives
				(gr_poly
					(pts
						(arc
							(start -0.1778 -0.2794)
							(mid -0.249642 -0.249642)
							(end -0.2794 -0.1778)
						)
						(arc
							(start -0.2794 0.1778)
							(mid -0.249642 0.249642)
							(end -0.1778 0.2794)
						)
						(arc
							(start 0.1778 0.2794)
							(mid 0.249642 0.249642)
							(end 0.2794 0.1778)
						)
						(arc
							(start 0.2794 -0.1778)
							(mid 0.249642 -0.249642)
							(end 0.1778 -0.2794)
						)
					)
					(width 0)
					(fill yes)
				)
			)
		)
	)
	(footprint ""
		(layer "F.Cu")
		(at 9.906 -147.2184 180)
		(property "Reference" "R66"
			(at 0 0 180)
			(layer "F.SilkS")
			(hide yes)
			(effects
				(font
					(size 1.27 1.27)
				)
			)
		)
		(property "Value" "4K7R2F-GP"
			(at 0.064008 -3.993896 180)
			(unlocked yes)
			(layer "F.Fab")
			(hide yes)
			(effects
				(font
					(size 1.016 1.016)
					(thickness 0.1524)
				)
			)
		)
		(property "Device Type" "R402H16"
			(at 0.064008 -5.517896 180)
			(unlocked yes)
			(layer "F.Fab")
			(hide yes)
			(effects
				(font
					(size 1.016 1.016)
					(thickness 0.1524)
				)
			)
		)
		(duplicate_pad_numbers_are_jumpers no)
		(fp_line
			(start 0.508 -0.9398)
			(end -0.508 -0.9398)
			(stroke
				(width 0.1524)
				(type default)
			)
			(layer "F.SilkS")
		)
		(fp_line
			(start -0.508 -0.9398)
			(end -0.508 0.9398)
			(stroke
				(width 0.1524)
				(type default)
			)
			(layer "F.SilkS")
		)
		(fp_rect
			(start -0.508 0.9398)
			(end 0.508 -0.9398)
			(stroke
				(width 0)
				(type default)
			)
			(fill no)
			(layer "F.CrtYd")
		)
		(fp_rect
			(start -0.508 0.9398)
			(end 0.508 -0.9398)
			(stroke
				(width 0)
				(type default)
			)
			(fill no)
			(layer "F.Fab")
		)
		(pad "1" smd custom
			(at 0 -0.4445 180)
			(size 0.1397 0.1397)
			(layers "F.Cu" "F.Mask" "F.Paste")
			(net "P12V")
			(options
				(clearance outline)
				(anchor circle)
			)
			(primitives
				(gr_poly
					(pts
						(arc
							(start -0.1778 -0.2794)
							(mid -0.249642 -0.249642)
							(end -0.2794 -0.1778)
						)
						(arc
							(start -0.2794 0.1778)
							(mid -0.249642 0.249642)
							(end -0.1778 0.2794)
						)
						(arc
							(start 0.1778 0.2794)
							(mid 0.249642 0.249642)
							(end 0.2794 0.1778)
						)
						(arc
							(start 0.2794 -0.1778)
							(mid 0.249642 -0.249642)
							(end 0.1778 -0.2794)
						)
					)
					(width 0)
					(fill yes)
				)
			)
		)
		(pad "2" smd custom
			(at 0 0.4445 180)
			(size 0.1397 0.1397)
			(layers "F.Cu" "F.Mask" "F.Paste")
			(net "FAN_TACH10")
			(options
				(clearance outline)
				(anchor circle)
			)
			(primitives
				(gr_poly
					(pts
						(arc
							(start -0.1778 -0.2794)
							(mid -0.249642 -0.249642)
							(end -0.2794 -0.1778)
						)
						(arc
							(start -0.2794 0.1778)
							(mid -0.249642 0.249642)
							(end -0.1778 0.2794)
						)
						(arc
							(start 0.1778 0.2794)
							(mid 0.249642 0.249642)
							(end 0.2794 0.1778)
						)
						(arc
							(start 0.2794 -0.1778)
							(mid 0.249642 -0.249642)
							(end 0.1778 -0.2794)
						)
					)
					(width 0)
					(fill yes)
				)
			)
		)
	)
	(footprint ""
		(layer "F.Cu")
		(at 38.5572 -109.4232 -90)
		(property "Reference" "PR103"
			(at 0 0 270)
			(layer "F.SilkS")
			(hide yes)
			(effects
				(font
					(size 1.27 1.27)
				)
			)
		)
		(property "Value" "10R2F-L-GP"
			(at 0.064008 -3.993896 270)
			(unlocked yes)
			(layer "F.Fab")
			(hide yes)
			(effects
				(font
					(size 1.016 1.016)
					(thickness 0.1524)
				)
			)
		)
		(property "Device Type" "R402H14"
			(at 0.064008 -5.517896 270)
			(unlocked yes)
			(layer "F.Fab")
			(hide yes)
			(effects
				(font
					(size 1.016 1.016)
					(thickness 0.1524)
				)
			)
		)
		(duplicate_pad_numbers_are_jumpers no)
		(fp_line
			(start -0.508 -0.9398)
			(end -0.508 0.9398)
			(stroke
				(width 0.1524)
				(type default)
			)
			(layer "F.SilkS")
		)
		(fp_line
			(start 0.508 -0.9398)
			(end -0.508 -0.9398)
			(stroke
				(width 0.1524)
				(type default)
			)
			(layer "F.SilkS")
		)
		(fp_rect
			(start -0.508 0.9398)
			(end 0.508 -0.9398)
			(stroke
				(width 0)
				(type default)
			)
			(fill no)
			(layer "F.CrtYd")
		)
		(fp_rect
			(start -0.508 0.9398)
			(end 0.508 -0.9398)
			(stroke
				(width 0)
				(type default)
			)
			(fill no)
			(layer "F.Fab")
		)
		(pad "1" smd custom
			(at 0 -0.4445 270)
			(size 0.1397 0.1397)
			(layers "F.Cu" "F.Mask" "F.Paste")
			(net "P12VL_2490_GATE_DRV")
			(options
				(clearance outline)
				(anchor circle)
			)
			(primitives
				(gr_poly
					(pts
						(arc
							(start -0.1778 -0.2794)
							(mid -0.249642 -0.249642)
							(end -0.2794 -0.1778)
						)
						(arc
							(start -0.2794 0.1778)
							(mid -0.249642 0.249642)
							(end -0.1778 0.2794)
						)
						(arc
							(start 0.1778 0.2794)
							(mid 0.249642 0.249642)
							(end 0.2794 0.1778)
						)
						(arc
							(start 0.2794 -0.1778)
							(mid 0.249642 -0.249642)
							(end 0.1778 -0.2794)
						)
					)
					(width 0)
					(fill yes)
				)
			)
		)
		(pad "2" smd custom
			(at 0 0.4445 270)
			(size 0.1397 0.1397)
			(layers "F.Cu" "F.Mask" "F.Paste")
			(net "P12VL_2490_GATE")
			(options
				(clearance outline)
				(anchor circle)
			)
			(primitives
				(gr_poly
					(pts
						(arc
							(start -0.1778 -0.2794)
							(mid -0.249642 -0.249642)
							(end -0.2794 -0.1778)
						)
						(arc
							(start -0.2794 0.1778)
							(mid -0.249642 0.249642)
							(end -0.1778 0.2794)
						)
						(arc
							(start 0.1778 0.2794)
							(mid 0.249642 0.249642)
							(end 0.2794 0.1778)
						)
						(arc
							(start 0.2794 -0.1778)
							(mid 0.249642 -0.249642)
							(end 0.1778 -0.2794)
						)
					)
					(width 0)
					(fill yes)
				)
			)
		)
	)
	(footprint ""
		(layer "F.Cu")
		(at 15.494 -167.0304 90)
		(property "Reference" "C33"
			(at 0 0 90)
			(layer "F.SilkS")
			(hide yes)
			(effects
				(font
					(size 1.27 1.27)
				)
			)
		)
		(property "Value" "SCD1U50V3KX-GP"
			(at 0 -2.8194 90)
			(unlocked yes)
			(layer "F.Fab")
			(hide yes)
			(effects
				(font
					(size 1.016 1.016)
					(thickness 0.1524)
				)
			)
		)
		(property "Device Type" "C603H36"
			(at 0 -4.3434 90)
			(unlocked yes)
			(layer "F.Fab")
			(hide yes)
			(effects
				(font
					(size 1.016 1.016)
					(thickness 0.1524)
				)
			)
		)
		(duplicate_pad_numbers_are_jumpers no)
		(fp_line
			(start 0.508 0)
			(end -0.508 0)
			(stroke
				(width 0.2032)
				(type default)
			)
			(layer "F.SilkS")
		)
		(fp_rect
			(start -0.5842 1.3335)
			(end 0.5842 -1.3335)
			(stroke
				(width 0)
				(type default)
			)
			(fill no)
			(layer "F.CrtYd")
		)
		(fp_rect
			(start -0.5842 1.3335)
			(end 0.5842 -1.3335)
			(stroke
				(width 0)
				(type default)
			)
			(fill no)
			(layer "F.Fab")
		)
		(pad "1" smd custom
			(at 0 -0.762 90)
			(size 0.2159 0.2159)
			(layers "F.Cu" "F.Mask" "F.Paste")
			(net "P12V")
			(options
				(clearance outline)
				(anchor circle)
			)
			(primitives
				(gr_poly
					(pts
						(arc
							(start -0.3302 -0.4318)
							(mid -0.402042 -0.402042)
							(end -0.4318 -0.3302)
						)
						(arc
							(start -0.4318 0.3302)
							(mid -0.402042 0.402042)
							(end -0.3302 0.4318)
						)
						(arc
							(start 0.3302 0.4318)
							(mid 0.402042 0.402042)
							(end 0.4318 0.3302)
						)
						(arc
							(start 0.4318 -0.3302)
							(mid 0.402042 -0.402042)
							(end 0.3302 -0.4318)
						)
					)
					(width 0)
					(fill yes)
				)
			)
		)
		(pad "2" smd custom
			(at 0 0.762 90)
			(size 0.2159 0.2159)
			(layers "F.Cu" "F.Mask" "F.Paste")
			(net "GND")
			(options
				(clearance outline)
				(anchor circle)
			)
			(primitives
				(gr_poly
					(pts
						(arc
							(start -0.3302 -0.4318)
							(mid -0.402042 -0.402042)
							(end -0.4318 -0.3302)
						)
						(arc
							(start -0.4318 0.3302)
							(mid -0.402042 0.402042)
							(end -0.3302 0.4318)
						)
						(arc
							(start 0.3302 0.4318)
							(mid 0.402042 0.402042)
							(end 0.4318 0.3302)
						)
						(arc
							(start 0.4318 -0.3302)
							(mid 0.402042 -0.402042)
							(end 0.3302 -0.4318)
						)
					)
					(width 0)
					(fill yes)
				)
			)
		)
	)
	(footprint ""
		(layer "F.Cu")
		(at 28.582366 -242.327176)
		(property "Reference" "R42"
			(at 0 0 0)
			(layer "F.SilkS")
			(hide yes)
			(effects
				(font
					(size 1.27 1.27)
				)
			)
		)
		(property "Value" "4K7R2J-2-GP"
			(at 0.064008 -3.993896 0)
			(unlocked yes)
			(layer "F.Fab")
			(hide yes)
			(effects
				(font
					(size 1.016 1.016)
					(thickness 0.1524)
				)
			)
		)
		(property "Device Type" "R402H16"
			(at 0.064008 -5.517896 0)
			(unlocked yes)
			(layer "F.Fab")
			(hide yes)
			(effects
				(font
					(size 1.016 1.016)
					(thickness 0.1524)
				)
			)
		)
		(duplicate_pad_numbers_are_jumpers no)
		(fp_line
			(start -0.508 -0.9398)
			(end -0.508 0.9398)
			(stroke
				(width 0.1524)
				(type default)
			)
			(layer "F.SilkS")
		)
		(fp_line
			(start 0.508 -0.9398)
			(end -0.508 -0.9398)
			(stroke
				(width 0.1524)
				(type default)
			)
			(layer "F.SilkS")
		)
		(fp_rect
			(start -0.508 0.9398)
			(end 0.508 -0.9398)
			(stroke
				(width 0)
				(type default)
			)
			(fill no)
			(layer "F.CrtYd")
		)
		(fp_rect
			(start -0.508 0.9398)
			(end 0.508 -0.9398)
			(stroke
				(width 0)
				(type default)
			)
			(fill no)
			(layer "F.Fab")
		)
		(pad "1" smd custom
			(at 0 -0.4445)
			(size 0.1397 0.1397)
			(layers "F.Cu" "F.Mask" "F.Paste")
			(net "FCB_EEPROM_A0")
			(options
				(clearance outline)
				(anchor circle)
			)
			(primitives
				(gr_poly
					(pts
						(arc
							(start -0.1778 -0.2794)
							(mid -0.249642 -0.249642)
							(end -0.2794 -0.1778)
						)
						(arc
							(start -0.2794 0.1778)
							(mid -0.249642 0.249642)
							(end -0.1778 0.2794)
						)
						(arc
							(start 0.1778 0.2794)
							(mid 0.249642 0.249642)
							(end 0.2794 0.1778)
						)
						(arc
							(start 0.2794 -0.1778)
							(mid 0.249642 -0.249642)
							(end 0.1778 -0.2794)
						)
					)
					(width 0)
					(fill yes)
				)
			)
		)
		(pad "2" smd custom
			(at 0 0.4445)
			(size 0.1397 0.1397)
			(layers "F.Cu" "F.Mask" "F.Paste")
			(net "GND")
			(options
				(clearance outline)
				(anchor circle)
			)
			(primitives
				(gr_poly
					(pts
						(arc
							(start -0.1778 -0.2794)
							(mid -0.249642 -0.249642)
							(end -0.2794 -0.1778)
						)
						(arc
							(start -0.2794 0.1778)
							(mid -0.249642 0.249642)
							(end -0.1778 0.2794)
						)
						(arc
							(start 0.1778 0.2794)
							(mid 0.249642 0.249642)
							(end 0.2794 0.1778)
						)
						(arc
							(start 0.2794 -0.1778)
							(mid 0.249642 -0.249642)
							(end 0.1778 -0.2794)
						)
					)
					(width 0)
					(fill yes)
				)
			)
		)
	)
	(footprint ""
		(layer "F.Cu")
		(at 14.8844 -42.4942 -90)
		(property "Reference" "R173"
			(at 0 0 270)
			(layer "F.SilkS")
			(hide yes)
			(effects
				(font
					(size 1.27 1.27)
				)
			)
		)
		(property "Value" "0R2J-2-GP"
			(at 0.064008 -3.993896 270)
			(unlocked yes)
			(layer "F.Fab")
			(hide yes)
			(effects
				(font
					(size 1.016 1.016)
					(thickness 0.1524)
				)
			)
		)
		(property "Device Type" "R402H16"
			(at 0.064008 -5.517896 270)
			(unlocked yes)
			(layer "F.Fab")
			(hide yes)
			(effects
				(font
					(size 1.016 1.016)
					(thickness 0.1524)
				)
			)
		)
		(duplicate_pad_numbers_are_jumpers no)
		(fp_line
			(start -0.508 -0.9398)
			(end -0.508 0.9398)
			(stroke
				(width 0.1524)
				(type default)
			)
			(layer "F.SilkS")
		)
		(fp_line
			(start 0.508 -0.9398)
			(end -0.508 -0.9398)
			(stroke
				(width 0.1524)
				(type default)
			)
			(layer "F.SilkS")
		)
		(fp_rect
			(start -0.508 0.9398)
			(end 0.508 -0.9398)
			(stroke
				(width 0)
				(type default)
			)
			(fill no)
			(layer "F.CrtYd")
		)
		(fp_rect
			(start -0.508 0.9398)
			(end 0.508 -0.9398)
			(stroke
				(width 0)
				(type default)
			)
			(fill no)
			(layer "F.Fab")
		)
		(pad "1" smd custom
			(at 0 -0.4445 270)
			(size 0.1397 0.1397)
			(layers "F.Cu" "F.Mask" "F.Paste")
			(net "SELF_2B_HB")
			(options
				(clearance outline)
				(anchor circle)
			)
			(primitives
				(gr_poly
					(pts
						(arc
							(start -0.1778 -0.2794)
							(mid -0.249642 -0.249642)
							(end -0.2794 -0.1778)
						)
						(arc
							(start -0.2794 0.1778)
							(mid -0.249642 0.249642)
							(end -0.1778 0.2794)
						)
						(arc
							(start 0.1778 0.2794)
							(mid 0.249642 0.249642)
							(end 0.2794 0.1778)
						)
						(arc
							(start 0.2794 -0.1778)
							(mid 0.249642 -0.249642)
							(end 0.1778 -0.2794)
						)
					)
					(width 0)
					(fill yes)
				)
			)
		)
		(pad "2" smd custom
			(at 0 0.4445 270)
			(size 0.1397 0.1397)
			(layers "F.Cu" "F.Mask" "F.Paste")
			(net "SEB_PEER_1B_HB")
			(options
				(clearance outline)
				(anchor circle)
			)
			(primitives
				(gr_poly
					(pts
						(arc
							(start -0.1778 -0.2794)
							(mid -0.249642 -0.249642)
							(end -0.2794 -0.1778)
						)
						(arc
							(start -0.2794 0.1778)
							(mid -0.249642 0.249642)
							(end -0.1778 0.2794)
						)
						(arc
							(start 0.1778 0.2794)
							(mid 0.249642 0.249642)
							(end 0.2794 0.1778)
						)
						(arc
							(start 0.2794 -0.1778)
							(mid 0.249642 -0.249642)
							(end 0.1778 -0.2794)
						)
					)
					(width 0)
					(fill yes)
				)
			)
		)
	)
	(footprint ""
		(layer "F.Cu")
		(at 27.0764 -168.1988 -90)
		(property "Reference" "R164"
			(at 0 0 270)
			(layer "F.SilkS")
			(hide yes)
			(effects
				(font
					(size 1.27 1.27)
				)
			)
		)
		(property "Value" "0R2J-2-GP"
			(at 0.064008 -3.993896 270)
			(unlocked yes)
			(layer "F.Fab")
			(hide yes)
			(effects
				(font
					(size 1.016 1.016)
					(thickness 0.1524)
				)
			)
		)
		(property "Device Type" "R402H16"
			(at 0.064008 -5.517896 270)
			(unlocked yes)
			(layer "F.Fab")
			(hide yes)
			(effects
				(font
					(size 1.016 1.016)
					(thickness 0.1524)
				)
			)
		)
		(duplicate_pad_numbers_are_jumpers no)
		(fp_line
			(start -0.508 -0.9398)
			(end -0.508 0.9398)
			(stroke
				(width 0.1524)
				(type default)
			)
			(layer "F.SilkS")
		)
		(fp_line
			(start 0.508 -0.9398)
			(end -0.508 -0.9398)
			(stroke
				(width 0.1524)
				(type default)
			)
			(layer "F.SilkS")
		)
		(fp_rect
			(start -0.508 0.9398)
			(end 0.508 -0.9398)
			(stroke
				(width 0)
				(type default)
			)
			(fill no)
			(layer "F.CrtYd")
		)
		(fp_rect
			(start -0.508 0.9398)
			(end 0.508 -0.9398)
			(stroke
				(width 0)
				(type default)
			)
			(fill no)
			(layer "F.Fab")
		)
		(pad "1" smd custom
			(at 0 -0.4445 270)
			(size 0.1397 0.1397)
			(layers "F.Cu" "F.Mask" "F.Paste")
			(net "PWM_BUFFER_IN_FAN3_FAN4")
			(options
				(clearance outline)
				(anchor circle)
			)
			(primitives
				(gr_poly
					(pts
						(arc
							(start -0.1778 -0.2794)
							(mid -0.249642 -0.249642)
							(end -0.2794 -0.1778)
						)
						(arc
							(start -0.2794 0.1778)
							(mid -0.249642 0.249642)
							(end -0.1778 0.2794)
						)
						(arc
							(start 0.1778 0.2794)
							(mid 0.249642 0.249642)
							(end 0.2794 0.1778)
						)
						(arc
							(start 0.2794 -0.1778)
							(mid 0.249642 -0.249642)
							(end 0.1778 -0.2794)
						)
					)
					(width 0)
					(fill yes)
				)
			)
		)
		(pad "2" smd custom
			(at 0 0.4445 270)
			(size 0.1397 0.1397)
			(layers "F.Cu" "F.Mask" "F.Paste")
			(net "PWM_BUFFER_IN_FAN5_FAN6")
			(options
				(clearance outline)
				(anchor circle)
			)
			(primitives
				(gr_poly
					(pts
						(arc
							(start -0.1778 -0.2794)
							(mid -0.249642 -0.249642)
							(end -0.2794 -0.1778)
						)
						(arc
							(start -0.2794 0.1778)
							(mid -0.249642 0.249642)
							(end -0.1778 0.2794)
						)
						(arc
							(start 0.1778 0.2794)
							(mid 0.249642 0.249642)
							(end 0.2794 0.1778)
						)
						(arc
							(start 0.2794 -0.1778)
							(mid 0.249642 -0.249642)
							(end 0.1778 -0.2794)
						)
					)
					(width 0)
					(fill yes)
				)
			)
		)
	)
	(footprint ""
		(layer "F.Cu")
		(at 37.338 -144.272 -90)
		(property "Reference" "PR111"
			(at 0 0 270)
			(layer "F.SilkS")
			(hide yes)
			(effects
				(font
					(size 1.27 1.27)
				)
			)
		)
		(property "Value" "178KR2F-GP"
			(at 0.064008 -3.993896 270)
			(unlocked yes)
			(layer "F.Fab")
			(hide yes)
			(effects
				(font
					(size 1.016 1.016)
					(thickness 0.1524)
				)
			)
		)
		(property "Device Type" "R402H16"
			(at 0.064008 -5.517896 270)
			(unlocked yes)
			(layer "F.Fab")
			(hide yes)
			(effects
				(font
					(size 1.016 1.016)
					(thickness 0.1524)
				)
			)
		)
		(duplicate_pad_numbers_are_jumpers no)
		(fp_line
			(start -0.508 -0.9398)
			(end -0.508 0.9398)
			(stroke
				(width 0.1524)
				(type default)
			)
			(layer "F.SilkS")
		)
		(fp_line
			(start 0.508 -0.9398)
			(end -0.508 -0.9398)
			(stroke
				(width 0.1524)
				(type default)
			)
			(layer "F.SilkS")
		)
		(fp_rect
			(start -0.508 0.9398)
			(end 0.508 -0.9398)
			(stroke
				(width 0)
				(type default)
			)
			(fill no)
			(layer "F.CrtYd")
		)
		(fp_rect
			(start -0.508 0.9398)
			(end 0.508 -0.9398)
			(stroke
				(width 0)
				(type default)
			)
			(fill no)
			(layer "F.Fab")
		)
		(pad "1" smd custom
			(at 0 -0.4445 270)
			(size 0.1397 0.1397)
			(layers "F.Cu" "F.Mask" "F.Paste")
			(net "P12VL_2490_VREF")
			(options
				(clearance outline)
				(anchor circle)
			)
			(primitives
				(gr_poly
					(pts
						(arc
							(start -0.1778 -0.2794)
							(mid -0.249642 -0.249642)
							(end -0.2794 -0.1778)
						)
						(arc
							(start -0.2794 0.1778)
							(mid -0.249642 0.249642)
							(end -0.1778 0.2794)
						)
						(arc
							(start 0.1778 0.2794)
							(mid 0.249642 0.249642)
							(end 0.2794 0.1778)
						)
						(arc
							(start 0.2794 -0.1778)
							(mid 0.249642 -0.249642)
							(end 0.1778 -0.2794)
						)
					)
					(width 0)
					(fill yes)
				)
			)
		)
		(pad "2" smd custom
			(at 0 0.4445 270)
			(size 0.1397 0.1397)
			(layers "F.Cu" "F.Mask" "F.Paste")
			(net "P12VL_2490_PROG")
			(options
				(clearance outline)
				(anchor circle)
			)
			(primitives
				(gr_poly
					(pts
						(arc
							(start -0.1778 -0.2794)
							(mid -0.249642 -0.249642)
							(end -0.2794 -0.1778)
						)
						(arc
							(start -0.2794 0.1778)
							(mid -0.249642 0.249642)
							(end -0.1778 0.2794)
						)
						(arc
							(start 0.1778 0.2794)
							(mid 0.249642 0.249642)
							(end 0.2794 0.1778)
						)
						(arc
							(start 0.2794 -0.1778)
							(mid 0.249642 -0.249642)
							(end 0.1778 -0.2794)
						)
					)
					(width 0)
					(fill yes)
				)
			)
		)
	)
	(footprint ""
		(layer "F.Cu")
		(at 26.416 -410.591)
		(property "Reference" "PR30"
			(at 0 0 0)
			(layer "F.SilkS")
			(hide yes)
			(effects
				(font
					(size 1.27 1.27)
				)
			)
		)
		(property "Value" "D0005RL1632F-GP-U"
			(at 3.2258 1.2954 0)
			(unlocked yes)
			(layer "F.Fab")
			(hide yes)
			(effects
				(font
					(size 1.016 1.016)
					(thickness 0.1524)
				)
			)
		)
		(property "Device Type" "RL3115-4PH45"
			(at 3.2258 -0.2286 0)
			(unlocked yes)
			(layer "F.Fab")
			(hide yes)
			(effects
				(font
					(size 1.016 1.016)
					(thickness 0.1524)
				)
			)
		)
		(duplicate_pad_numbers_are_jumpers no)
		(fp_line
			(start -2.0574 -1.7653)
			(end -2.0574 -0.4064)
			(stroke
				(width 0.3302)
				(type default)
			)
			(layer "F.SilkS")
		)
		(fp_line
			(start -1.9685 -1.651)
			(end 1.9685 -1.651)
			(stroke
				(width 0.1524)
				(type default)
			)
			(layer "F.SilkS")
		)
		(fp_line
			(start -1.9685 1.651)
			(end -1.9685 -1.651)
			(stroke
				(width 0.1524)
				(type default)
			)
			(layer "F.SilkS")
		)
		(fp_line
			(start -0.5334 -1.7653)
			(end -2.0574 -1.7653)
			(stroke
				(width 0.3302)
				(type default)
			)
			(layer "F.SilkS")
		)
		(fp_line
			(start 1.9685 -1.651)
			(end 1.9685 1.651)
			(stroke
				(width 0.1524)
				(type default)
			)
			(layer "F.SilkS")
		)
		(fp_line
			(start 1.9685 1.651)
			(end -1.9685 1.651)
			(stroke
				(width 0.1524)
				(type default)
			)
			(layer "F.SilkS")
		)
		(fp_poly
			(pts
				(xy -0.561594 -1.726946) (xy -0.053594 -2.234946) (xy -1.069594 -2.234946)
			)
			(stroke
				(width 0)
				(type default)
			)
			(fill yes)
			(layer "F.SilkS")
		)
		(fp_rect
			(start -1.524 0.7493)
			(end 1.524 -0.7493)
			(stroke
				(width 0)
				(type default)
			)
			(fill no)
			(layer "F.CrtYd")
		)
		(fp_poly
			(pts
				(xy -2.2225 1.905) (xy -2.2225 -1.905) (xy 2.2225 -1.905) (xy 2.2225 -0.7493) (xy -1.524 -0.7493)
				(xy -1.524 0.7493) (xy 1.524 0.7493) (xy 1.524 -0.7366) (xy 2.2225 -0.7366) (xy 2.2225 1.905)
			)
			(stroke
				(width 0)
				(type default)
			)
			(fill no)
			(layer "F.CrtYd")
		)
		(fp_rect
			(start -2.2225 1.905)
			(end 2.2225 -1.905)
			(stroke
				(width 0)
				(type default)
			)
			(fill no)
			(layer "F.Fab")
		)
		(pad "1" smd rect
			(at -0.5715 -0.813562)
			(size 2.286 1.143)
			(layers "F.Cu" "F.Mask" "F.Paste")
			(net "P12V_AUX")
		)
		(pad "2" smd rect
			(at -0.5715 0.813562)
			(size 2.286 1.143)
			(layers "F.Cu" "F.Mask" "F.Paste")
			(net "P12V_SENSE_TRACE")
		)
		(pad "3" smd rect
			(at 1.334008 -0.813562)
			(size 0.762 1.143)
			(layers "F.Cu" "F.Mask" "F.Paste")
			(net "SENSE+_R2")
		)
		(pad "4" smd rect
			(at 1.334008 0.813562)
			(size 0.762 1.143)
			(layers "F.Cu" "F.Mask" "F.Paste")
			(net "SENSE-_R2")
		)
		(zone
			(layer "F.Cu")
			(hatch none 0.5)
			(connect_pads
				(clearance 0)
			)
			(min_thickness 0.25)
			(keepout
				(tracks not_allowed)
				(vias allowed)
				(pads allowed)
				(copperpour not_allowed)
				(footprints allowed)
			)
			(placement
				(enabled no)
				(sheetname "")
			)
			(fill
				(thermal_gap 0.5)
				(thermal_bridge_width 0.5)
				(island_removal_mode 0)
			)
			(polygon
				(pts
					(xy 26.9875 -410.833062) (xy 27.369008 -410.833062) (xy 27.369008 -411.3403) (xy 26.9875 -411.3403)
				)
			)
		)
		(zone
			(layer "F.Cu")
			(hatch none 0.5)
			(connect_pads
				(clearance 0)
			)
			(min_thickness 0.25)
			(keepout
				(tracks allowed)
				(vias not_allowed)
				(pads allowed)
				(copperpour not_allowed)
				(footprints allowed)
			)
			(placement
				(enabled no)
				(sheetname "")
			)
			(fill
				(thermal_gap 0.5)
				(thermal_bridge_width 0.5)
				(island_removal_mode 0)
			)
			(polygon
				(pts
					(xy 26.9875 -410.833062) (xy 27.369008 -410.833062) (xy 27.369008 -411.3403) (xy 26.9875 -411.3403)
				)
			)
		)
		(zone
			(layer "F.Cu")
			(hatch none 0.5)
			(connect_pads
				(clearance 0)
			)
			(min_thickness 0.25)
			(keepout
				(tracks allowed)
				(vias not_allowed)
				(pads allowed)
				(copperpour not_allowed)
				(footprints allowed)
			)
			(placement
				(enabled no)
				(sheetname "")
			)
			(fill
				(thermal_gap 0.5)
				(thermal_bridge_width 0.5)
				(island_removal_mode 0)
			)
			(polygon
				(pts
					(xy 26.9875 -409.8417) (xy 27.369008 -409.8417) (xy 27.369008 -410.348938) (xy 26.9875 -410.348938)
				)
			)
		)
		(zone
			(layer "F.Cu")
			(hatch none 0.5)
			(connect_pads
				(clearance 0)
			)
			(min_thickness 0.25)
			(keepout
				(tracks not_allowed)
				(vias allowed)
				(pads allowed)
				(copperpour not_allowed)
				(footprints allowed)
			)
			(placement
				(enabled no)
				(sheetname "")
			)
			(fill
				(thermal_gap 0.5)
				(thermal_bridge_width 0.5)
				(island_removal_mode 0)
			)
			(polygon
				(pts
					(xy 26.9875 -409.8417) (xy 27.369008 -409.8417) (xy 27.369008 -410.348938) (xy 26.9875 -410.348938)
				)
			)
		)
	)
	(footprint ""
		(layer "F.Cu")
		(at 5.1562 -417.6522 90)
		(property "Reference" "R27"
			(at 0 0 90)
			(layer "F.SilkS")
			(hide yes)
			(effects
				(font
					(size 1.27 1.27)
				)
			)
		)
		(property "Value" "33R2F-3-GP"
			(at 0.064008 -3.993896 90)
			(unlocked yes)
			(layer "F.Fab")
			(hide yes)
			(effects
				(font
					(size 1.016 1.016)
					(thickness 0.1524)
				)
			)
		)
		(property "Device Type" "R402H16"
			(at 0.064008 -5.517896 90)
			(unlocked yes)
			(layer "F.Fab")
			(hide yes)
			(effects
				(font
					(size 1.016 1.016)
					(thickness 0.1524)
				)
			)
		)
		(duplicate_pad_numbers_are_jumpers no)
		(fp_line
			(start 0.508 -0.9398)
			(end -0.508 -0.9398)
			(stroke
				(width 0.1524)
				(type default)
			)
			(layer "F.SilkS")
		)
		(fp_line
			(start -0.508 -0.9398)
			(end -0.508 0.9398)
			(stroke
				(width 0.1524)
				(type default)
			)
			(layer "F.SilkS")
		)
		(fp_rect
			(start -0.508 0.9398)
			(end 0.508 -0.9398)
			(stroke
				(width 0)
				(type default)
			)
			(fill no)
			(layer "F.CrtYd")
		)
		(fp_rect
			(start -0.508 0.9398)
			(end 0.508 -0.9398)
			(stroke
				(width 0)
				(type default)
			)
			(fill no)
			(layer "F.Fab")
		)
		(pad "1" smd custom
			(at 0 -0.4445 90)
			(size 0.1397 0.1397)
			(layers "F.Cu" "F.Mask" "F.Paste")
			(net "P3V3")
			(options
				(clearance outline)
				(anchor circle)
			)
			(primitives
				(gr_poly
					(pts
						(arc
							(start -0.1778 -0.2794)
							(mid -0.249642 -0.249642)
							(end -0.2794 -0.1778)
						)
						(arc
							(start -0.2794 0.1778)
							(mid -0.249642 0.249642)
							(end -0.1778 0.2794)
						)
						(arc
							(start 0.1778 0.2794)
							(mid 0.249642 0.249642)
							(end 0.2794 0.1778)
						)
						(arc
							(start 0.2794 -0.1778)
							(mid 0.249642 -0.249642)
							(end 0.1778 -0.2794)
						)
					)
					(width 0)
					(fill yes)
				)
			)
		)
		(pad "2" smd custom
			(at 0 0.4445 90)
			(size 0.1397 0.1397)
			(layers "F.Cu" "F.Mask" "F.Paste")
			(net "LED_DR_LED1_BLUE")
			(options
				(clearance outline)
				(anchor circle)
			)
			(primitives
				(gr_poly
					(pts
						(arc
							(start -0.1778 -0.2794)
							(mid -0.249642 -0.249642)
							(end -0.2794 -0.1778)
						)
						(arc
							(start -0.2794 0.1778)
							(mid -0.249642 0.249642)
							(end -0.1778 0.2794)
						)
						(arc
							(start 0.1778 0.2794)
							(mid 0.249642 0.249642)
							(end 0.2794 0.1778)
						)
						(arc
							(start 0.2794 -0.1778)
							(mid 0.249642 -0.249642)
							(end 0.1778 -0.2794)
						)
					)
					(width 0)
					(fill yes)
				)
			)
		)
	)
	(footprint ""
		(layer "F.Cu")
		(at 40.999918 -450.44995 90)
		(property "Reference" "PAD2"
			(at 0 0 90)
			(layer "F.SilkS")
			(hide yes)
			(effects
				(font
					(size 1.27 1.27)
				)
			)
		)
		(property "Value" "PAD-1P-424137-1-OG-GP"
			(at -22.9743 -0.4572 90)
			(unlocked yes)
			(layer "F.Fab")
			(hide yes)
			(effects
				(font
					(size 1.016 1.016)
					(thickness 0.1524)
				)
			)
		)
		(property "Device Type" "PAD-1P-424137-1-OG"
			(at -22.9743 -1.9812 90)
			(unlocked yes)
			(layer "F.Fab")
			(hide yes)
			(effects
				(font
					(size 1.016 1.016)
					(thickness 0.1524)
				)
			)
		)
		(duplicate_pad_numbers_are_jumpers no)
		(fp_line
			(start 21.4503 -7.0993)
			(end 21.4503 7.0993)
			(stroke
				(width 0.1524)
				(type default)
			)
			(layer "F.SilkS")
		)
		(fp_line
			(start 2.816098 -7.0993)
			(end 21.4503 -7.0993)
			(stroke
				(width 0.1524)
				(type default)
			)
			(layer "F.SilkS")
		)
		(fp_line
			(start -0.075946 -7.0993)
			(end -0.075946 -5.750052)
			(stroke
				(width 0.1524)
				(type default)
			)
			(layer "F.SilkS")
		)
		(fp_line
			(start -21.4503 -7.0993)
			(end -0.075946 -7.0993)
			(stroke
				(width 0.1524)
				(type default)
			)
			(layer "F.SilkS")
		)
		(fp_line
			(start 2.816098 -5.750052)
			(end 2.816098 -7.0993)
			(stroke
				(width 0.1524)
				(type default)
			)
			(layer "F.SilkS")
		)
		(fp_line
			(start 21.4503 7.0993)
			(end -21.4503 7.0993)
			(stroke
				(width 0.1524)
				(type default)
			)
			(layer "F.SilkS")
		)
		(fp_line
			(start -21.4503 7.0993)
			(end -21.4503 -7.0993)
			(stroke
				(width 0.1524)
				(type default)
			)
			(layer "F.SilkS")
		)
		(fp_arc
			(start 2.816098 -5.750052)
			(mid 1.37008 -4.30403)
			(end -0.075946 -5.750052)
			(stroke
				(width 0.1524)
				(type default)
			)
			(layer "F.SilkS")
		)
		(fp_poly
			(pts
				(xy -21.7043 7.3533) (xy -21.7043 -7.3533) (xy 0.178054 -7.3533)
				(arc
					(start 0.178054 -5.750052)
					(mid 1.370076 -4.55803)
					(end 2.562098 -5.750052)
				)
				(xy 2.562098 -7.3533) (xy 21.7043 -7.3533) (xy 21.7043 7.3533)
			)
			(stroke
				(width 0)
				(type default)
			)
			(fill no)
			(layer "F.CrtYd")
		)
		(fp_poly
			(pts
				(xy -21.7043 7.3533) (xy -21.7043 -7.3533) (xy 0.178054 -7.3533)
				(arc
					(start 0.178054 -5.750052)
					(mid 1.370076 -4.55803)
					(end 2.562098 -5.750052)
				)
				(xy 2.562098 -7.3533) (xy 21.7043 -7.3533) (xy 21.7043 7.3533)
			)
			(stroke
				(width 0)
				(type default)
			)
			(fill no)
			(layer "F.Fab")
		)
		(pad "1" smd custom
			(at 0 0 90)
			(size 3.425063 3.425063)
			(layers "F.Cu" "F.Mask" "F.Paste")
			(net "GND")
			(options
				(clearance outline)
				(anchor circle)
			)
			(primitives
				(gr_poly
					(pts
						(xy -0.329946 -6.850126) (xy -21.20011 -6.850126) (xy -21.20011 6.850126) (xy 21.20011 6.850126)
						(xy 21.20011 -6.850126) (xy 3.070098 -6.850126)
						(arc
							(start 3.070098 -5.750052)
							(mid 1.370076 -4.05003)
							(end -0.329946 -5.750052)
						)
					)
					(width 0)
					(fill yes)
				)
			)
		)
	)
	(footprint ""
		(layer "F.Cu")
		(at 15.3924 -49.0982 180)
		(property "Reference" "R184"
			(at 0 0 180)
			(layer "F.SilkS")
			(hide yes)
			(effects
				(font
					(size 1.27 1.27)
				)
			)
		)
		(property "Value" "0R2J-2-GP"
			(at 0.064008 -3.993896 180)
			(unlocked yes)
			(layer "F.Fab")
			(hide yes)
			(effects
				(font
					(size 1.016 1.016)
					(thickness 0.1524)
				)
			)
		)
		(property "Device Type" "R402H16"
			(at 0.064008 -5.517896 180)
			(unlocked yes)
			(layer "F.Fab")
			(hide yes)
			(effects
				(font
					(size 1.016 1.016)
					(thickness 0.1524)
				)
			)
		)
		(duplicate_pad_numbers_are_jumpers no)
		(fp_line
			(start 0.508 -0.9398)
			(end -0.508 -0.9398)
			(stroke
				(width 0.1524)
				(type default)
			)
			(layer "F.SilkS")
		)
		(fp_line
			(start -0.508 -0.9398)
			(end -0.508 0.9398)
			(stroke
				(width 0.1524)
				(type default)
			)
			(layer "F.SilkS")
		)
		(fp_rect
			(start -0.508 0.9398)
			(end 0.508 -0.9398)
			(stroke
				(width 0)
				(type default)
			)
			(fill no)
			(layer "F.CrtYd")
		)
		(fp_rect
			(start -0.508 0.9398)
			(end 0.508 -0.9398)
			(stroke
				(width 0)
				(type default)
			)
			(fill no)
			(layer "F.Fab")
		)
		(pad "1" smd custom
			(at 0 -0.4445 180)
			(size 0.1397 0.1397)
			(layers "F.Cu" "F.Mask" "F.Paste")
			(net "SD_LATCH_RELEASE_L")
			(options
				(clearance outline)
				(anchor circle)
			)
			(primitives
				(gr_poly
					(pts
						(arc
							(start -0.1778 -0.2794)
							(mid -0.249642 -0.249642)
							(end -0.2794 -0.1778)
						)
						(arc
							(start -0.2794 0.1778)
							(mid -0.249642 0.249642)
							(end -0.1778 0.2794)
						)
						(arc
							(start 0.1778 0.2794)
							(mid 0.249642 0.249642)
							(end 0.2794 0.1778)
						)
						(arc
							(start 0.2794 -0.1778)
							(mid 0.249642 -0.249642)
							(end 0.1778 -0.2794)
						)
					)
					(width 0)
					(fill yes)
				)
			)
		)
		(pad "2" smd custom
			(at 0 0.4445 180)
			(size 0.1397 0.1397)
			(layers "F.Cu" "F.Mask" "F.Paste")
			(net "TEMP_ALM#_REVERSE_R")
			(options
				(clearance outline)
				(anchor circle)
			)
			(primitives
				(gr_poly
					(pts
						(arc
							(start -0.1778 -0.2794)
							(mid -0.249642 -0.249642)
							(end -0.2794 -0.1778)
						)
						(arc
							(start -0.2794 0.1778)
							(mid -0.249642 0.249642)
							(end -0.1778 0.2794)
						)
						(arc
							(start 0.1778 0.2794)
							(mid 0.249642 0.249642)
							(end 0.2794 0.1778)
						)
						(arc
							(start 0.2794 -0.1778)
							(mid 0.249642 -0.249642)
							(end 0.1778 -0.2794)
						)
					)
					(width 0)
					(fill yes)
				)
			)
		)
	)
	(footprint ""
		(layer "F.Cu")
		(at 28.702 -195.3514 90)
		(property "Reference" "C42"
			(at 0 0 90)
			(layer "F.SilkS")
			(hide yes)
			(effects
				(font
					(size 1.27 1.27)
				)
			)
		)
		(property "Value" "SC1U25V3KX-1-GP"
			(at 0 -2.8194 90)
			(unlocked yes)
			(layer "F.Fab")
			(hide yes)
			(effects
				(font
					(size 1.016 1.016)
					(thickness 0.1524)
				)
			)
		)
		(property "Device Type" "C603H36"
			(at 0 -4.3434 90)
			(unlocked yes)
			(layer "F.Fab")
			(hide yes)
			(effects
				(font
					(size 1.016 1.016)
					(thickness 0.1524)
				)
			)
		)
		(duplicate_pad_numbers_are_jumpers no)
		(fp_line
			(start 0.508 0)
			(end -0.508 0)
			(stroke
				(width 0.2032)
				(type default)
			)
			(layer "F.SilkS")
		)
		(fp_rect
			(start -0.5842 1.3335)
			(end 0.5842 -1.3335)
			(stroke
				(width 0)
				(type default)
			)
			(fill no)
			(layer "F.CrtYd")
		)
		(fp_rect
			(start -0.5842 1.3335)
			(end 0.5842 -1.3335)
			(stroke
				(width 0)
				(type default)
			)
			(fill no)
			(layer "F.Fab")
		)
		(pad "1" smd custom
			(at 0 -0.762 90)
			(size 0.2159 0.2159)
			(layers "F.Cu" "F.Mask" "F.Paste")
			(net "P12V")
			(options
				(clearance outline)
				(anchor circle)
			)
			(primitives
				(gr_poly
					(pts
						(arc
							(start -0.3302 -0.4318)
							(mid -0.402042 -0.402042)
							(end -0.4318 -0.3302)
						)
						(arc
							(start -0.4318 0.3302)
							(mid -0.402042 0.402042)
							(end -0.3302 0.4318)
						)
						(arc
							(start 0.3302 0.4318)
							(mid 0.402042 0.402042)
							(end 0.4318 0.3302)
						)
						(arc
							(start 0.4318 -0.3302)
							(mid 0.402042 -0.402042)
							(end 0.3302 -0.4318)
						)
					)
					(width 0)
					(fill yes)
				)
			)
		)
		(pad "2" smd custom
			(at 0 0.762 90)
			(size 0.2159 0.2159)
			(layers "F.Cu" "F.Mask" "F.Paste")
			(net "GND")
			(options
				(clearance outline)
				(anchor circle)
			)
			(primitives
				(gr_poly
					(pts
						(arc
							(start -0.3302 -0.4318)
							(mid -0.402042 -0.402042)
							(end -0.4318 -0.3302)
						)
						(arc
							(start -0.4318 0.3302)
							(mid -0.402042 0.402042)
							(end -0.3302 0.4318)
						)
						(arc
							(start 0.3302 0.4318)
							(mid 0.402042 0.402042)
							(end 0.4318 0.3302)
						)
						(arc
							(start 0.4318 -0.3302)
							(mid 0.402042 -0.402042)
							(end 0.3302 -0.4318)
						)
					)
					(width 0)
					(fill yes)
				)
			)
		)
	)
	(footprint ""
		(layer "F.Cu")
		(at 48.895 -111.633 90)
		(property "Reference" "PR119"
			(at 0 0 90)
			(layer "F.SilkS")
			(hide yes)
			(effects
				(font
					(size 1.27 1.27)
				)
			)
		)
		(property "Value" "10R2F-L-GP"
			(at 0.064008 -3.993896 90)
			(unlocked yes)
			(layer "F.Fab")
			(hide yes)
			(effects
				(font
					(size 1.016 1.016)
					(thickness 0.1524)
				)
			)
		)
		(property "Device Type" "R402H14"
			(at 0.064008 -5.517896 90)
			(unlocked yes)
			(layer "F.Fab")
			(hide yes)
			(effects
				(font
					(size 1.016 1.016)
					(thickness 0.1524)
				)
			)
		)
		(duplicate_pad_numbers_are_jumpers no)
		(fp_line
			(start 0.508 -0.9398)
			(end -0.508 -0.9398)
			(stroke
				(width 0.1524)
				(type default)
			)
			(layer "F.SilkS")
		)
		(fp_line
			(start -0.508 -0.9398)
			(end -0.508 0.9398)
			(stroke
				(width 0.1524)
				(type default)
			)
			(layer "F.SilkS")
		)
		(fp_rect
			(start -0.508 0.9398)
			(end 0.508 -0.9398)
			(stroke
				(width 0)
				(type default)
			)
			(fill no)
			(layer "F.CrtYd")
		)
		(fp_rect
			(start -0.508 0.9398)
			(end 0.508 -0.9398)
			(stroke
				(width 0)
				(type default)
			)
			(fill no)
			(layer "F.Fab")
		)
		(pad "1" smd custom
			(at 0 -0.4445 90)
			(size 0.1397 0.1397)
			(layers "F.Cu" "F.Mask" "F.Paste")
			(net "P12VL_2490_GATE_DRV_2")
			(options
				(clearance outline)
				(anchor circle)
			)
			(primitives
				(gr_poly
					(pts
						(arc
							(start -0.1778 -0.2794)
							(mid -0.249642 -0.249642)
							(end -0.2794 -0.1778)
						)
						(arc
							(start -0.2794 0.1778)
							(mid -0.249642 0.249642)
							(end -0.1778 0.2794)
						)
						(arc
							(start 0.1778 0.2794)
							(mid 0.249642 0.249642)
							(end 0.2794 0.1778)
						)
						(arc
							(start 0.2794 -0.1778)
							(mid 0.249642 -0.249642)
							(end 0.1778 -0.2794)
						)
					)
					(width 0)
					(fill yes)
				)
			)
		)
		(pad "2" smd custom
			(at 0 0.4445 90)
			(size 0.1397 0.1397)
			(layers "F.Cu" "F.Mask" "F.Paste")
			(net "P12VL_2490_GATE")
			(options
				(clearance outline)
				(anchor circle)
			)
			(primitives
				(gr_poly
					(pts
						(arc
							(start -0.1778 -0.2794)
							(mid -0.249642 -0.249642)
							(end -0.2794 -0.1778)
						)
						(arc
							(start -0.2794 0.1778)
							(mid -0.249642 0.249642)
							(end -0.1778 0.2794)
						)
						(arc
							(start 0.1778 0.2794)
							(mid 0.249642 0.249642)
							(end 0.2794 0.1778)
						)
						(arc
							(start 0.2794 -0.1778)
							(mid 0.249642 -0.249642)
							(end 0.1778 -0.2794)
						)
					)
					(width 0)
					(fill yes)
				)
			)
		)
	)
	(footprint ""
		(layer "F.Cu")
		(at 25.5016 -140.5382 90)
		(property "Reference" "PC85"
			(at 0 0 90)
			(layer "F.SilkS")
			(hide yes)
			(effects
				(font
					(size 1.27 1.27)
				)
			)
		)
		(property "Value" "SCD01U25V2KX-3GP"
			(at 1.1811 -2.7051 90)
			(unlocked yes)
			(layer "F.Fab")
			(hide yes)
			(effects
				(font
					(size 1.016 1.016)
					(thickness 0.1524)
				)
			)
		)
		(property "Device Type" "C402H22"
			(at 1.1811 -4.2291 90)
			(unlocked yes)
			(layer "F.Fab")
			(hide yes)
			(effects
				(font
					(size 1.016 1.016)
					(thickness 0.1524)
				)
			)
		)
		(duplicate_pad_numbers_are_jumpers no)
		(fp_rect
			(start -0.4318 0.9525)
			(end 0.4318 -0.9525)
			(stroke
				(width 0)
				(type default)
			)
			(fill no)
			(layer "F.CrtYd")
		)
		(fp_rect
			(start -0.4318 0.9525)
			(end 0.4318 -0.9525)
			(stroke
				(width 0)
				(type default)
			)
			(fill no)
			(layer "F.Fab")
		)
		(pad "1" smd custom
			(at 0 -0.4445 90)
			(size 0.1524 0.1524)
			(layers "F.Cu" "F.Mask" "F.Paste")
			(net "P12VU_2490_RC")
			(options
				(clearance outline)
				(anchor circle)
			)
			(primitives
				(gr_poly
					(pts
						(arc
							(start 0.3048 -0.2032)
							(mid 0.275042 -0.275042)
							(end 0.2032 -0.3048)
						)
						(arc
							(start -0.2032 -0.3048)
							(mid -0.275042 -0.275042)
							(end -0.3048 -0.2032)
						)
						(arc
							(start -0.3048 0.2032)
							(mid -0.275042 0.275042)
							(end -0.2032 0.3048)
						)
						(arc
							(start 0.2032 0.3048)
							(mid 0.275042 0.275042)
							(end 0.3048 0.2032)
						)
					)
					(width 0)
					(fill yes)
				)
			)
		)
		(pad "2" smd custom
			(at 0 0.4445 90)
			(size 0.1524 0.1524)
			(layers "F.Cu" "F.Mask" "F.Paste")
			(net "GND")
			(options
				(clearance outline)
				(anchor circle)
			)
			(primitives
				(gr_poly
					(pts
						(arc
							(start 0.3048 -0.2032)
							(mid 0.275042 -0.275042)
							(end 0.2032 -0.3048)
						)
						(arc
							(start -0.2032 -0.3048)
							(mid -0.275042 -0.275042)
							(end -0.3048 -0.2032)
						)
						(arc
							(start -0.3048 0.2032)
							(mid -0.275042 0.275042)
							(end -0.2032 0.3048)
						)
						(arc
							(start 0.2032 0.3048)
							(mid 0.275042 0.275042)
							(end 0.3048 0.2032)
						)
					)
					(width 0)
					(fill yes)
				)
			)
		)
	)
	(footprint ""
		(layer "F.Cu")
		(at 32.9946 -251.3838 180)
		(property "Reference" "C19"
			(at 0 0 180)
			(layer "F.SilkS")
			(hide yes)
			(effects
				(font
					(size 1.27 1.27)
				)
			)
		)
		(property "Value" "SC1U16V3KX-5GP"
			(at 0 -2.8194 180)
			(unlocked yes)
			(layer "F.Fab")
			(hide yes)
			(effects
				(font
					(size 1.016 1.016)
					(thickness 0.1524)
				)
			)
		)
		(property "Device Type" "C603H36"
			(at 0 -4.3434 180)
			(unlocked yes)
			(layer "F.Fab")
			(hide yes)
			(effects
				(font
					(size 1.016 1.016)
					(thickness 0.1524)
				)
			)
		)
		(duplicate_pad_numbers_are_jumpers no)
		(fp_line
			(start 0.508 0)
			(end -0.508 0)
			(stroke
				(width 0.2032)
				(type default)
			)
			(layer "F.SilkS")
		)
		(fp_rect
			(start -0.5842 1.3335)
			(end 0.5842 -1.3335)
			(stroke
				(width 0)
				(type default)
			)
			(fill no)
			(layer "F.CrtYd")
		)
		(fp_rect
			(start -0.5842 1.3335)
			(end 0.5842 -1.3335)
			(stroke
				(width 0)
				(type default)
			)
			(fill no)
			(layer "F.Fab")
		)
		(pad "1" smd custom
			(at 0 -0.762 180)
			(size 0.2159 0.2159)
			(layers "F.Cu" "F.Mask" "F.Paste")
			(net "P3V3")
			(options
				(clearance outline)
				(anchor circle)
			)
			(primitives
				(gr_poly
					(pts
						(arc
							(start -0.3302 -0.4318)
							(mid -0.402042 -0.402042)
							(end -0.4318 -0.3302)
						)
						(arc
							(start -0.4318 0.3302)
							(mid -0.402042 0.402042)
							(end -0.3302 0.4318)
						)
						(arc
							(start 0.3302 0.4318)
							(mid 0.402042 0.402042)
							(end 0.4318 0.3302)
						)
						(arc
							(start 0.4318 -0.3302)
							(mid 0.402042 -0.402042)
							(end 0.3302 -0.4318)
						)
					)
					(width 0)
					(fill yes)
				)
			)
		)
		(pad "2" smd custom
			(at 0 0.762 180)
			(size 0.2159 0.2159)
			(layers "F.Cu" "F.Mask" "F.Paste")
			(net "GND")
			(options
				(clearance outline)
				(anchor circle)
			)
			(primitives
				(gr_poly
					(pts
						(arc
							(start -0.3302 -0.4318)
							(mid -0.402042 -0.402042)
							(end -0.4318 -0.3302)
						)
						(arc
							(start -0.4318 0.3302)
							(mid -0.402042 0.402042)
							(end -0.3302 0.4318)
						)
						(arc
							(start 0.3302 0.4318)
							(mid 0.402042 0.402042)
							(end 0.4318 0.3302)
						)
						(arc
							(start 0.4318 -0.3302)
							(mid 0.402042 -0.402042)
							(end 0.3302 -0.4318)
						)
					)
					(width 0)
					(fill yes)
				)
			)
		)
	)
	(footprint ""
		(layer "F.Cu")
		(at 19.9136 -149.6822)
		(property "Reference" "R76"
			(at 0 0 0)
			(layer "F.SilkS")
			(hide yes)
			(effects
				(font
					(size 1.27 1.27)
				)
			)
		)
		(property "Value" "10KR2F-2-GP"
			(at 0.064008 -3.993896 0)
			(unlocked yes)
			(layer "F.Fab")
			(hide yes)
			(effects
				(font
					(size 1.016 1.016)
					(thickness 0.1524)
				)
			)
		)
		(property "Device Type" "R402H16"
			(at 0.064008 -5.517896 0)
			(unlocked yes)
			(layer "F.Fab")
			(hide yes)
			(effects
				(font
					(size 1.016 1.016)
					(thickness 0.1524)
				)
			)
		)
		(duplicate_pad_numbers_are_jumpers no)
		(fp_line
			(start -0.508 -0.9398)
			(end -0.508 0.9398)
			(stroke
				(width 0.1524)
				(type default)
			)
			(layer "F.SilkS")
		)
		(fp_line
			(start 0.508 -0.9398)
			(end -0.508 -0.9398)
			(stroke
				(width 0.1524)
				(type default)
			)
			(layer "F.SilkS")
		)
		(fp_rect
			(start -0.508 0.9398)
			(end 0.508 -0.9398)
			(stroke
				(width 0)
				(type default)
			)
			(fill no)
			(layer "F.CrtYd")
		)
		(fp_rect
			(start -0.508 0.9398)
			(end 0.508 -0.9398)
			(stroke
				(width 0)
				(type default)
			)
			(fill no)
			(layer "F.Fab")
		)
		(pad "1" smd custom
			(at 0 -0.4445)
			(size 0.1397 0.1397)
			(layers "F.Cu" "F.Mask" "F.Paste")
			(net "FANIN_9")
			(options
				(clearance outline)
				(anchor circle)
			)
			(primitives
				(gr_poly
					(pts
						(arc
							(start -0.1778 -0.2794)
							(mid -0.249642 -0.249642)
							(end -0.2794 -0.1778)
						)
						(arc
							(start -0.2794 0.1778)
							(mid -0.249642 0.249642)
							(end -0.1778 0.2794)
						)
						(arc
							(start 0.1778 0.2794)
							(mid 0.249642 0.249642)
							(end 0.2794 0.1778)
						)
						(arc
							(start 0.2794 -0.1778)
							(mid 0.249642 -0.249642)
							(end 0.1778 -0.2794)
						)
					)
					(width 0)
					(fill yes)
				)
			)
		)
		(pad "2" smd custom
			(at 0 0.4445)
			(size 0.1397 0.1397)
			(layers "F.Cu" "F.Mask" "F.Paste")
			(net "GND")
			(options
				(clearance outline)
				(anchor circle)
			)
			(primitives
				(gr_poly
					(pts
						(arc
							(start -0.1778 -0.2794)
							(mid -0.249642 -0.249642)
							(end -0.2794 -0.1778)
						)
						(arc
							(start -0.2794 0.1778)
							(mid -0.249642 0.249642)
							(end -0.1778 0.2794)
						)
						(arc
							(start 0.1778 0.2794)
							(mid 0.249642 0.249642)
							(end 0.2794 0.1778)
						)
						(arc
							(start 0.2794 -0.1778)
							(mid 0.249642 -0.249642)
							(end 0.1778 -0.2794)
						)
					)
					(width 0)
					(fill yes)
				)
			)
		)
	)
	(footprint ""
		(layer "F.Cu")
		(at 31.012638 -289.229292 -90)
		(property "Reference" "F5"
			(at 0 0 270)
			(layer "F.SilkS")
			(hide yes)
			(effects
				(font
					(size 1.27 1.27)
				)
			)
		)
		(property "Value" "FUSE-3A15V-GP"
			(at 0.2286 -10.5918 270)
			(unlocked yes)
			(layer "F.Fab")
			(hide yes)
			(effects
				(font
					(size 1.016 1.016)
					(thickness 0.1524)
				)
			)
		)
		(property "Device Type" "FUSE-7452-UH50"
			(at 0.2286 -12.4968 270)
			(unlocked yes)
			(layer "F.Fab")
			(hide yes)
			(effects
				(font
					(size 1.016 1.016)
					(thickness 0.1524)
				)
			)
		)
		(duplicate_pad_numbers_are_jumpers no)
		(fp_line
			(start -4.9276 2.921)
			(end -4.9276 -2.921)
			(stroke
				(width 0.1524)
				(type default)
			)
			(layer "F.SilkS")
		)
		(fp_line
			(start 4.9276 2.921)
			(end -4.9276 2.921)
			(stroke
				(width 0.1524)
				(type default)
			)
			(layer "F.SilkS")
		)
		(fp_line
			(start -4.9276 -2.921)
			(end 4.9276 -2.921)
			(stroke
				(width 0.1524)
				(type default)
			)
			(layer "F.SilkS")
		)
		(fp_line
			(start 4.9276 -2.921)
			(end 4.9276 2.921)
			(stroke
				(width 0.1524)
				(type default)
			)
			(layer "F.SilkS")
		)
		(fp_poly
			(pts
				(xy -5.08 3.0988) (xy 5.08 3.0988) (xy 5.08 -3.0988) (xy -5.08 -3.0988)
			)
			(stroke
				(width 0)
				(type default)
			)
			(fill no)
			(layer "F.CrtYd")
		)
		(fp_poly
			(pts
				(xy -5.08 -3.0988) (xy 5.08 -3.0988) (xy 5.08 3.0988) (xy -5.08 3.0988)
			)
			(stroke
				(width 0)
				(type default)
			)
			(fill no)
			(layer "F.Fab")
		)
		(pad "1" smd rect
			(at -3.4036 0 270)
			(size 2.2098 5.2832)
			(layers "F.Cu" "F.Mask" "F.Paste")
			(net "P12V_FAN2")
		)
		(pad "2" smd rect
			(at 3.4036 0 270)
			(size 2.2098 5.2832)
			(layers "F.Cu" "F.Mask" "F.Paste")
			(net "P12V")
		)
	)
	(footprint ""
		(layer "F.Cu")
		(at 40.005 -371.475 -90)
		(property "Reference" "C255"
			(at 0 0 270)
			(layer "F.SilkS")
			(hide yes)
			(effects
				(font
					(size 1.27 1.27)
				)
			)
		)
		(property "Value" "SCD1U25V3KX-LL-GP"
			(at 0 -2.8194 270)
			(unlocked yes)
			(layer "F.Fab")
			(hide yes)
			(effects
				(font
					(size 1.016 1.016)
					(thickness 0.1524)
				)
			)
		)
		(property "Device Type" "C603H36"
			(at 0 -4.3434 270)
			(unlocked yes)
			(layer "F.Fab")
			(hide yes)
			(effects
				(font
					(size 1.016 1.016)
					(thickness 0.1524)
				)
			)
		)
		(duplicate_pad_numbers_are_jumpers no)
		(fp_line
			(start 0.508 0)
			(end -0.508 0)
			(stroke
				(width 0.2032)
				(type default)
			)
			(layer "F.SilkS")
		)
		(fp_rect
			(start -0.5842 1.3335)
			(end 0.5842 -1.3335)
			(stroke
				(width 0)
				(type default)
			)
			(fill no)
			(layer "F.CrtYd")
		)
		(fp_rect
			(start -0.5842 1.3335)
			(end 0.5842 -1.3335)
			(stroke
				(width 0)
				(type default)
			)
			(fill no)
			(layer "F.Fab")
		)
		(pad "1" smd custom
			(at 0 -0.762 270)
			(size 0.2159 0.2159)
			(layers "F.Cu" "F.Mask" "F.Paste")
			(net "ADM1276_LATCH_B")
			(options
				(clearance outline)
				(anchor circle)
			)
			(primitives
				(gr_poly
					(pts
						(arc
							(start -0.3302 -0.4318)
							(mid -0.402042 -0.402042)
							(end -0.4318 -0.3302)
						)
						(arc
							(start -0.4318 0.3302)
							(mid -0.402042 0.402042)
							(end -0.3302 0.4318)
						)
						(arc
							(start 0.3302 0.4318)
							(mid 0.402042 0.402042)
							(end 0.4318 0.3302)
						)
						(arc
							(start 0.4318 -0.3302)
							(mid 0.402042 -0.402042)
							(end 0.3302 -0.4318)
						)
					)
					(width 0)
					(fill yes)
				)
			)
		)
		(pad "2" smd custom
			(at 0 0.762 270)
			(size 0.2159 0.2159)
			(layers "F.Cu" "F.Mask" "F.Paste")
			(net "GND")
			(options
				(clearance outline)
				(anchor circle)
			)
			(primitives
				(gr_poly
					(pts
						(arc
							(start -0.3302 -0.4318)
							(mid -0.402042 -0.402042)
							(end -0.4318 -0.3302)
						)
						(arc
							(start -0.4318 0.3302)
							(mid -0.402042 0.402042)
							(end -0.3302 0.4318)
						)
						(arc
							(start 0.3302 0.4318)
							(mid 0.402042 0.402042)
							(end 0.4318 0.3302)
						)
						(arc
							(start 0.4318 -0.3302)
							(mid 0.402042 -0.402042)
							(end 0.3302 -0.4318)
						)
					)
					(width 0)
					(fill yes)
				)
			)
		)
	)
	(footprint ""
		(layer "F.Cu")
		(at 17.9832 -248.5644 180)
		(property "Reference" "PR52"
			(at 0 0 180)
			(layer "F.SilkS")
			(hide yes)
			(effects
				(font
					(size 1.27 1.27)
				)
			)
		)
		(property "Value" "47KR3F-GP"
			(at -0.0254 -2.5146 180)
			(unlocked yes)
			(layer "F.Fab")
			(hide yes)
			(effects
				(font
					(size 1.016 1.016)
					(thickness 0.1524)
				)
			)
		)
		(property "Device Type" "R603H22"
			(at -0.0254 -4.0386 180)
			(unlocked yes)
			(layer "F.Fab")
			(hide yes)
			(effects
				(font
					(size 1.016 1.016)
					(thickness 0.1524)
				)
			)
		)
		(duplicate_pad_numbers_are_jumpers no)
		(fp_line
			(start 0.2032 0)
			(end 0.4826 0)
			(stroke
				(width 0.2032)
				(type default)
			)
			(layer "F.SilkS")
		)
		(fp_line
			(start -0.4826 0)
			(end -0.2032 0)
			(stroke
				(width 0.2032)
				(type default)
			)
			(layer "F.SilkS")
		)
		(fp_rect
			(start -0.5842 1.3335)
			(end 0.5842 -1.3335)
			(stroke
				(width 0)
				(type default)
			)
			(fill no)
			(layer "F.CrtYd")
		)
		(fp_rect
			(start -0.5842 1.3335)
			(end 0.5842 -1.3335)
			(stroke
				(width 0)
				(type default)
			)
			(fill no)
			(layer "F.Fab")
		)
		(pad "1" smd custom
			(at 0 -0.762 180)
			(size 0.2159 0.2159)
			(layers "F.Cu" "F.Mask" "F.Paste")
			(net "P3V3_IN")
			(options
				(clearance outline)
				(anchor circle)
			)
			(primitives
				(gr_poly
					(pts
						(arc
							(start -0.3302 -0.4318)
							(mid -0.402042 -0.402042)
							(end -0.4318 -0.3302)
						)
						(arc
							(start -0.4318 0.3302)
							(mid -0.402042 0.402042)
							(end -0.3302 0.4318)
						)
						(arc
							(start 0.3302 0.4318)
							(mid 0.402042 0.402042)
							(end 0.4318 0.3302)
						)
						(arc
							(start 0.4318 -0.3302)
							(mid 0.402042 -0.402042)
							(end 0.3302 -0.4318)
						)
					)
					(width 0)
					(fill yes)
				)
			)
		)
		(pad "2" smd custom
			(at 0 0.762 180)
			(size 0.2159 0.2159)
			(layers "F.Cu" "F.Mask" "F.Paste")
			(net "P3V3_EN")
			(options
				(clearance outline)
				(anchor circle)
			)
			(primitives
				(gr_poly
					(pts
						(arc
							(start -0.3302 -0.4318)
							(mid -0.402042 -0.402042)
							(end -0.4318 -0.3302)
						)
						(arc
							(start -0.4318 0.3302)
							(mid -0.402042 0.402042)
							(end -0.3302 0.4318)
						)
						(arc
							(start 0.3302 0.4318)
							(mid 0.402042 0.402042)
							(end 0.4318 0.3302)
						)
						(arc
							(start 0.4318 -0.3302)
							(mid 0.402042 -0.402042)
							(end 0.3302 -0.4318)
						)
					)
					(width 0)
					(fill yes)
				)
			)
		)
	)
	(footprint ""
		(layer "F.Cu")
		(at 44.831 -111.633)
		(property "Reference" "PQ12"
			(at 0 0 0)
			(layer "F.SilkS")
			(hide yes)
			(effects
				(font
					(size 1.27 1.27)
				)
			)
		)
		(property "Value" "PH0925CL-GP"
			(at -4.2799 -0.4572 0)
			(unlocked yes)
			(layer "F.Fab")
			(hide yes)
			(effects
				(font
					(size 1.016 1.016)
					(thickness 0.1524)
				)
			)
		)
		(property "Device Type" "LFPAK-5PH48-U"
			(at -4.2799 -1.9812 0)
			(unlocked yes)
			(layer "F.Fab")
			(hide yes)
			(effects
				(font
					(size 1.016 1.016)
					(thickness 0.1524)
				)
			)
		)
		(duplicate_pad_numbers_are_jumpers no)
		(fp_line
			(start -2.7559 -6.5532)
			(end -2.7559 1.0668)
			(stroke
				(width 0.1524)
				(type default)
			)
			(layer "F.SilkS")
		)
		(fp_line
			(start -2.7559 1.0668)
			(end 2.7559 1.0668)
			(stroke
				(width 0.1524)
				(type default)
			)
			(layer "F.SilkS")
		)
		(fp_line
			(start -1.7272 1.1684)
			(end -2.1082 1.1684)
			(stroke
				(width 0.3302)
				(type default)
			)
			(layer "F.SilkS")
		)
		(fp_line
			(start 2.7559 -6.5532)
			(end -2.7559 -6.5532)
			(stroke
				(width 0.1524)
				(type default)
			)
			(layer "F.SilkS")
		)
		(fp_line
			(start 2.7559 1.0668)
			(end 2.7559 -6.5532)
			(stroke
				(width 0.1524)
				(type default)
			)
			(layer "F.SilkS")
		)
		(fp_poly
			(pts
				(xy -2.3368 1.5748) (xy -1.905 1.143) (xy -1.4732 1.5748)
			)
			(stroke
				(width 0)
				(type default)
			)
			(fill yes)
			(layer "F.SilkS")
		)
		(fp_poly
			(pts
				(xy -2.5019 -4.02971) (xy -0.3302 -4.02971) (xy -0.3302 -6.30301) (xy -2.5019 -6.30301)
			)
			(stroke
				(width 0)
				(type default)
			)
			(fill yes)
			(layer "F.Paste")
		)
		(fp_poly
			(pts
				(xy -2.5019 -1.09601) (xy -0.3302 -1.09601) (xy -0.3302 -3.36931) (xy -2.5019 -3.36931)
			)
			(stroke
				(width 0)
				(type default)
			)
			(fill yes)
			(layer "F.Paste")
		)
		(fp_poly
			(pts
				(xy 0.3302 -4.02971) (xy 2.5019 -4.02971) (xy 2.5019 -6.30301) (xy 0.3302 -6.30301)
			)
			(stroke
				(width 0)
				(type default)
			)
			(fill yes)
			(layer "F.Paste")
		)
		(fp_poly
			(pts
				(xy 0.3302 -1.09601) (xy 2.5019 -1.09601) (xy 2.5019 -3.36931) (xy 0.3302 -3.36931)
			)
			(stroke
				(width 0)
				(type default)
			)
			(fill yes)
			(layer "F.Paste")
		)
		(fp_rect
			(start -2.4511 0.3048)
			(end 2.4511 -5.6896)
			(stroke
				(width 0)
				(type default)
			)
			(fill no)
			(layer "F.CrtYd")
		)
		(fp_poly
			(pts
				(xy -3.0099 1.3208) (xy -3.0099 -6.8072) (xy 3.0099 -6.8072) (xy 3.0099 -1.016) (xy 2.4511 -1.016)
				(xy 2.4511 -5.6896) (xy -2.4511 -5.6896) (xy -2.4511 0.3048) (xy 2.4511 0.3048) (xy 2.4511 -1.0033)
				(xy 3.0099 -1.0033) (xy 3.0099 1.3208)
			)
			(stroke
				(width 0)
				(type default)
			)
			(fill no)
			(layer "F.CrtYd")
		)
		(fp_rect
			(start -3.0099 1.3208)
			(end 3.0099 -6.8072)
			(stroke
				(width 0)
				(type default)
			)
			(fill no)
			(layer "F.Fab")
		)
		(pad "1" smd rect
			(at -1.905 0)
			(size 0.762 1.6256)
			(layers "F.Cu" "F.Mask" "F.Paste")
			(net "P12VL")
		)
		(pad "2" smd rect
			(at -0.635 0)
			(size 0.762 1.6256)
			(layers "F.Cu" "F.Mask" "F.Paste")
			(net "P12VL")
		)
		(pad "3" smd rect
			(at 0.635 0)
			(size 0.762 1.6256)
			(layers "F.Cu" "F.Mask" "F.Paste")
			(net "P12VL")
		)
		(pad "4" smd rect
			(at 1.905 0)
			(size 0.762 1.6256)
			(layers "F.Cu" "F.Mask" "F.Paste")
			(net "P12VL_2490_GATE_DRV_2")
		)
		(pad "5" smd rect
			(at 0 -3.69951)
			(size 5.0038 5.207)
			(layers "F.Cu" "F.Mask" "F.Paste")
			(net "P12VL_NET")
		)
	)
	(footprint ""
		(layer "F.Cu")
		(at 36.740338 -477.189292 90)
		(property "Reference" "C50"
			(at 0 0 90)
			(layer "F.SilkS")
			(hide yes)
			(effects
				(font
					(size 1.27 1.27)
				)
			)
		)
		(property "Value" "SC1U25V3KX-1-GP"
			(at 0 -2.8194 90)
			(unlocked yes)
			(layer "F.Fab")
			(hide yes)
			(effects
				(font
					(size 1.016 1.016)
					(thickness 0.1524)
				)
			)
		)
		(property "Device Type" "C603H36"
			(at 0 -4.3434 90)
			(unlocked yes)
			(layer "F.Fab")
			(hide yes)
			(effects
				(font
					(size 1.016 1.016)
					(thickness 0.1524)
				)
			)
		)
		(duplicate_pad_numbers_are_jumpers no)
		(fp_line
			(start 0.508 0)
			(end -0.508 0)
			(stroke
				(width 0.2032)
				(type default)
			)
			(layer "F.SilkS")
		)
		(fp_rect
			(start -0.5842 1.3335)
			(end 0.5842 -1.3335)
			(stroke
				(width 0)
				(type default)
			)
			(fill no)
			(layer "F.CrtYd")
		)
		(fp_rect
			(start -0.5842 1.3335)
			(end 0.5842 -1.3335)
			(stroke
				(width 0)
				(type default)
			)
			(fill no)
			(layer "F.Fab")
		)
		(pad "1" smd custom
			(at 0 -0.762 90)
			(size 0.2159 0.2159)
			(layers "F.Cu" "F.Mask" "F.Paste")
			(net "P12V")
			(options
				(clearance outline)
				(anchor circle)
			)
			(primitives
				(gr_poly
					(pts
						(arc
							(start -0.3302 -0.4318)
							(mid -0.402042 -0.402042)
							(end -0.4318 -0.3302)
						)
						(arc
							(start -0.4318 0.3302)
							(mid -0.402042 0.402042)
							(end -0.3302 0.4318)
						)
						(arc
							(start 0.3302 0.4318)
							(mid 0.402042 0.402042)
							(end 0.4318 0.3302)
						)
						(arc
							(start 0.4318 -0.3302)
							(mid 0.402042 -0.402042)
							(end 0.3302 -0.4318)
						)
					)
					(width 0)
					(fill yes)
				)
			)
		)
		(pad "2" smd custom
			(at 0 0.762 90)
			(size 0.2159 0.2159)
			(layers "F.Cu" "F.Mask" "F.Paste")
			(net "GND")
			(options
				(clearance outline)
				(anchor circle)
			)
			(primitives
				(gr_poly
					(pts
						(arc
							(start -0.3302 -0.4318)
							(mid -0.402042 -0.402042)
							(end -0.4318 -0.3302)
						)
						(arc
							(start -0.4318 0.3302)
							(mid -0.402042 0.402042)
							(end -0.3302 0.4318)
						)
						(arc
							(start 0.3302 0.4318)
							(mid 0.402042 0.402042)
							(end 0.4318 0.3302)
						)
						(arc
							(start 0.4318 -0.3302)
							(mid 0.402042 -0.402042)
							(end 0.3302 -0.4318)
						)
					)
					(width 0)
					(fill yes)
				)
			)
		)
	)
	(footprint ""
		(layer "F.Cu")
		(at 28.2448 -210.8454 180)
		(property "Reference" "R137"
			(at 0 0 180)
			(layer "F.SilkS")
			(hide yes)
			(effects
				(font
					(size 1.27 1.27)
				)
			)
		)
		(property "Value" "0R2J-2-GP"
			(at 0.064008 -3.993896 180)
			(unlocked yes)
			(layer "F.Fab")
			(hide yes)
			(effects
				(font
					(size 1.016 1.016)
					(thickness 0.1524)
				)
			)
		)
		(property "Device Type" "R402H16"
			(at 0.064008 -5.517896 180)
			(unlocked yes)
			(layer "F.Fab")
			(hide yes)
			(effects
				(font
					(size 1.016 1.016)
					(thickness 0.1524)
				)
			)
		)
		(duplicate_pad_numbers_are_jumpers no)
		(fp_line
			(start 0.508 -0.9398)
			(end -0.508 -0.9398)
			(stroke
				(width 0.1524)
				(type default)
			)
			(layer "F.SilkS")
		)
		(fp_line
			(start -0.508 -0.9398)
			(end -0.508 0.9398)
			(stroke
				(width 0.1524)
				(type default)
			)
			(layer "F.SilkS")
		)
		(fp_rect
			(start -0.508 0.9398)
			(end 0.508 -0.9398)
			(stroke
				(width 0)
				(type default)
			)
			(fill no)
			(layer "F.CrtYd")
		)
		(fp_rect
			(start -0.508 0.9398)
			(end 0.508 -0.9398)
			(stroke
				(width 0)
				(type default)
			)
			(fill no)
			(layer "F.Fab")
		)
		(pad "1" smd custom
			(at 0 -0.4445 180)
			(size 0.1397 0.1397)
			(layers "F.Cu" "F.Mask" "F.Paste")
			(net "PWM_OUT_FAN5_NET")
			(options
				(clearance outline)
				(anchor circle)
			)
			(primitives
				(gr_poly
					(pts
						(arc
							(start -0.1778 -0.2794)
							(mid -0.249642 -0.249642)
							(end -0.2794 -0.1778)
						)
						(arc
							(start -0.2794 0.1778)
							(mid -0.249642 0.249642)
							(end -0.1778 0.2794)
						)
						(arc
							(start 0.1778 0.2794)
							(mid 0.249642 0.249642)
							(end 0.2794 0.1778)
						)
						(arc
							(start 0.2794 -0.1778)
							(mid 0.249642 -0.249642)
							(end 0.1778 -0.2794)
						)
					)
					(width 0)
					(fill yes)
				)
			)
		)
		(pad "2" smd custom
			(at 0 0.4445 180)
			(size 0.1397 0.1397)
			(layers "F.Cu" "F.Mask" "F.Paste")
			(net "PWM_OUT_FAN5")
			(options
				(clearance outline)
				(anchor circle)
			)
			(primitives
				(gr_poly
					(pts
						(arc
							(start -0.1778 -0.2794)
							(mid -0.249642 -0.249642)
							(end -0.2794 -0.1778)
						)
						(arc
							(start -0.2794 0.1778)
							(mid -0.249642 0.249642)
							(end -0.1778 0.2794)
						)
						(arc
							(start 0.1778 0.2794)
							(mid 0.249642 0.249642)
							(end 0.2794 0.1778)
						)
						(arc
							(start 0.2794 -0.1778)
							(mid 0.249642 -0.249642)
							(end 0.1778 -0.2794)
						)
					)
					(width 0)
					(fill yes)
				)
			)
		)
	)
	(footprint ""
		(layer "F.Cu")
		(at 42.05859 -162.643566 180)
		(property "Reference" "OSC1"
			(at 0 0 180)
			(layer "F.SilkS")
			(hide yes)
			(effects
				(font
					(size 1.27 1.27)
				)
			)
		)
		(property "Value" "OSC-33MHZ-7-GP"
			(at 0 -10.1092 180)
			(unlocked yes)
			(layer "F.Fab")
			(hide yes)
			(effects
				(font
					(size 1.016 1.016)
					(thickness 0.1524)
				)
			)
		)
		(property "Device Type" "SMD-OSC8H52"
			(at 0 -11.6332 180)
			(unlocked yes)
			(layer "F.Fab")
			(hide yes)
			(effects
				(font
					(size 1.016 1.016)
					(thickness 0.1524)
				)
			)
		)
		(duplicate_pad_numbers_are_jumpers no)
		(fp_line
			(start 2.7559 2.4638)
			(end -2.7559 2.4638)
			(stroke
				(width 0.1524)
				(type default)
			)
			(layer "F.SilkS")
		)
		(fp_line
			(start 2.7559 -2.4638)
			(end 2.7559 2.4638)
			(stroke
				(width 0.1524)
				(type default)
			)
			(layer "F.SilkS")
		)
		(fp_line
			(start -1.242822 2.55143)
			(end -2.852166 2.55143)
			(stroke
				(width 0.3302)
				(type default)
			)
			(layer "F.SilkS")
		)
		(fp_line
			(start -2.7559 2.4638)
			(end -2.7559 -2.4638)
			(stroke
				(width 0.1524)
				(type default)
			)
			(layer "F.SilkS")
		)
		(fp_line
			(start -2.7559 -2.4638)
			(end 2.7559 -2.4638)
			(stroke
				(width 0.1524)
				(type default)
			)
			(layer "F.SilkS")
		)
		(fp_line
			(start -2.852166 2.55143)
			(end -2.852166 1.131316)
			(stroke
				(width 0.3302)
				(type default)
			)
			(layer "F.SilkS")
		)
		(fp_poly
			(pts
				(xy -1.778 3.0734) (xy -1.2446 2.54) (xy -0.762 3.0734)
			)
			(stroke
				(width 0)
				(type default)
			)
			(fill yes)
			(layer "F.SilkS")
		)
		(fp_poly
			(pts
				(xy -3.0099 2.7178) (xy -3.0099 -2.7178) (xy 3.0099 -2.7178) (xy 3.0099 2.7178)
			)
			(stroke
				(width 0)
				(type default)
			)
			(fill no)
			(layer "F.CrtYd")
		)
		(fp_poly
			(pts
				(xy -3.0099 -2.7178) (xy 3.0099 -2.7178) (xy 3.0099 2.7178) (xy -3.0099 2.7178)
			)
			(stroke
				(width 0)
				(type default)
			)
			(fill no)
			(layer "F.Fab")
		)
		(pad "1" smd rect
			(at -1.46939 1.39954 180)
			(size 1.8034 1.6002)
			(layers "F.Cu" "F.Mask" "F.Paste")
			(net "OSC_TRI_S")
		)
		(pad "2" smd rect
			(at 1.46939 1.39954 180)
			(size 1.8034 1.6002)
			(layers "F.Cu" "F.Mask" "F.Paste")
			(net "GND")
		)
		(pad "3" smd rect
			(at 1.46939 -1.39954 180)
			(size 1.8034 1.6002)
			(layers "F.Cu" "F.Mask" "F.Paste")
			(net "NCT7904_CLK")
		)
		(pad "4" smd rect
			(at -1.46939 -1.39954 180)
			(size 1.8034 1.6002)
			(layers "F.Cu" "F.Mask" "F.Paste")
			(net "P3V3")
		)
		(zone
			(layer "F.Cu")
			(hatch none 0.5)
			(connect_pads
				(clearance 0)
			)
			(min_thickness 0.25)
			(keepout
				(tracks not_allowed)
				(vias allowed)
				(pads allowed)
				(copperpour not_allowed)
				(footprints allowed)
			)
			(placement
				(enabled no)
				(sheetname "")
			)
			(fill
				(thermal_gap 0.5)
				(thermal_bridge_width 0.5)
				(island_removal_mode 0)
			)
			(polygon
				(pts
					(xy 42.302938 -162.367468) (xy 42.302938 -162.919664) (xy 41.814242 -162.919664) (xy 41.814242 -162.367468)
				)
			)
		)
		(zone
			(layer "F.Cu")
			(hatch none 0.5)
			(connect_pads
				(clearance 0)
			)
			(min_thickness 0.25)
			(keepout
				(tracks allowed)
				(vias not_allowed)
				(pads allowed)
				(copperpour not_allowed)
				(footprints allowed)
			)
			(placement
				(enabled no)
				(sheetname "")
			)
			(fill
				(thermal_gap 0.5)
				(thermal_bridge_width 0.5)
				(island_removal_mode 0)
			)
			(polygon
				(pts
					(xy 42.62628 -164.843206) (xy 42.62628 -163.243006) (xy 44.42968 -163.243006) (xy 44.42968 -162.044126)
					(xy 42.62628 -162.044126) (xy 42.62628 -160.443926) (xy 41.4909 -160.443926) (xy 41.4909 -162.044126)
					(xy 39.6875 -162.044126) (xy 39.6875 -163.243006) (xy 41.4909 -163.243006) (xy 41.4909 -164.843206)
				)
			)
		)
	)
	(footprint ""
		(layer "F.Cu")
		(at 37.70249 -165.513766 180)
		(property "Reference" "R2"
			(at 0 0 180)
			(layer "F.SilkS")
			(hide yes)
			(effects
				(font
					(size 1.27 1.27)
				)
			)
		)
		(property "Value" "0R2J-2-GP"
			(at 0.064008 -3.993896 180)
			(unlocked yes)
			(layer "F.Fab")
			(hide yes)
			(effects
				(font
					(size 1.016 1.016)
					(thickness 0.1524)
				)
			)
		)
		(property "Device Type" "R402H16"
			(at 0.064008 -5.517896 180)
			(unlocked yes)
			(layer "F.Fab")
			(hide yes)
			(effects
				(font
					(size 1.016 1.016)
					(thickness 0.1524)
				)
			)
		)
		(duplicate_pad_numbers_are_jumpers no)
		(fp_line
			(start 0.508 -0.9398)
			(end -0.508 -0.9398)
			(stroke
				(width 0.1524)
				(type default)
			)
			(layer "F.SilkS")
		)
		(fp_line
			(start -0.508 -0.9398)
			(end -0.508 0.9398)
			(stroke
				(width 0.1524)
				(type default)
			)
			(layer "F.SilkS")
		)
		(fp_rect
			(start -0.508 0.9398)
			(end 0.508 -0.9398)
			(stroke
				(width 0)
				(type default)
			)
			(fill no)
			(layer "F.CrtYd")
		)
		(fp_rect
			(start -0.508 0.9398)
			(end 0.508 -0.9398)
			(stroke
				(width 0)
				(type default)
			)
			(fill no)
			(layer "F.Fab")
		)
		(pad "1" smd custom
			(at 0 -0.4445 180)
			(size 0.1397 0.1397)
			(layers "F.Cu" "F.Mask" "F.Paste")
			(net "I2C_C_SCL_NCT7904")
			(options
				(clearance outline)
				(anchor circle)
			)
			(primitives
				(gr_poly
					(pts
						(arc
							(start -0.1778 -0.2794)
							(mid -0.249642 -0.249642)
							(end -0.2794 -0.1778)
						)
						(arc
							(start -0.2794 0.1778)
							(mid -0.249642 0.249642)
							(end -0.1778 0.2794)
						)
						(arc
							(start 0.1778 0.2794)
							(mid 0.249642 0.249642)
							(end 0.2794 0.1778)
						)
						(arc
							(start 0.2794 -0.1778)
							(mid 0.249642 -0.249642)
							(end 0.1778 -0.2794)
						)
					)
					(width 0)
					(fill yes)
				)
			)
		)
		(pad "2" smd custom
			(at 0 0.4445 180)
			(size 0.1397 0.1397)
			(layers "F.Cu" "F.Mask" "F.Paste")
			(net "I2C_C_SCL")
			(options
				(clearance outline)
				(anchor circle)
			)
			(primitives
				(gr_poly
					(pts
						(arc
							(start -0.1778 -0.2794)
							(mid -0.249642 -0.249642)
							(end -0.2794 -0.1778)
						)
						(arc
							(start -0.2794 0.1778)
							(mid -0.249642 0.249642)
							(end -0.1778 0.2794)
						)
						(arc
							(start 0.1778 0.2794)
							(mid 0.249642 0.249642)
							(end 0.2794 0.1778)
						)
						(arc
							(start 0.2794 -0.1778)
							(mid 0.249642 -0.249642)
							(end 0.1778 -0.2794)
						)
					)
					(width 0)
					(fill yes)
				)
			)
		)
	)
	(footprint ""
		(layer "F.Cu")
		(at 31.7246 -184.2516)
		(property "Reference" "PR117"
			(at 0 0 0)
			(layer "F.SilkS")
			(hide yes)
			(effects
				(font
					(size 1.27 1.27)
				)
			)
		)
		(property "Value" "3K3R3F-GP"
			(at -0.0254 -2.5146 0)
			(unlocked yes)
			(layer "F.Fab")
			(hide yes)
			(effects
				(font
					(size 1.016 1.016)
					(thickness 0.1524)
				)
			)
		)
		(property "Device Type" "R603H22"
			(at -0.0254 -4.0386 0)
			(unlocked yes)
			(layer "F.Fab")
			(hide yes)
			(effects
				(font
					(size 1.016 1.016)
					(thickness 0.1524)
				)
			)
		)
		(duplicate_pad_numbers_are_jumpers no)
		(fp_line
			(start -0.4826 0)
			(end -0.2032 0)
			(stroke
				(width 0.2032)
				(type default)
			)
			(layer "F.SilkS")
		)
		(fp_line
			(start 0.2032 0)
			(end 0.4826 0)
			(stroke
				(width 0.2032)
				(type default)
			)
			(layer "F.SilkS")
		)
		(fp_rect
			(start -0.5842 1.3335)
			(end 0.5842 -1.3335)
			(stroke
				(width 0)
				(type default)
			)
			(fill no)
			(layer "F.CrtYd")
		)
		(fp_rect
			(start -0.5842 1.3335)
			(end 0.5842 -1.3335)
			(stroke
				(width 0)
				(type default)
			)
			(fill no)
			(layer "F.Fab")
		)
		(pad "1" smd custom
			(at 0 -0.762)
			(size 0.2159 0.2159)
			(layers "F.Cu" "F.Mask" "F.Paste")
			(net "P12V_AUX")
			(options
				(clearance outline)
				(anchor circle)
			)
			(primitives
				(gr_poly
					(pts
						(arc
							(start -0.3302 -0.4318)
							(mid -0.402042 -0.402042)
							(end -0.4318 -0.3302)
						)
						(arc
							(start -0.4318 0.3302)
							(mid -0.402042 0.402042)
							(end -0.3302 0.4318)
						)
						(arc
							(start 0.3302 0.4318)
							(mid 0.402042 0.402042)
							(end 0.4318 0.3302)
						)
						(arc
							(start 0.4318 -0.3302)
							(mid 0.402042 -0.402042)
							(end 0.3302 -0.4318)
						)
					)
					(width 0)
					(fill yes)
				)
			)
		)
		(pad "2" smd custom
			(at 0 0.762)
			(size 0.2159 0.2159)
			(layers "F.Cu" "F.Mask" "F.Paste")
			(net "P3V3_AUX_BJT_B")
			(options
				(clearance outline)
				(anchor circle)
			)
			(primitives
				(gr_poly
					(pts
						(arc
							(start -0.3302 -0.4318)
							(mid -0.402042 -0.402042)
							(end -0.4318 -0.3302)
						)
						(arc
							(start -0.4318 0.3302)
							(mid -0.402042 0.402042)
							(end -0.3302 0.4318)
						)
						(arc
							(start 0.3302 0.4318)
							(mid 0.402042 0.402042)
							(end 0.4318 0.3302)
						)
						(arc
							(start 0.4318 -0.3302)
							(mid 0.402042 -0.402042)
							(end 0.3302 -0.4318)
						)
					)
					(width 0)
					(fill yes)
				)
			)
		)
	)
	(footprint ""
		(layer "F.Cu")
		(at 30.3022 -224.3074)
		(property "Reference" "R138"
			(at 0 0 0)
			(layer "F.SilkS")
			(hide yes)
			(effects
				(font
					(size 1.27 1.27)
				)
			)
		)
		(property "Value" "0R2J-2-GP"
			(at 0.064008 -3.993896 0)
			(unlocked yes)
			(layer "F.Fab")
			(hide yes)
			(effects
				(font
					(size 1.016 1.016)
					(thickness 0.1524)
				)
			)
		)
		(property "Device Type" "R402H16"
			(at 0.064008 -5.517896 0)
			(unlocked yes)
			(layer "F.Fab")
			(hide yes)
			(effects
				(font
					(size 1.016 1.016)
					(thickness 0.1524)
				)
			)
		)
		(duplicate_pad_numbers_are_jumpers no)
		(fp_line
			(start -0.508 -0.9398)
			(end -0.508 0.9398)
			(stroke
				(width 0.1524)
				(type default)
			)
			(layer "F.SilkS")
		)
		(fp_line
			(start 0.508 -0.9398)
			(end -0.508 -0.9398)
			(stroke
				(width 0.1524)
				(type default)
			)
			(layer "F.SilkS")
		)
		(fp_rect
			(start -0.508 0.9398)
			(end 0.508 -0.9398)
			(stroke
				(width 0)
				(type default)
			)
			(fill no)
			(layer "F.CrtYd")
		)
		(fp_rect
			(start -0.508 0.9398)
			(end 0.508 -0.9398)
			(stroke
				(width 0)
				(type default)
			)
			(fill no)
			(layer "F.Fab")
		)
		(pad "1" smd custom
			(at 0 -0.4445)
			(size 0.1397 0.1397)
			(layers "F.Cu" "F.Mask" "F.Paste")
			(net "PWM_OUT_FAN3_NET")
			(options
				(clearance outline)
				(anchor circle)
			)
			(primitives
				(gr_poly
					(pts
						(arc
							(start -0.1778 -0.2794)
							(mid -0.249642 -0.249642)
							(end -0.2794 -0.1778)
						)
						(arc
							(start -0.2794 0.1778)
							(mid -0.249642 0.249642)
							(end -0.1778 0.2794)
						)
						(arc
							(start 0.1778 0.2794)
							(mid 0.249642 0.249642)
							(end 0.2794 0.1778)
						)
						(arc
							(start 0.2794 -0.1778)
							(mid 0.249642 -0.249642)
							(end 0.1778 -0.2794)
						)
					)
					(width 0)
					(fill yes)
				)
			)
		)
		(pad "2" smd custom
			(at 0 0.4445)
			(size 0.1397 0.1397)
			(layers "F.Cu" "F.Mask" "F.Paste")
			(net "PWM_OUT_FAN3")
			(options
				(clearance outline)
				(anchor circle)
			)
			(primitives
				(gr_poly
					(pts
						(arc
							(start -0.1778 -0.2794)
							(mid -0.249642 -0.249642)
							(end -0.2794 -0.1778)
						)
						(arc
							(start -0.2794 0.1778)
							(mid -0.249642 0.249642)
							(end -0.1778 0.2794)
						)
						(arc
							(start 0.1778 0.2794)
							(mid 0.249642 0.249642)
							(end 0.2794 0.1778)
						)
						(arc
							(start 0.2794 -0.1778)
							(mid 0.249642 -0.249642)
							(end 0.1778 -0.2794)
						)
					)
					(width 0)
					(fill yes)
				)
			)
		)
	)
	(footprint ""
		(layer "F.Cu")
		(at 14.3764 -49.0982)
		(property "Reference" "R186"
			(at 0 0 0)
			(layer "F.SilkS")
			(hide yes)
			(effects
				(font
					(size 1.27 1.27)
				)
			)
		)
		(property "Value" "0R2J-2-GP"
			(at 0.064008 -3.993896 0)
			(unlocked yes)
			(layer "F.Fab")
			(hide yes)
			(effects
				(font
					(size 1.016 1.016)
					(thickness 0.1524)
				)
			)
		)
		(property "Device Type" "R402H16"
			(at 0.064008 -5.517896 0)
			(unlocked yes)
			(layer "F.Fab")
			(hide yes)
			(effects
				(font
					(size 1.016 1.016)
					(thickness 0.1524)
				)
			)
		)
		(duplicate_pad_numbers_are_jumpers no)
		(fp_line
			(start -0.508 -0.9398)
			(end -0.508 0.9398)
			(stroke
				(width 0.1524)
				(type default)
			)
			(layer "F.SilkS")
		)
		(fp_line
			(start 0.508 -0.9398)
			(end -0.508 -0.9398)
			(stroke
				(width 0.1524)
				(type default)
			)
			(layer "F.SilkS")
		)
		(fp_rect
			(start -0.508 0.9398)
			(end 0.508 -0.9398)
			(stroke
				(width 0)
				(type default)
			)
			(fill no)
			(layer "F.CrtYd")
		)
		(fp_rect
			(start -0.508 0.9398)
			(end 0.508 -0.9398)
			(stroke
				(width 0)
				(type default)
			)
			(fill no)
			(layer "F.Fab")
		)
		(pad "1" smd custom
			(at 0 -0.4445)
			(size 0.1397 0.1397)
			(layers "F.Cu" "F.Mask" "F.Paste")
			(net "SD_LATCH_RELEASE_U")
			(options
				(clearance outline)
				(anchor circle)
			)
			(primitives
				(gr_poly
					(pts
						(arc
							(start -0.1778 -0.2794)
							(mid -0.249642 -0.249642)
							(end -0.2794 -0.1778)
						)
						(arc
							(start -0.2794 0.1778)
							(mid -0.249642 0.249642)
							(end -0.1778 0.2794)
						)
						(arc
							(start 0.1778 0.2794)
							(mid 0.249642 0.249642)
							(end 0.2794 0.1778)
						)
						(arc
							(start 0.2794 -0.1778)
							(mid 0.249642 -0.249642)
							(end 0.1778 -0.2794)
						)
					)
					(width 0)
					(fill yes)
				)
			)
		)
		(pad "2" smd custom
			(at 0 0.4445)
			(size 0.1397 0.1397)
			(layers "F.Cu" "F.Mask" "F.Paste")
			(net "D_LATCH_PRE#")
			(options
				(clearance outline)
				(anchor circle)
			)
			(primitives
				(gr_poly
					(pts
						(arc
							(start -0.1778 -0.2794)
							(mid -0.249642 -0.249642)
							(end -0.2794 -0.1778)
						)
						(arc
							(start -0.2794 0.1778)
							(mid -0.249642 0.249642)
							(end -0.1778 0.2794)
						)
						(arc
							(start 0.1778 0.2794)
							(mid 0.249642 0.249642)
							(end 0.2794 0.1778)
						)
						(arc
							(start 0.2794 -0.1778)
							(mid 0.249642 -0.249642)
							(end 0.1778 -0.2794)
						)
					)
					(width 0)
					(fill yes)
				)
			)
		)
	)
	(footprint ""
		(layer "F.Cu")
		(at 28.702 -381 180)
		(property "Reference" "PR18"
			(at 0 0 180)
			(layer "F.SilkS")
			(hide yes)
			(effects
				(font
					(size 1.27 1.27)
				)
			)
		)
		(property "Value" "10R2F-L-GP"
			(at 0.064008 -3.993896 180)
			(unlocked yes)
			(layer "F.Fab")
			(hide yes)
			(effects
				(font
					(size 1.016 1.016)
					(thickness 0.1524)
				)
			)
		)
		(property "Device Type" "R402H14"
			(at 0.064008 -5.517896 180)
			(unlocked yes)
			(layer "F.Fab")
			(hide yes)
			(effects
				(font
					(size 1.016 1.016)
					(thickness 0.1524)
				)
			)
		)
		(duplicate_pad_numbers_are_jumpers no)
		(fp_line
			(start 0.508 -0.9398)
			(end -0.508 -0.9398)
			(stroke
				(width 0.1524)
				(type default)
			)
			(layer "F.SilkS")
		)
		(fp_line
			(start -0.508 -0.9398)
			(end -0.508 0.9398)
			(stroke
				(width 0.1524)
				(type default)
			)
			(layer "F.SilkS")
		)
		(fp_rect
			(start -0.508 0.9398)
			(end 0.508 -0.9398)
			(stroke
				(width 0)
				(type default)
			)
			(fill no)
			(layer "F.CrtYd")
		)
		(fp_rect
			(start -0.508 0.9398)
			(end 0.508 -0.9398)
			(stroke
				(width 0)
				(type default)
			)
			(fill no)
			(layer "F.Fab")
		)
		(pad "1" smd custom
			(at 0 -0.4445 180)
			(size 0.1397 0.1397)
			(layers "F.Cu" "F.Mask" "F.Paste")
			(net "ADM1276_SENSE+")
			(options
				(clearance outline)
				(anchor circle)
			)
			(primitives
				(gr_poly
					(pts
						(arc
							(start -0.1778 -0.2794)
							(mid -0.249642 -0.249642)
							(end -0.2794 -0.1778)
						)
						(arc
							(start -0.2794 0.1778)
							(mid -0.249642 0.249642)
							(end -0.1778 0.2794)
						)
						(arc
							(start 0.1778 0.2794)
							(mid 0.249642 0.249642)
							(end 0.2794 0.1778)
						)
						(arc
							(start 0.2794 -0.1778)
							(mid 0.249642 -0.249642)
							(end 0.1778 -0.2794)
						)
					)
					(width 0)
					(fill yes)
				)
			)
		)
		(pad "2" smd custom
			(at 0 0.4445 180)
			(size 0.1397 0.1397)
			(layers "F.Cu" "F.Mask" "F.Paste")
			(net "SENSE+_R3")
			(options
				(clearance outline)
				(anchor circle)
			)
			(primitives
				(gr_poly
					(pts
						(arc
							(start -0.1778 -0.2794)
							(mid -0.249642 -0.249642)
							(end -0.2794 -0.1778)
						)
						(arc
							(start -0.2794 0.1778)
							(mid -0.249642 0.249642)
							(end -0.1778 0.2794)
						)
						(arc
							(start 0.1778 0.2794)
							(mid 0.249642 0.249642)
							(end 0.2794 0.1778)
						)
						(arc
							(start 0.2794 -0.1778)
							(mid 0.249642 -0.249642)
							(end 0.1778 -0.2794)
						)
					)
					(width 0)
					(fill yes)
				)
			)
		)
	)
	(footprint ""
		(layer "F.Cu")
		(at 24.003 -248.793)
		(property "Reference" "PR56"
			(at 0 0 0)
			(layer "F.SilkS")
			(hide yes)
			(effects
				(font
					(size 1.27 1.27)
				)
			)
		)
		(property "Value" "22K1R3F-GP"
			(at -0.0254 -2.5146 0)
			(unlocked yes)
			(layer "F.Fab")
			(hide yes)
			(effects
				(font
					(size 1.016 1.016)
					(thickness 0.1524)
				)
			)
		)
		(property "Device Type" "R603H22"
			(at -0.0254 -4.0386 0)
			(unlocked yes)
			(layer "F.Fab")
			(hide yes)
			(effects
				(font
					(size 1.016 1.016)
					(thickness 0.1524)
				)
			)
		)
		(duplicate_pad_numbers_are_jumpers no)
		(fp_line
			(start -0.4826 0)
			(end -0.2032 0)
			(stroke
				(width 0.2032)
				(type default)
			)
			(layer "F.SilkS")
		)
		(fp_line
			(start 0.2032 0)
			(end 0.4826 0)
			(stroke
				(width 0.2032)
				(type default)
			)
			(layer "F.SilkS")
		)
		(fp_rect
			(start -0.5842 1.3335)
			(end 0.5842 -1.3335)
			(stroke
				(width 0)
				(type default)
			)
			(fill no)
			(layer "F.CrtYd")
		)
		(fp_rect
			(start -0.5842 1.3335)
			(end 0.5842 -1.3335)
			(stroke
				(width 0)
				(type default)
			)
			(fill no)
			(layer "F.Fab")
		)
		(pad "1" smd custom
			(at 0 -0.762)
			(size 0.2159 0.2159)
			(layers "F.Cu" "F.Mask" "F.Paste")
			(net "P3V3_FB")
			(options
				(clearance outline)
				(anchor circle)
			)
			(primitives
				(gr_poly
					(pts
						(arc
							(start -0.3302 -0.4318)
							(mid -0.402042 -0.402042)
							(end -0.4318 -0.3302)
						)
						(arc
							(start -0.4318 0.3302)
							(mid -0.402042 0.402042)
							(end -0.3302 0.4318)
						)
						(arc
							(start 0.3302 0.4318)
							(mid 0.402042 0.402042)
							(end 0.4318 0.3302)
						)
						(arc
							(start 0.4318 -0.3302)
							(mid 0.402042 -0.402042)
							(end 0.3302 -0.4318)
						)
					)
					(width 0)
					(fill yes)
				)
			)
		)
		(pad "2" smd custom
			(at 0 0.762)
			(size 0.2159 0.2159)
			(layers "F.Cu" "F.Mask" "F.Paste")
			(net "GND")
			(options
				(clearance outline)
				(anchor circle)
			)
			(primitives
				(gr_poly
					(pts
						(arc
							(start -0.3302 -0.4318)
							(mid -0.402042 -0.402042)
							(end -0.4318 -0.3302)
						)
						(arc
							(start -0.4318 0.3302)
							(mid -0.402042 0.402042)
							(end -0.3302 0.4318)
						)
						(arc
							(start 0.3302 0.4318)
							(mid 0.402042 0.402042)
							(end 0.4318 0.3302)
						)
						(arc
							(start 0.4318 -0.3302)
							(mid 0.402042 -0.402042)
							(end 0.3302 -0.4318)
						)
					)
					(width 0)
					(fill yes)
				)
			)
		)
	)
	(footprint ""
		(layer "F.Cu")
		(at 35.0266 -378.3076 180)
		(property "Reference" "PR51"
			(at 0 0 180)
			(layer "F.SilkS")
			(hide yes)
			(effects
				(font
					(size 1.27 1.27)
				)
			)
		)
		(property "Value" "10R2F-L-GP"
			(at 0.064008 -3.993896 180)
			(unlocked yes)
			(layer "F.Fab")
			(hide yes)
			(effects
				(font
					(size 1.016 1.016)
					(thickness 0.1524)
				)
			)
		)
		(property "Device Type" "R402H14"
			(at 0.064008 -5.517896 180)
			(unlocked yes)
			(layer "F.Fab")
			(hide yes)
			(effects
				(font
					(size 1.016 1.016)
					(thickness 0.1524)
				)
			)
		)
		(duplicate_pad_numbers_are_jumpers no)
		(fp_line
			(start 0.508 -0.9398)
			(end -0.508 -0.9398)
			(stroke
				(width 0.1524)
				(type default)
			)
			(layer "F.SilkS")
		)
		(fp_line
			(start -0.508 -0.9398)
			(end -0.508 0.9398)
			(stroke
				(width 0.1524)
				(type default)
			)
			(layer "F.SilkS")
		)
		(fp_rect
			(start -0.508 0.9398)
			(end 0.508 -0.9398)
			(stroke
				(width 0)
				(type default)
			)
			(fill no)
			(layer "F.CrtYd")
		)
		(fp_rect
			(start -0.508 0.9398)
			(end 0.508 -0.9398)
			(stroke
				(width 0)
				(type default)
			)
			(fill no)
			(layer "F.Fab")
		)
		(pad "1" smd custom
			(at 0 -0.4445 180)
			(size 0.1397 0.1397)
			(layers "F.Cu" "F.Mask" "F.Paste")
			(net "ADM1276_GATE")
			(options
				(clearance outline)
				(anchor circle)
			)
			(primitives
				(gr_poly
					(pts
						(arc
							(start -0.1778 -0.2794)
							(mid -0.249642 -0.249642)
							(end -0.2794 -0.1778)
						)
						(arc
							(start -0.2794 0.1778)
							(mid -0.249642 0.249642)
							(end -0.1778 0.2794)
						)
						(arc
							(start 0.1778 0.2794)
							(mid 0.249642 0.249642)
							(end 0.2794 0.1778)
						)
						(arc
							(start 0.2794 -0.1778)
							(mid 0.249642 -0.249642)
							(end 0.1778 -0.2794)
						)
					)
					(width 0)
					(fill yes)
				)
			)
		)
		(pad "2" smd custom
			(at 0 0.4445 180)
			(size 0.1397 0.1397)
			(layers "F.Cu" "F.Mask" "F.Paste")
			(net "ADM1276_GATE_DRV0")
			(options
				(clearance outline)
				(anchor circle)
			)
			(primitives
				(gr_poly
					(pts
						(arc
							(start -0.1778 -0.2794)
							(mid -0.249642 -0.249642)
							(end -0.2794 -0.1778)
						)
						(arc
							(start -0.2794 0.1778)
							(mid -0.249642 0.249642)
							(end -0.1778 0.2794)
						)
						(arc
							(start 0.1778 0.2794)
							(mid 0.249642 0.249642)
							(end 0.2794 0.1778)
						)
						(arc
							(start 0.2794 -0.1778)
							(mid 0.249642 -0.249642)
							(end 0.1778 -0.2794)
						)
					)
					(width 0)
					(fill yes)
				)
			)
		)
	)
	(footprint ""
		(layer "F.Cu")
		(at 41.0464 -139.5222 -90)
		(property "Reference" "PC86"
			(at 0 0 270)
			(layer "F.SilkS")
			(hide yes)
			(effects
				(font
					(size 1.27 1.27)
				)
			)
		)
		(property "Value" "SCD01U25V2KX-3GP"
			(at 1.1811 -2.7051 270)
			(unlocked yes)
			(layer "F.Fab")
			(hide yes)
			(effects
				(font
					(size 1.016 1.016)
					(thickness 0.1524)
				)
			)
		)
		(property "Device Type" "C402H22"
			(at 1.1811 -4.2291 270)
			(unlocked yes)
			(layer "F.Fab")
			(hide yes)
			(effects
				(font
					(size 1.016 1.016)
					(thickness 0.1524)
				)
			)
		)
		(duplicate_pad_numbers_are_jumpers no)
		(fp_rect
			(start -0.4318 0.9525)
			(end 0.4318 -0.9525)
			(stroke
				(width 0)
				(type default)
			)
			(fill no)
			(layer "F.CrtYd")
		)
		(fp_rect
			(start -0.4318 0.9525)
			(end 0.4318 -0.9525)
			(stroke
				(width 0)
				(type default)
			)
			(fill no)
			(layer "F.Fab")
		)
		(pad "1" smd custom
			(at 0 -0.4445 270)
			(size 0.1524 0.1524)
			(layers "F.Cu" "F.Mask" "F.Paste")
			(net "P12VL_2490_RC")
			(options
				(clearance outline)
				(anchor circle)
			)
			(primitives
				(gr_poly
					(pts
						(arc
							(start 0.3048 -0.2032)
							(mid 0.275042 -0.275042)
							(end 0.2032 -0.3048)
						)
						(arc
							(start -0.2032 -0.3048)
							(mid -0.275042 -0.275042)
							(end -0.3048 -0.2032)
						)
						(arc
							(start -0.3048 0.2032)
							(mid -0.275042 0.275042)
							(end -0.2032 0.3048)
						)
						(arc
							(start 0.2032 0.3048)
							(mid 0.275042 0.275042)
							(end 0.3048 0.2032)
						)
					)
					(width 0)
					(fill yes)
				)
			)
		)
		(pad "2" smd custom
			(at 0 0.4445 270)
			(size 0.1524 0.1524)
			(layers "F.Cu" "F.Mask" "F.Paste")
			(net "GND")
			(options
				(clearance outline)
				(anchor circle)
			)
			(primitives
				(gr_poly
					(pts
						(arc
							(start 0.3048 -0.2032)
							(mid 0.275042 -0.275042)
							(end 0.2032 -0.3048)
						)
						(arc
							(start -0.2032 -0.3048)
							(mid -0.275042 -0.275042)
							(end -0.3048 -0.2032)
						)
						(arc
							(start -0.3048 0.2032)
							(mid -0.275042 0.275042)
							(end -0.2032 0.3048)
						)
						(arc
							(start 0.2032 0.3048)
							(mid 0.275042 0.275042)
							(end 0.3048 0.2032)
						)
					)
					(width 0)
					(fill yes)
				)
			)
		)
	)
	(footprint ""
		(layer "F.Cu")
		(at 18.669 -410.591)
		(property "Reference" "PR29"
			(at 0 0 0)
			(layer "F.SilkS")
			(hide yes)
			(effects
				(font
					(size 1.27 1.27)
				)
			)
		)
		(property "Value" "D0005RL1632F-GP-U"
			(at 3.2258 1.2954 0)
			(unlocked yes)
			(layer "F.Fab")
			(hide yes)
			(effects
				(font
					(size 1.016 1.016)
					(thickness 0.1524)
				)
			)
		)
		(property "Device Type" "RL3115-4PH45"
			(at 3.2258 -0.2286 0)
			(unlocked yes)
			(layer "F.Fab")
			(hide yes)
			(effects
				(font
					(size 1.016 1.016)
					(thickness 0.1524)
				)
			)
		)
		(duplicate_pad_numbers_are_jumpers no)
		(fp_line
			(start -2.0574 -1.7653)
			(end -2.0574 -0.4064)
			(stroke
				(width 0.3302)
				(type default)
			)
			(layer "F.SilkS")
		)
		(fp_line
			(start -1.9685 -1.651)
			(end 1.9685 -1.651)
			(stroke
				(width 0.1524)
				(type default)
			)
			(layer "F.SilkS")
		)
		(fp_line
			(start -1.9685 1.651)
			(end -1.9685 -1.651)
			(stroke
				(width 0.1524)
				(type default)
			)
			(layer "F.SilkS")
		)
		(fp_line
			(start -0.5334 -1.7653)
			(end -2.0574 -1.7653)
			(stroke
				(width 0.3302)
				(type default)
			)
			(layer "F.SilkS")
		)
		(fp_line
			(start 1.9685 -1.651)
			(end 1.9685 1.651)
			(stroke
				(width 0.1524)
				(type default)
			)
			(layer "F.SilkS")
		)
		(fp_line
			(start 1.9685 1.651)
			(end -1.9685 1.651)
			(stroke
				(width 0.1524)
				(type default)
			)
			(layer "F.SilkS")
		)
		(fp_poly
			(pts
				(xy -0.561594 -1.726946) (xy -0.053594 -2.234946) (xy -1.069594 -2.234946)
			)
			(stroke
				(width 0)
				(type default)
			)
			(fill yes)
			(layer "F.SilkS")
		)
		(fp_rect
			(start -1.524 0.7493)
			(end 1.524 -0.7493)
			(stroke
				(width 0)
				(type default)
			)
			(fill no)
			(layer "F.CrtYd")
		)
		(fp_poly
			(pts
				(xy -2.2225 1.905) (xy -2.2225 -1.905) (xy 2.2225 -1.905) (xy 2.2225 -0.7493) (xy -1.524 -0.7493)
				(xy -1.524 0.7493) (xy 1.524 0.7493) (xy 1.524 -0.7366) (xy 2.2225 -0.7366) (xy 2.2225 1.905)
			)
			(stroke
				(width 0)
				(type default)
			)
			(fill no)
			(layer "F.CrtYd")
		)
		(fp_rect
			(start -2.2225 1.905)
			(end 2.2225 -1.905)
			(stroke
				(width 0)
				(type default)
			)
			(fill no)
			(layer "F.Fab")
		)
		(pad "1" smd rect
			(at -0.5715 -0.813562)
			(size 2.286 1.143)
			(layers "F.Cu" "F.Mask" "F.Paste")
			(net "P12V_AUX")
		)
		(pad "2" smd rect
			(at -0.5715 0.813562)
			(size 2.286 1.143)
			(layers "F.Cu" "F.Mask" "F.Paste")
			(net "P12V_SENSE_TRACE")
		)
		(pad "3" smd rect
			(at 1.334008 -0.813562)
			(size 0.762 1.143)
			(layers "F.Cu" "F.Mask" "F.Paste")
			(net "SENSE+_R1")
		)
		(pad "4" smd rect
			(at 1.334008 0.813562)
			(size 0.762 1.143)
			(layers "F.Cu" "F.Mask" "F.Paste")
			(net "SENSE-_R1")
		)
		(zone
			(layer "F.Cu")
			(hatch none 0.5)
			(connect_pads
				(clearance 0)
			)
			(min_thickness 0.25)
			(keepout
				(tracks not_allowed)
				(vias allowed)
				(pads allowed)
				(copperpour not_allowed)
				(footprints allowed)
			)
			(placement
				(enabled no)
				(sheetname "")
			)
			(fill
				(thermal_gap 0.5)
				(thermal_bridge_width 0.5)
				(island_removal_mode 0)
			)
			(polygon
				(pts
					(xy 19.2405 -410.833062) (xy 19.622008 -410.833062) (xy 19.622008 -411.3403) (xy 19.2405 -411.3403)
				)
			)
		)
		(zone
			(layer "F.Cu")
			(hatch none 0.5)
			(connect_pads
				(clearance 0)
			)
			(min_thickness 0.25)
			(keepout
				(tracks allowed)
				(vias not_allowed)
				(pads allowed)
				(copperpour not_allowed)
				(footprints allowed)
			)
			(placement
				(enabled no)
				(sheetname "")
			)
			(fill
				(thermal_gap 0.5)
				(thermal_bridge_width 0.5)
				(island_removal_mode 0)
			)
			(polygon
				(pts
					(xy 19.2405 -410.833062) (xy 19.622008 -410.833062) (xy 19.622008 -411.3403) (xy 19.2405 -411.3403)
				)
			)
		)
		(zone
			(layer "F.Cu")
			(hatch none 0.5)
			(connect_pads
				(clearance 0)
			)
			(min_thickness 0.25)
			(keepout
				(tracks not_allowed)
				(vias allowed)
				(pads allowed)
				(copperpour not_allowed)
				(footprints allowed)
			)
			(placement
				(enabled no)
				(sheetname "")
			)
			(fill
				(thermal_gap 0.5)
				(thermal_bridge_width 0.5)
				(island_removal_mode 0)
			)
			(polygon
				(pts
					(xy 19.2405 -409.8417) (xy 19.622008 -409.8417) (xy 19.622008 -410.348938) (xy 19.2405 -410.348938)
				)
			)
		)
		(zone
			(layer "F.Cu")
			(hatch none 0.5)
			(connect_pads
				(clearance 0)
			)
			(min_thickness 0.25)
			(keepout
				(tracks allowed)
				(vias not_allowed)
				(pads allowed)
				(copperpour not_allowed)
				(footprints allowed)
			)
			(placement
				(enabled no)
				(sheetname "")
			)
			(fill
				(thermal_gap 0.5)
				(thermal_bridge_width 0.5)
				(island_removal_mode 0)
			)
			(polygon
				(pts
					(xy 19.2405 -409.8417) (xy 19.622008 -409.8417) (xy 19.622008 -410.348938) (xy 19.2405 -410.348938)
				)
			)
		)
	)
	(footprint ""
		(layer "F.Cu")
		(at 17.0688 -179.8828 180)
		(property "Reference" "C54"
			(at 0 0 180)
			(layer "F.SilkS")
			(hide yes)
			(effects
				(font
					(size 1.27 1.27)
				)
			)
		)
		(property "Value" "SCD1U50V3KX-GP"
			(at 0 -2.8194 180)
			(unlocked yes)
			(layer "F.Fab")
			(hide yes)
			(effects
				(font
					(size 1.016 1.016)
					(thickness 0.1524)
				)
			)
		)
		(property "Device Type" "C603H36"
			(at 0 -4.3434 180)
			(unlocked yes)
			(layer "F.Fab")
			(hide yes)
			(effects
				(font
					(size 1.016 1.016)
					(thickness 0.1524)
				)
			)
		)
		(duplicate_pad_numbers_are_jumpers no)
		(fp_line
			(start 0.508 0)
			(end -0.508 0)
			(stroke
				(width 0.2032)
				(type default)
			)
			(layer "F.SilkS")
		)
		(fp_rect
			(start -0.5842 1.3335)
			(end 0.5842 -1.3335)
			(stroke
				(width 0)
				(type default)
			)
			(fill no)
			(layer "F.CrtYd")
		)
		(fp_rect
			(start -0.5842 1.3335)
			(end 0.5842 -1.3335)
			(stroke
				(width 0)
				(type default)
			)
			(fill no)
			(layer "F.Fab")
		)
		(pad "1" smd custom
			(at 0 -0.762 180)
			(size 0.2159 0.2159)
			(layers "F.Cu" "F.Mask" "F.Paste")
			(net "P3V3")
			(options
				(clearance outline)
				(anchor circle)
			)
			(primitives
				(gr_poly
					(pts
						(arc
							(start -0.3302 -0.4318)
							(mid -0.402042 -0.402042)
							(end -0.4318 -0.3302)
						)
						(arc
							(start -0.4318 0.3302)
							(mid -0.402042 0.402042)
							(end -0.3302 0.4318)
						)
						(arc
							(start 0.3302 0.4318)
							(mid 0.402042 0.402042)
							(end 0.4318 0.3302)
						)
						(arc
							(start 0.4318 -0.3302)
							(mid 0.402042 -0.402042)
							(end 0.3302 -0.4318)
						)
					)
					(width 0)
					(fill yes)
				)
			)
		)
		(pad "2" smd custom
			(at 0 0.762 180)
			(size 0.2159 0.2159)
			(layers "F.Cu" "F.Mask" "F.Paste")
			(net "GND")
			(options
				(clearance outline)
				(anchor circle)
			)
			(primitives
				(gr_poly
					(pts
						(arc
							(start -0.3302 -0.4318)
							(mid -0.402042 -0.402042)
							(end -0.4318 -0.3302)
						)
						(arc
							(start -0.4318 0.3302)
							(mid -0.402042 0.402042)
							(end -0.3302 0.4318)
						)
						(arc
							(start 0.3302 0.4318)
							(mid 0.402042 0.402042)
							(end 0.4318 0.3302)
						)
						(arc
							(start 0.4318 -0.3302)
							(mid 0.402042 -0.402042)
							(end 0.3302 -0.4318)
						)
					)
					(width 0)
					(fill yes)
				)
			)
		)
	)
	(footprint ""
		(layer "F.Cu")
		(at 43.8912 -90.6018 90)
		(property "Reference" "TC6"
			(at 0 0 90)
			(layer "F.SilkS")
			(hide yes)
			(effects
				(font
					(size 1.27 1.27)
				)
			)
		)
		(property "Value" "ST68U16VDM-1-GP"
			(at 0 -9.6012 90)
			(unlocked yes)
			(layer "F.Fab")
			(hide yes)
			(effects
				(font
					(size 1.016 1.016)
					(thickness 0.1524)
				)
			)
		)
		(property "Device Type" "CT7343H79"
			(at 0 -11.1252 90)
			(unlocked yes)
			(layer "F.Fab")
			(hide yes)
			(effects
				(font
					(size 1.016 1.016)
					(thickness 0.1524)
				)
			)
		)
		(duplicate_pad_numbers_are_jumpers no)
		(fp_line
			(start 2.286 -4.8768)
			(end -2.286 -4.8768)
			(stroke
				(width 0.1524)
				(type default)
			)
			(layer "F.SilkS")
		)
		(fp_line
			(start -2.286 -4.8768)
			(end -2.286 -2.032)
			(stroke
				(width 0.1524)
				(type default)
			)
			(layer "F.SilkS")
		)
		(fp_line
			(start 2.1082 -4.699)
			(end -2.1082 -4.699)
			(stroke
				(width 0.508)
				(type default)
			)
			(layer "F.SilkS")
		)
		(fp_line
			(start 2.286 -2.032)
			(end 2.286 -4.8768)
			(stroke
				(width 0.1524)
				(type default)
			)
			(layer "F.SilkS")
		)
		(fp_line
			(start 2.286 2.032)
			(end 2.286 4.8768)
			(stroke
				(width 0.1524)
				(type default)
			)
			(layer "F.SilkS")
		)
		(fp_line
			(start 2.286 4.8768)
			(end -2.286 4.8768)
			(stroke
				(width 0.1524)
				(type default)
			)
			(layer "F.SilkS")
		)
		(fp_line
			(start -2.286 4.8768)
			(end -2.286 2.032)
			(stroke
				(width 0.1524)
				(type default)
			)
			(layer "F.SilkS")
		)
		(fp_rect
			(start -2.1463 3.6449)
			(end 2.1463 -3.6449)
			(stroke
				(width 0)
				(type default)
			)
			(fill no)
			(layer "F.CrtYd")
		)
		(fp_poly
			(pts
				(xy -2.54 4.953) (xy -2.54 4.2926) (xy -3.81 4.2926) (xy -3.81 -4.2926) (xy -2.54 -4.2926) (xy -2.54 -4.953)
				(xy 2.54 -4.953) (xy 2.54 -4.2926) (xy 3.81 -4.2926) (xy 3.81 -1.6256) (xy 2.1463 -1.6256) (xy 2.1463 -3.6449)
				(xy -2.1463 -3.6449) (xy -2.1463 3.6449) (xy 2.1463 3.6449) (xy 2.1463 -1.6129) (xy 3.81 -1.6129)
				(xy 3.81 4.2926) (xy 2.54 4.2926) (xy 2.54 4.953)
			)
			(stroke
				(width 0)
				(type default)
			)
			(fill no)
			(layer "F.CrtYd")
		)
		(fp_rect
			(start 2.54 4.2926)
			(end 3.81 -4.2926)
			(stroke
				(width 0)
				(type default)
			)
			(fill no)
			(layer "F.Fab")
		)
		(fp_rect
			(start -3.81 4.2926)
			(end -2.54 -4.2926)
			(stroke
				(width 0)
				(type default)
			)
			(fill no)
			(layer "F.Fab")
		)
		(fp_rect
			(start -2.54 4.953)
			(end 2.54 -4.953)
			(stroke
				(width 0)
				(type default)
			)
			(fill no)
			(layer "F.Fab")
		)
		(pad "1" smd rect
			(at 0 -3.1496 90)
			(size 2.413 2.286)
			(layers "F.Cu" "F.Mask" "F.Paste")
			(net "P12VL")
		)
		(pad "2" smd rect
			(at 0 3.1496 90)
			(size 2.413 2.286)
			(layers "F.Cu" "F.Mask" "F.Paste")
			(net "GND")
		)
		(zone
			(layer "F.Cu")
			(hatch none 0.5)
			(connect_pads
				(clearance 0)
			)
			(min_thickness 0.25)
			(keepout
				(tracks allowed)
				(vias not_allowed)
				(pads allowed)
				(copperpour not_allowed)
				(footprints allowed)
			)
			(placement
				(enabled no)
				(sheetname "")
			)
			(fill
				(thermal_gap 0.5)
				(thermal_bridge_width 0.5)
				(island_removal_mode 0)
			)
			(polygon
				(pts
					(xy 42.2021 -92.1131) (xy 39.2938 -92.1131) (xy 39.2938 -89.0905) (xy 42.1894 -89.0905) (xy 42.5196 -89.0905)
					(xy 42.5196 -92.1131)
				)
			)
		)
		(zone
			(layer "F.Cu")
			(hatch none 0.5)
			(connect_pads
				(clearance 0)
			)
			(min_thickness 0.25)
			(keepout
				(tracks allowed)
				(vias not_allowed)
				(pads allowed)
				(copperpour not_allowed)
				(footprints allowed)
			)
			(placement
				(enabled no)
				(sheetname "")
			)
			(fill
				(thermal_gap 0.5)
				(thermal_bridge_width 0.5)
				(island_removal_mode 0)
			)
			(polygon
				(pts
					(xy 48.4886 -89.0905) (xy 48.4886 -92.1131) (xy 45.593 -92.1131) (xy 45.2628 -92.1131) (xy 45.2628 -89.0905)
					(xy 45.593 -89.0905)
				)
			)
		)
	)
	(footprint ""
		(layer "F.Cu")
		(at 20.9296 -174.3456 90)
		(property "Reference" "R22"
			(at 0 0 90)
			(layer "F.SilkS")
			(hide yes)
			(effects
				(font
					(size 1.27 1.27)
				)
			)
		)
		(property "Value" "4K7R2F-GP"
			(at 0.064008 -3.993896 90)
			(unlocked yes)
			(layer "F.Fab")
			(hide yes)
			(effects
				(font
					(size 1.016 1.016)
					(thickness 0.1524)
				)
			)
		)
		(property "Device Type" "R402H16"
			(at 0.064008 -5.517896 90)
			(unlocked yes)
			(layer "F.Fab")
			(hide yes)
			(effects
				(font
					(size 1.016 1.016)
					(thickness 0.1524)
				)
			)
		)
		(duplicate_pad_numbers_are_jumpers no)
		(fp_line
			(start 0.508 -0.9398)
			(end -0.508 -0.9398)
			(stroke
				(width 0.1524)
				(type default)
			)
			(layer "F.SilkS")
		)
		(fp_line
			(start -0.508 -0.9398)
			(end -0.508 0.9398)
			(stroke
				(width 0.1524)
				(type default)
			)
			(layer "F.SilkS")
		)
		(fp_rect
			(start -0.508 0.9398)
			(end 0.508 -0.9398)
			(stroke
				(width 0)
				(type default)
			)
			(fill no)
			(layer "F.CrtYd")
		)
		(fp_rect
			(start -0.508 0.9398)
			(end 0.508 -0.9398)
			(stroke
				(width 0)
				(type default)
			)
			(fill no)
			(layer "F.Fab")
		)
		(pad "1" smd custom
			(at 0 -0.4445 90)
			(size 0.1397 0.1397)
			(layers "F.Cu" "F.Mask" "F.Paste")
			(net "P3V3")
			(options
				(clearance outline)
				(anchor circle)
			)
			(primitives
				(gr_poly
					(pts
						(arc
							(start -0.1778 -0.2794)
							(mid -0.249642 -0.249642)
							(end -0.2794 -0.1778)
						)
						(arc
							(start -0.2794 0.1778)
							(mid -0.249642 0.249642)
							(end -0.1778 0.2794)
						)
						(arc
							(start 0.1778 0.2794)
							(mid 0.249642 0.249642)
							(end 0.2794 0.1778)
						)
						(arc
							(start 0.2794 -0.1778)
							(mid 0.249642 -0.249642)
							(end 0.1778 -0.2794)
						)
					)
					(width 0)
					(fill yes)
				)
			)
		)
		(pad "2" smd custom
			(at 0 0.4445 90)
			(size 0.1397 0.1397)
			(layers "F.Cu" "F.Mask" "F.Paste")
			(net "THERMHOT#")
			(options
				(clearance outline)
				(anchor circle)
			)
			(primitives
				(gr_poly
					(pts
						(arc
							(start -0.1778 -0.2794)
							(mid -0.249642 -0.249642)
							(end -0.2794 -0.1778)
						)
						(arc
							(start -0.2794 0.1778)
							(mid -0.249642 0.249642)
							(end -0.1778 0.2794)
						)
						(arc
							(start 0.1778 0.2794)
							(mid 0.249642 0.249642)
							(end 0.2794 0.1778)
						)
						(arc
							(start 0.2794 -0.1778)
							(mid 0.249642 -0.249642)
							(end 0.1778 -0.2794)
						)
					)
					(width 0)
					(fill yes)
				)
			)
		)
	)
	(footprint ""
		(layer "F.Cu")
		(at 17.63649 -172.175424 180)
		(property "Reference" "U3"
			(at 0 0 180)
			(layer "F.SilkS")
			(hide yes)
			(effects
				(font
					(size 1.27 1.27)
				)
			)
		)
		(property "Value" "74LVC1G32GW-1GP"
			(at -2.3368 -8.6868 180)
			(unlocked yes)
			(layer "F.Fab")
			(hide yes)
			(effects
				(font
					(size 1.016 1.016)
					(thickness 0.1524)
				)
			)
		)
		(property "Device Type" "SC70-5H44"
			(at -2.3114 -10.414 180)
			(unlocked yes)
			(layer "F.Fab")
			(hide yes)
			(effects
				(font
					(size 1.016 1.016)
					(thickness 0.1524)
				)
			)
		)
		(duplicate_pad_numbers_are_jumpers no)
		(fp_line
			(start 1.3843 -1.8034)
			(end 1.3843 -1.1176)
			(stroke
				(width 0.3302)
				(type default)
			)
			(layer "F.SilkS")
		)
		(fp_line
			(start 1.27 1.7018)
			(end -1.27 1.7018)
			(stroke
				(width 0.1524)
				(type default)
			)
			(layer "F.SilkS")
		)
		(fp_line
			(start 1.27 -1.7018)
			(end 1.27 1.7018)
			(stroke
				(width 0.1524)
				(type default)
			)
			(layer "F.SilkS")
		)
		(fp_line
			(start 0.6604 -1.8034)
			(end 1.3843 -1.8034)
			(stroke
				(width 0.3302)
				(type default)
			)
			(layer "F.SilkS")
		)
		(fp_line
			(start -1.27 1.7018)
			(end -1.27 -1.7018)
			(stroke
				(width 0.1524)
				(type default)
			)
			(layer "F.SilkS")
		)
		(fp_line
			(start -1.27 -1.7018)
			(end 1.27 -1.7018)
			(stroke
				(width 0.1524)
				(type default)
			)
			(layer "F.SilkS")
		)
		(fp_rect
			(start -1.524 1.9558)
			(end 1.524 -1.9558)
			(stroke
				(width 0)
				(type default)
			)
			(fill no)
			(layer "F.CrtYd")
		)
		(fp_poly
			(pts
				(xy -1.524 -1.9558) (xy 1.524 -1.9558) (xy 1.524 1.9558) (xy -1.524 1.9558)
			)
			(stroke
				(width 0)
				(type default)
			)
			(fill no)
			(layer "F.Fab")
		)
		(pad "1" smd rect
			(at 0.65024 -0.8255 180)
			(size 0.4064 1.2192)
			(layers "F.Cu" "F.Mask" "F.Paste")
			(net "SEB_PEER_1A_1B_HB_OUT")
		)
		(pad "2" smd rect
			(at 0 -0.8255 180)
			(size 0.4064 1.2192)
			(layers "F.Cu" "F.Mask" "F.Paste")
			(net "SEB_PEER_2A_2B_HB_OUT")
		)
		(pad "3" smd rect
			(at -0.65024 -0.8255 180)
			(size 0.4064 1.2192)
			(layers "F.Cu" "F.Mask" "F.Paste")
			(net "GND")
		)
		(pad "4" smd rect
			(at -0.65024 0.8255 180)
			(size 0.4064 1.2192)
			(layers "F.Cu" "F.Mask" "F.Paste")
			(net "THERMHOT#_R")
		)
		(pad "5" smd rect
			(at 0.65024 0.8255 180)
			(size 0.4064 1.2192)
			(layers "F.Cu" "F.Mask" "F.Paste")
			(net "P3V3")
		)
	)
	(footprint ""
		(layer "F.Cu")
		(at 21.0058 -247.9802 90)
		(property "Reference" "U4"
			(at 0 0 90)
			(layer "F.SilkS")
			(hide yes)
			(effects
				(font
					(size 1.27 1.27)
				)
			)
		)
		(property "Value" "SY8201ABC-GP"
			(at -0.0254 -11.9634 90)
			(unlocked yes)
			(layer "F.Fab")
			(hide yes)
			(effects
				(font
					(size 1.016 1.016)
					(thickness 0.1524)
				)
			)
		)
		(property "Device Type" "SOT-6H56"
			(at -0.0254 -13.5636 90)
			(unlocked yes)
			(layer "F.Fab")
			(hide yes)
			(effects
				(font
					(size 1.016 1.016)
					(thickness 0.1524)
				)
			)
		)
		(duplicate_pad_numbers_are_jumpers no)
		(fp_line
			(start 1.7145 -0.5842)
			(end -1.9685 -0.5842)
			(stroke
				(width 0.1524)
				(type default)
			)
			(layer "F.SilkS")
		)
		(fp_line
			(start -1.9685 -0.5842)
			(end -1.9685 0.5842)
			(stroke
				(width 0.1524)
				(type default)
			)
			(layer "F.SilkS")
		)
		(fp_line
			(start -1.9685 -0.4064)
			(end -1.5621 0)
			(stroke
				(width 0.1524)
				(type default)
			)
			(layer "F.SilkS")
		)
		(fp_line
			(start -1.5621 0)
			(end -1.9685 0.4064)
			(stroke
				(width 0.1524)
				(type default)
			)
			(layer "F.SilkS")
		)
		(fp_line
			(start 1.7145 0.5842)
			(end 1.7145 -0.5842)
			(stroke
				(width 0.1524)
				(type default)
			)
			(layer "F.SilkS")
		)
		(fp_line
			(start -1.9685 0.5842)
			(end 1.7145 0.5842)
			(stroke
				(width 0.1524)
				(type default)
			)
			(layer "F.SilkS")
		)
		(fp_line
			(start -1.9685 0.5842)
			(end -1.9685 2.3622)
			(stroke
				(width 0.508)
				(type default)
			)
			(layer "F.SilkS")
		)
		(fp_poly
			(pts
				(xy -1.27 -0.635) (xy 1.27 -0.635) (xy 1.27 0.635) (xy -1.27 0.635)
			)
			(stroke
				(width 0)
				(type default)
			)
			(fill yes)
			(layer "F.SilkS")
		)
		(fp_rect
			(start -1.9685 2.3622)
			(end 1.9685 -2.3622)
			(stroke
				(width 0)
				(type default)
			)
			(fill no)
			(layer "F.CrtYd")
		)
		(fp_poly
			(pts
				(xy -1.9685 -2.3622) (xy 1.9685 -2.3622) (xy 1.9685 2.3622) (xy -1.9685 2.3622)
			)
			(stroke
				(width 0)
				(type default)
			)
			(fill no)
			(layer "F.Fab")
		)
		(pad "1" smd rect
			(at -0.9525 1.3462 90)
			(size 0.5842 1.016)
			(layers "F.Cu" "F.Mask" "F.Paste")
			(net "P3V3_BS_NET")
		)
		(pad "2" smd rect
			(at 0 1.3462 90)
			(size 0.5842 1.016)
			(layers "F.Cu" "F.Mask" "F.Paste")
			(net "GND")
		)
		(pad "3" smd rect
			(at 0.9525 1.3462 90)
			(size 0.5842 1.016)
			(layers "F.Cu" "F.Mask" "F.Paste")
			(net "P3V3_FB")
		)
		(pad "4" smd rect
			(at 0.9525 -1.3462 90)
			(size 0.5842 1.016)
			(layers "F.Cu" "F.Mask" "F.Paste")
			(net "P3V3_EN")
		)
		(pad "5" smd rect
			(at 0 -1.3462 90)
			(size 0.5842 1.016)
			(layers "F.Cu" "F.Mask" "F.Paste")
			(net "P3V3_IN")
		)
		(pad "6" smd rect
			(at -0.9525 -1.3462 90)
			(size 0.5842 1.016)
			(layers "F.Cu" "F.Mask" "F.Paste")
			(net "P3V3_LX")
		)
	)
	(footprint ""
		(layer "F.Cu")
		(at 29.1338 -153.289 90)
		(property "Reference" "C8"
			(at 0 0 90)
			(layer "F.SilkS")
			(hide yes)
			(effects
				(font
					(size 1.27 1.27)
				)
			)
		)
		(property "Value" "SC2200P50V2KX-2GP"
			(at 1.1811 -2.7051 90)
			(unlocked yes)
			(layer "F.Fab")
			(hide yes)
			(effects
				(font
					(size 1.016 1.016)
					(thickness 0.1524)
				)
			)
		)
		(property "Device Type" "C402H22"
			(at 1.1811 -4.2291 90)
			(unlocked yes)
			(layer "F.Fab")
			(hide yes)
			(effects
				(font
					(size 1.016 1.016)
					(thickness 0.1524)
				)
			)
		)
		(duplicate_pad_numbers_are_jumpers no)
		(fp_rect
			(start -0.4318 0.9525)
			(end 0.4318 -0.9525)
			(stroke
				(width 0)
				(type default)
			)
			(fill no)
			(layer "F.CrtYd")
		)
		(fp_rect
			(start -0.4318 0.9525)
			(end 0.4318 -0.9525)
			(stroke
				(width 0)
				(type default)
			)
			(fill no)
			(layer "F.Fab")
		)
		(pad "1" smd custom
			(at 0 -0.4445 90)
			(size 0.1524 0.1524)
			(layers "F.Cu" "F.Mask" "F.Paste")
			(net "NCT7904_D2+")
			(options
				(clearance outline)
				(anchor circle)
			)
			(primitives
				(gr_poly
					(pts
						(arc
							(start 0.3048 -0.2032)
							(mid 0.275042 -0.275042)
							(end 0.2032 -0.3048)
						)
						(arc
							(start -0.2032 -0.3048)
							(mid -0.275042 -0.275042)
							(end -0.3048 -0.2032)
						)
						(arc
							(start -0.3048 0.2032)
							(mid -0.275042 0.275042)
							(end -0.2032 0.3048)
						)
						(arc
							(start 0.2032 0.3048)
							(mid 0.275042 0.275042)
							(end 0.3048 0.2032)
						)
					)
					(width 0)
					(fill yes)
				)
			)
		)
		(pad "2" smd custom
			(at 0 0.4445 90)
			(size 0.1524 0.1524)
			(layers "F.Cu" "F.Mask" "F.Paste")
			(net "NCT7904_D2-")
			(options
				(clearance outline)
				(anchor circle)
			)
			(primitives
				(gr_poly
					(pts
						(arc
							(start 0.3048 -0.2032)
							(mid 0.275042 -0.275042)
							(end 0.2032 -0.3048)
						)
						(arc
							(start -0.2032 -0.3048)
							(mid -0.275042 -0.275042)
							(end -0.3048 -0.2032)
						)
						(arc
							(start -0.3048 0.2032)
							(mid -0.275042 0.275042)
							(end -0.2032 0.3048)
						)
						(arc
							(start 0.2032 0.3048)
							(mid 0.275042 0.275042)
							(end 0.3048 0.2032)
						)
					)
					(width 0)
					(fill yes)
				)
			)
		)
	)
	(footprint ""
		(layer "F.Cu")
		(at 18.7198 -137.5664 180)
		(property "Reference" "PR104"
			(at 0 0 180)
			(layer "F.SilkS")
			(hide yes)
			(effects
				(font
					(size 1.27 1.27)
				)
			)
		)
		(property "Value" "2K7R2F-GP"
			(at 0.064008 -3.993896 180)
			(unlocked yes)
			(layer "F.Fab")
			(hide yes)
			(effects
				(font
					(size 1.016 1.016)
					(thickness 0.1524)
				)
			)
		)
		(property "Device Type" "R402H16"
			(at 0.064008 -5.517896 180)
			(unlocked yes)
			(layer "F.Fab")
			(hide yes)
			(effects
				(font
					(size 1.016 1.016)
					(thickness 0.1524)
				)
			)
		)
		(duplicate_pad_numbers_are_jumpers no)
		(fp_line
			(start 0.508 -0.9398)
			(end -0.508 -0.9398)
			(stroke
				(width 0.1524)
				(type default)
			)
			(layer "F.SilkS")
		)
		(fp_line
			(start -0.508 -0.9398)
			(end -0.508 0.9398)
			(stroke
				(width 0.1524)
				(type default)
			)
			(layer "F.SilkS")
		)
		(fp_rect
			(start -0.508 0.9398)
			(end 0.508 -0.9398)
			(stroke
				(width 0)
				(type default)
			)
			(fill no)
			(layer "F.CrtYd")
		)
		(fp_rect
			(start -0.508 0.9398)
			(end 0.508 -0.9398)
			(stroke
				(width 0)
				(type default)
			)
			(fill no)
			(layer "F.Fab")
		)
		(pad "1" smd custom
			(at 0 -0.4445 180)
			(size 0.1397 0.1397)
			(layers "F.Cu" "F.Mask" "F.Paste")
			(net "P12VU")
			(options
				(clearance outline)
				(anchor circle)
			)
			(primitives
				(gr_poly
					(pts
						(arc
							(start -0.1778 -0.2794)
							(mid -0.249642 -0.249642)
							(end -0.2794 -0.1778)
						)
						(arc
							(start -0.2794 0.1778)
							(mid -0.249642 0.249642)
							(end -0.1778 0.2794)
						)
						(arc
							(start 0.1778 0.2794)
							(mid 0.249642 0.249642)
							(end 0.2794 0.1778)
						)
						(arc
							(start 0.2794 -0.1778)
							(mid 0.249642 -0.249642)
							(end 0.1778 -0.2794)
						)
					)
					(width 0)
					(fill yes)
				)
			)
		)
		(pad "2" smd custom
			(at 0 0.4445 180)
			(size 0.1397 0.1397)
			(layers "F.Cu" "F.Mask" "F.Paste")
			(net "P12VU_2490_PG")
			(options
				(clearance outline)
				(anchor circle)
			)
			(primitives
				(gr_poly
					(pts
						(arc
							(start -0.1778 -0.2794)
							(mid -0.249642 -0.249642)
							(end -0.2794 -0.1778)
						)
						(arc
							(start -0.2794 0.1778)
							(mid -0.249642 0.249642)
							(end -0.1778 0.2794)
						)
						(arc
							(start 0.1778 0.2794)
							(mid 0.249642 0.249642)
							(end 0.2794 0.1778)
						)
						(arc
							(start 0.2794 -0.1778)
							(mid 0.249642 -0.249642)
							(end 0.1778 -0.2794)
						)
					)
					(width 0)
					(fill yes)
				)
			)
		)
	)
	(footprint ""
		(layer "F.Cu")
		(at 11.0236 -227.1776 180)
		(property "Reference" "R33"
			(at 0 0 180)
			(layer "F.SilkS")
			(hide yes)
			(effects
				(font
					(size 1.27 1.27)
				)
			)
		)
		(property "Value" "33R2F-3-GP"
			(at 0.064008 -3.993896 180)
			(unlocked yes)
			(layer "F.Fab")
			(hide yes)
			(effects
				(font
					(size 1.016 1.016)
					(thickness 0.1524)
				)
			)
		)
		(property "Device Type" "R402H16"
			(at 0.064008 -5.517896 180)
			(unlocked yes)
			(layer "F.Fab")
			(hide yes)
			(effects
				(font
					(size 1.016 1.016)
					(thickness 0.1524)
				)
			)
		)
		(duplicate_pad_numbers_are_jumpers no)
		(fp_line
			(start 0.508 -0.9398)
			(end -0.508 -0.9398)
			(stroke
				(width 0.1524)
				(type default)
			)
			(layer "F.SilkS")
		)
		(fp_line
			(start -0.508 -0.9398)
			(end -0.508 0.9398)
			(stroke
				(width 0.1524)
				(type default)
			)
			(layer "F.SilkS")
		)
		(fp_rect
			(start -0.508 0.9398)
			(end 0.508 -0.9398)
			(stroke
				(width 0)
				(type default)
			)
			(fill no)
			(layer "F.CrtYd")
		)
		(fp_rect
			(start -0.508 0.9398)
			(end 0.508 -0.9398)
			(stroke
				(width 0)
				(type default)
			)
			(fill no)
			(layer "F.Fab")
		)
		(pad "1" smd custom
			(at 0 -0.4445 180)
			(size 0.1397 0.1397)
			(layers "F.Cu" "F.Mask" "F.Paste")
			(net "P3V3")
			(options
				(clearance outline)
				(anchor circle)
			)
			(primitives
				(gr_poly
					(pts
						(arc
							(start -0.1778 -0.2794)
							(mid -0.249642 -0.249642)
							(end -0.2794 -0.1778)
						)
						(arc
							(start -0.2794 0.1778)
							(mid -0.249642 0.249642)
							(end -0.1778 0.2794)
						)
						(arc
							(start 0.1778 0.2794)
							(mid 0.249642 0.249642)
							(end 0.2794 0.1778)
						)
						(arc
							(start 0.2794 -0.1778)
							(mid 0.249642 -0.249642)
							(end 0.1778 -0.2794)
						)
					)
					(width 0)
					(fill yes)
				)
			)
		)
		(pad "2" smd custom
			(at 0 0.4445 180)
			(size 0.1397 0.1397)
			(layers "F.Cu" "F.Mask" "F.Paste")
			(net "LED_DR_LED3_BLUE")
			(options
				(clearance outline)
				(anchor circle)
			)
			(primitives
				(gr_poly
					(pts
						(arc
							(start -0.1778 -0.2794)
							(mid -0.249642 -0.249642)
							(end -0.2794 -0.1778)
						)
						(arc
							(start -0.2794 0.1778)
							(mid -0.249642 0.249642)
							(end -0.1778 0.2794)
						)
						(arc
							(start 0.1778 0.2794)
							(mid 0.249642 0.249642)
							(end 0.2794 0.1778)
						)
						(arc
							(start 0.2794 -0.1778)
							(mid 0.249642 -0.249642)
							(end 0.1778 -0.2794)
						)
					)
					(width 0)
					(fill yes)
				)
			)
		)
	)
	(footprint ""
		(layer "F.Cu")
		(at 8.0772 -275.2344 90)
		(property "Reference" "R38"
			(at 0 0 90)
			(layer "F.SilkS")
			(hide yes)
			(effects
				(font
					(size 1.27 1.27)
				)
			)
		)
		(property "Value" "0R2J-2-GP"
			(at 0.064008 -3.993896 90)
			(unlocked yes)
			(layer "F.Fab")
			(hide yes)
			(effects
				(font
					(size 1.016 1.016)
					(thickness 0.1524)
				)
			)
		)
		(property "Device Type" "R402H16"
			(at 0.064008 -5.517896 90)
			(unlocked yes)
			(layer "F.Fab")
			(hide yes)
			(effects
				(font
					(size 1.016 1.016)
					(thickness 0.1524)
				)
			)
		)
		(duplicate_pad_numbers_are_jumpers no)
		(fp_line
			(start 0.508 -0.9398)
			(end -0.508 -0.9398)
			(stroke
				(width 0.1524)
				(type default)
			)
			(layer "F.SilkS")
		)
		(fp_line
			(start -0.508 -0.9398)
			(end -0.508 0.9398)
			(stroke
				(width 0.1524)
				(type default)
			)
			(layer "F.SilkS")
		)
		(fp_rect
			(start -0.508 0.9398)
			(end 0.508 -0.9398)
			(stroke
				(width 0)
				(type default)
			)
			(fill no)
			(layer "F.CrtYd")
		)
		(fp_rect
			(start -0.508 0.9398)
			(end 0.508 -0.9398)
			(stroke
				(width 0)
				(type default)
			)
			(fill no)
			(layer "F.Fab")
		)
		(pad "1" smd custom
			(at 0 -0.4445 90)
			(size 0.1397 0.1397)
			(layers "F.Cu" "F.Mask" "F.Paste")
			(net "LED_DR_LED2_K")
			(options
				(clearance outline)
				(anchor circle)
			)
			(primitives
				(gr_poly
					(pts
						(arc
							(start -0.1778 -0.2794)
							(mid -0.249642 -0.249642)
							(end -0.2794 -0.1778)
						)
						(arc
							(start -0.2794 0.1778)
							(mid -0.249642 0.249642)
							(end -0.1778 0.2794)
						)
						(arc
							(start 0.1778 0.2794)
							(mid 0.249642 0.249642)
							(end 0.2794 0.1778)
						)
						(arc
							(start 0.2794 -0.1778)
							(mid 0.249642 -0.249642)
							(end 0.1778 -0.2794)
						)
					)
					(width 0)
					(fill yes)
				)
			)
		)
		(pad "2" smd custom
			(at 0 0.4445 90)
			(size 0.1397 0.1397)
			(layers "F.Cu" "F.Mask" "F.Paste")
			(net "GND")
			(options
				(clearance outline)
				(anchor circle)
			)
			(primitives
				(gr_poly
					(pts
						(arc
							(start -0.1778 -0.2794)
							(mid -0.249642 -0.249642)
							(end -0.2794 -0.1778)
						)
						(arc
							(start -0.2794 0.1778)
							(mid -0.249642 0.249642)
							(end -0.1778 0.2794)
						)
						(arc
							(start 0.1778 0.2794)
							(mid 0.249642 0.249642)
							(end 0.2794 0.1778)
						)
						(arc
							(start 0.2794 -0.1778)
							(mid 0.249642 -0.249642)
							(end 0.1778 -0.2794)
						)
					)
					(width 0)
					(fill yes)
				)
			)
		)
	)
	(footprint ""
		(layer "F.Cu")
		(at 24.4094 -135.1788)
		(property "Reference" "PR94"
			(at 0 0 0)
			(layer "F.SilkS")
			(hide yes)
			(effects
				(font
					(size 1.27 1.27)
				)
			)
		)
		(property "Value" "0R2J-2-GP"
			(at 0.064008 -3.993896 0)
			(unlocked yes)
			(layer "F.Fab")
			(hide yes)
			(effects
				(font
					(size 1.016 1.016)
					(thickness 0.1524)
				)
			)
		)
		(property "Device Type" "R402H16"
			(at 0.064008 -5.517896 0)
			(unlocked yes)
			(layer "F.Fab")
			(hide yes)
			(effects
				(font
					(size 1.016 1.016)
					(thickness 0.1524)
				)
			)
		)
		(duplicate_pad_numbers_are_jumpers no)
		(fp_line
			(start -0.508 -0.9398)
			(end -0.508 0.9398)
			(stroke
				(width 0.1524)
				(type default)
			)
			(layer "F.SilkS")
		)
		(fp_line
			(start 0.508 -0.9398)
			(end -0.508 -0.9398)
			(stroke
				(width 0.1524)
				(type default)
			)
			(layer "F.SilkS")
		)
		(fp_rect
			(start -0.508 0.9398)
			(end 0.508 -0.9398)
			(stroke
				(width 0)
				(type default)
			)
			(fill no)
			(layer "F.CrtYd")
		)
		(fp_rect
			(start -0.508 0.9398)
			(end 0.508 -0.9398)
			(stroke
				(width 0)
				(type default)
			)
			(fill no)
			(layer "F.Fab")
		)
		(pad "1" smd custom
			(at 0 -0.4445)
			(size 0.1397 0.1397)
			(layers "F.Cu" "F.Mask" "F.Paste")
			(net "P12VU_2490_VCC")
			(options
				(clearance outline)
				(anchor circle)
			)
			(primitives
				(gr_poly
					(pts
						(arc
							(start -0.1778 -0.2794)
							(mid -0.249642 -0.249642)
							(end -0.2794 -0.1778)
						)
						(arc
							(start -0.2794 0.1778)
							(mid -0.249642 0.249642)
							(end -0.1778 0.2794)
						)
						(arc
							(start 0.1778 0.2794)
							(mid 0.249642 0.249642)
							(end 0.2794 0.1778)
						)
						(arc
							(start 0.2794 -0.1778)
							(mid 0.249642 -0.249642)
							(end 0.1778 -0.2794)
						)
					)
					(width 0)
					(fill yes)
				)
			)
		)
		(pad "2" smd custom
			(at 0 0.4445)
			(size 0.1397 0.1397)
			(layers "F.Cu" "F.Mask" "F.Paste")
			(net "P12V")
			(options
				(clearance outline)
				(anchor circle)
			)
			(primitives
				(gr_poly
					(pts
						(arc
							(start -0.1778 -0.2794)
							(mid -0.249642 -0.249642)
							(end -0.2794 -0.1778)
						)
						(arc
							(start -0.2794 0.1778)
							(mid -0.249642 0.249642)
							(end -0.1778 0.2794)
						)
						(arc
							(start 0.1778 0.2794)
							(mid 0.249642 0.249642)
							(end 0.2794 0.1778)
						)
						(arc
							(start 0.2794 -0.1778)
							(mid 0.249642 -0.249642)
							(end 0.1778 -0.2794)
						)
					)
					(width 0)
					(fill yes)
				)
			)
		)
	)
	(footprint ""
		(layer "F.Cu")
		(at 36.195 -176.657 -90)
		(property "Reference" "C256"
			(at 0 0 270)
			(layer "F.SilkS")
			(hide yes)
			(effects
				(font
					(size 1.27 1.27)
				)
			)
		)
		(property "Value" "SCD1U16V2KX-3GP"
			(at 1.1811 -2.7051 270)
			(unlocked yes)
			(layer "F.Fab")
			(hide yes)
			(effects
				(font
					(size 1.016 1.016)
					(thickness 0.1524)
				)
			)
		)
		(property "Device Type" "C402H22"
			(at 1.1811 -4.2291 270)
			(unlocked yes)
			(layer "F.Fab")
			(hide yes)
			(effects
				(font
					(size 1.016 1.016)
					(thickness 0.1524)
				)
			)
		)
		(duplicate_pad_numbers_are_jumpers no)
		(fp_rect
			(start -0.4318 0.9525)
			(end 0.4318 -0.9525)
			(stroke
				(width 0)
				(type default)
			)
			(fill no)
			(layer "F.CrtYd")
		)
		(fp_rect
			(start -0.4318 0.9525)
			(end 0.4318 -0.9525)
			(stroke
				(width 0)
				(type default)
			)
			(fill no)
			(layer "F.Fab")
		)
		(pad "1" smd custom
			(at 0 -0.4445 270)
			(size 0.1524 0.1524)
			(layers "F.Cu" "F.Mask" "F.Paste")
			(net "TEMP_ALM#_IN_D")
			(options
				(clearance outline)
				(anchor circle)
			)
			(primitives
				(gr_poly
					(pts
						(arc
							(start 0.3048 -0.2032)
							(mid 0.275042 -0.275042)
							(end 0.2032 -0.3048)
						)
						(arc
							(start -0.2032 -0.3048)
							(mid -0.275042 -0.275042)
							(end -0.3048 -0.2032)
						)
						(arc
							(start -0.3048 0.2032)
							(mid -0.275042 0.275042)
							(end -0.2032 0.3048)
						)
						(arc
							(start 0.2032 0.3048)
							(mid 0.275042 0.275042)
							(end 0.3048 0.2032)
						)
					)
					(width 0)
					(fill yes)
				)
			)
		)
		(pad "2" smd custom
			(at 0 0.4445 270)
			(size 0.1524 0.1524)
			(layers "F.Cu" "F.Mask" "F.Paste")
			(net "GND")
			(options
				(clearance outline)
				(anchor circle)
			)
			(primitives
				(gr_poly
					(pts
						(arc
							(start 0.3048 -0.2032)
							(mid 0.275042 -0.275042)
							(end 0.2032 -0.3048)
						)
						(arc
							(start -0.2032 -0.3048)
							(mid -0.275042 -0.275042)
							(end -0.3048 -0.2032)
						)
						(arc
							(start -0.3048 0.2032)
							(mid -0.275042 0.275042)
							(end -0.2032 0.3048)
						)
						(arc
							(start 0.2032 0.3048)
							(mid 0.275042 0.275042)
							(end 0.3048 0.2032)
						)
					)
					(width 0)
					(fill yes)
				)
			)
		)
	)
	(footprint ""
		(layer "F.Cu")
		(at 4.040124 -372.65991 -90)
		(property "Reference" "CN2"
			(at 0 0 270)
			(layer "F.SilkS")
			(hide yes)
			(effects
				(font
					(size 1.27 1.27)
				)
			)
		)
		(property "Value" "JWT-CON5-42-GP"
			(at -7.8105 2.9591 270)
			(unlocked yes)
			(layer "F.Fab")
			(hide yes)
			(effects
				(font
					(size 1.016 1.016)
					(thickness 0.1524)
				)
			)
		)
		(property "Device Type" "A2541WR0-1TX5PA-6T-0E"
			(at -7.8105 1.4351 270)
			(unlocked yes)
			(layer "F.Fab")
			(hide yes)
			(effects
				(font
					(size 1.016 1.016)
					(thickness 0.1524)
				)
			)
		)
		(duplicate_pad_numbers_are_jumpers no)
		(fp_line
			(start -6.604 10.287)
			(end 6.604 10.287)
			(stroke
				(width 0.1524)
				(type default)
			)
			(layer "F.SilkS")
		)
		(fp_line
			(start 6.604 10.287)
			(end 6.604 -0.9652)
			(stroke
				(width 0.1524)
				(type default)
			)
			(layer "F.SilkS")
		)
		(fp_line
			(start -6.604 -0.9652)
			(end -6.604 10.287)
			(stroke
				(width 0.1524)
				(type default)
			)
			(layer "F.SilkS")
		)
		(fp_line
			(start 6.604 -0.9652)
			(end -6.604 -0.9652)
			(stroke
				(width 0.1524)
				(type default)
			)
			(layer "F.SilkS")
		)
		(fp_line
			(start -6.731 -1.0922)
			(end -6.731 0.1778)
			(stroke
				(width 0.4064)
				(type default)
			)
			(layer "F.SilkS")
		)
		(fp_line
			(start -5.461 -1.0922)
			(end -6.731 -1.0922)
			(stroke
				(width 0.4064)
				(type default)
			)
			(layer "F.SilkS")
		)
		(fp_circle
			(center -5.08 0)
			(end -5.08 -1.0668)
			(stroke
				(width 0.3048)
				(type default)
			)
			(fill no)
			(layer "F.SilkS")
		)
		(fp_circle
			(center -2.54 0)
			(end -2.54 -1.0668)
			(stroke
				(width 0.3048)
				(type default)
			)
			(fill no)
			(layer "F.SilkS")
		)
		(fp_circle
			(center 0 0)
			(end 0 -1.0668)
			(stroke
				(width 0.3048)
				(type default)
			)
			(fill no)
			(layer "F.SilkS")
		)
		(fp_circle
			(center 2.54 0)
			(end 2.54 -1.0668)
			(stroke
				(width 0.3048)
				(type default)
			)
			(fill no)
			(layer "F.SilkS")
		)
		(fp_circle
			(center 5.08 0)
			(end 5.08 -1.0668)
			(stroke
				(width 0.3048)
				(type default)
			)
			(fill no)
			(layer "F.SilkS")
		)
		(fp_rect
			(start -6.35 10.033)
			(end 6.35 -0.3302)
			(stroke
				(width 0)
				(type default)
			)
			(fill no)
			(layer "F.CrtYd")
		)
		(fp_poly
			(pts
				(xy -6.35 -0.3302) (xy 6.858 -0.3302) (xy 6.858 -1.2192) (xy -6.858 -1.2192) (xy -6.858 10.541)
				(xy 6.858 10.541) (xy 6.858 -0.3175) (xy 6.35 -0.3175) (xy 6.35 10.033) (xy -6.35 10.033)
			)
			(stroke
				(width 0)
				(type default)
			)
			(fill no)
			(layer "F.CrtYd")
		)
		(fp_rect
			(start -6.858 10.541)
			(end 6.858 -1.2192)
			(stroke
				(width 0)
				(type default)
			)
			(fill no)
			(layer "F.Fab")
		)
		(pad "1" thru_hole circle
			(at -5.08 0 270)
			(size 1.4224 1.4224)
			(drill 1.016)
			(layers "*.Cu" "*.Mask")
			(remove_unused_layers no)
			(net "GND")
			(clearance 0.1524)
			(thermal_gap 0.1524)
		)
		(pad "2" thru_hole circle
			(at -2.54 0 270)
			(size 1.4224 1.4224)
			(drill 1.016)
			(layers "*.Cu" "*.Mask")
			(remove_unused_layers no)
			(net "P12V_FAN2")
			(clearance 0.1524)
			(thermal_gap 0.1524)
		)
		(pad "3" thru_hole circle
			(at 0 0 270)
			(size 1.4224 1.4224)
			(drill 1.016)
			(layers "*.Cu" "*.Mask")
			(remove_unused_layers no)
			(net "FAN_TACH4")
			(clearance 0.1524)
			(thermal_gap 0.1524)
		)
		(pad "4" thru_hole circle
			(at 2.54 0 270)
			(size 1.4224 1.4224)
			(drill 1.016)
			(layers "*.Cu" "*.Mask")
			(remove_unused_layers no)
			(net "PWM_OUT_FAN2_NET")
			(clearance 0.1524)
			(thermal_gap 0.1524)
		)
		(pad "5" thru_hole circle
			(at 5.08 0 270)
			(size 1.4224 1.4224)
			(drill 1.016)
			(layers "*.Cu" "*.Mask")
			(remove_unused_layers no)
			(net "FAN_TACH3")
			(clearance 0.1524)
			(thermal_gap 0.1524)
		)
	)
	(footprint ""
		(layer "F.Cu")
		(at 4.897882 -78.481428)
		(property "Reference" "R113"
			(at 0 0 0)
			(layer "F.SilkS")
			(hide yes)
			(effects
				(font
					(size 1.27 1.27)
				)
			)
		)
		(property "Value" "2KR2F-3-GP"
			(at 0.064008 -3.993896 0)
			(unlocked yes)
			(layer "F.Fab")
			(hide yes)
			(effects
				(font
					(size 1.016 1.016)
					(thickness 0.1524)
				)
			)
		)
		(property "Device Type" "R402H16"
			(at 0.064008 -5.517896 0)
			(unlocked yes)
			(layer "F.Fab")
			(hide yes)
			(effects
				(font
					(size 1.016 1.016)
					(thickness 0.1524)
				)
			)
		)
		(duplicate_pad_numbers_are_jumpers no)
		(fp_line
			(start -0.508 -0.9398)
			(end -0.508 0.9398)
			(stroke
				(width 0.1524)
				(type default)
			)
			(layer "F.SilkS")
		)
		(fp_line
			(start 0.508 -0.9398)
			(end -0.508 -0.9398)
			(stroke
				(width 0.1524)
				(type default)
			)
			(layer "F.SilkS")
		)
		(fp_rect
			(start -0.508 0.9398)
			(end 0.508 -0.9398)
			(stroke
				(width 0)
				(type default)
			)
			(fill no)
			(layer "F.CrtYd")
		)
		(fp_rect
			(start -0.508 0.9398)
			(end 0.508 -0.9398)
			(stroke
				(width 0)
				(type default)
			)
			(fill no)
			(layer "F.Fab")
		)
		(pad "1" smd custom
			(at 0 -0.4445)
			(size 0.1397 0.1397)
			(layers "F.Cu" "F.Mask" "F.Paste")
			(net "LED_DR_LED4")
			(options
				(clearance outline)
				(anchor circle)
			)
			(primitives
				(gr_poly
					(pts
						(arc
							(start -0.1778 -0.2794)
							(mid -0.249642 -0.249642)
							(end -0.2794 -0.1778)
						)
						(arc
							(start -0.2794 0.1778)
							(mid -0.249642 0.249642)
							(end -0.1778 0.2794)
						)
						(arc
							(start 0.1778 0.2794)
							(mid 0.249642 0.249642)
							(end 0.2794 0.1778)
						)
						(arc
							(start 0.2794 -0.1778)
							(mid 0.249642 -0.249642)
							(end 0.1778 -0.2794)
						)
					)
					(width 0)
					(fill yes)
				)
			)
		)
		(pad "2" smd custom
			(at 0 0.4445)
			(size 0.1397 0.1397)
			(layers "F.Cu" "F.Mask" "F.Paste")
			(net "LED_DR_LED4_B")
			(options
				(clearance outline)
				(anchor circle)
			)
			(primitives
				(gr_poly
					(pts
						(arc
							(start -0.1778 -0.2794)
							(mid -0.249642 -0.249642)
							(end -0.2794 -0.1778)
						)
						(arc
							(start -0.2794 0.1778)
							(mid -0.249642 0.249642)
							(end -0.1778 0.2794)
						)
						(arc
							(start 0.1778 0.2794)
							(mid 0.249642 0.249642)
							(end 0.2794 0.1778)
						)
						(arc
							(start 0.2794 -0.1778)
							(mid 0.249642 -0.249642)
							(end 0.1778 -0.2794)
						)
					)
					(width 0)
					(fill yes)
				)
			)
		)
	)
	(footprint ""
		(layer "F.Cu")
		(at 41.0464 -138.5824 90)
		(property "Reference" "PR101"
			(at 0 0 90)
			(layer "F.SilkS")
			(hide yes)
			(effects
				(font
					(size 1.27 1.27)
				)
			)
		)
		(property "Value" "100R2F-L1-GP-U"
			(at 0.064008 -3.993896 90)
			(unlocked yes)
			(layer "F.Fab")
			(hide yes)
			(effects
				(font
					(size 1.016 1.016)
					(thickness 0.1524)
				)
			)
		)
		(property "Device Type" "R402H14"
			(at 0.064008 -5.517896 90)
			(unlocked yes)
			(layer "F.Fab")
			(hide yes)
			(effects
				(font
					(size 1.016 1.016)
					(thickness 0.1524)
				)
			)
		)
		(duplicate_pad_numbers_are_jumpers no)
		(fp_line
			(start 0.508 -0.9398)
			(end -0.508 -0.9398)
			(stroke
				(width 0.1524)
				(type default)
			)
			(layer "F.SilkS")
		)
		(fp_line
			(start -0.508 -0.9398)
			(end -0.508 0.9398)
			(stroke
				(width 0.1524)
				(type default)
			)
			(layer "F.SilkS")
		)
		(fp_rect
			(start -0.508 0.9398)
			(end 0.508 -0.9398)
			(stroke
				(width 0)
				(type default)
			)
			(fill no)
			(layer "F.CrtYd")
		)
		(fp_rect
			(start -0.508 0.9398)
			(end 0.508 -0.9398)
			(stroke
				(width 0)
				(type default)
			)
			(fill no)
			(layer "F.Fab")
		)
		(pad "1" smd custom
			(at 0 -0.4445 90)
			(size 0.1397 0.1397)
			(layers "F.Cu" "F.Mask" "F.Paste")
			(net "P12VL_2490_GATE")
			(options
				(clearance outline)
				(anchor circle)
			)
			(primitives
				(gr_poly
					(pts
						(arc
							(start -0.1778 -0.2794)
							(mid -0.249642 -0.249642)
							(end -0.2794 -0.1778)
						)
						(arc
							(start -0.2794 0.1778)
							(mid -0.249642 0.249642)
							(end -0.1778 0.2794)
						)
						(arc
							(start 0.1778 0.2794)
							(mid 0.249642 0.249642)
							(end 0.2794 0.1778)
						)
						(arc
							(start 0.2794 -0.1778)
							(mid 0.249642 -0.249642)
							(end 0.1778 -0.2794)
						)
					)
					(width 0)
					(fill yes)
				)
			)
		)
		(pad "2" smd custom
			(at 0 0.4445 90)
			(size 0.1397 0.1397)
			(layers "F.Cu" "F.Mask" "F.Paste")
			(net "P12VL_2490_RC")
			(options
				(clearance outline)
				(anchor circle)
			)
			(primitives
				(gr_poly
					(pts
						(arc
							(start -0.1778 -0.2794)
							(mid -0.249642 -0.249642)
							(end -0.2794 -0.1778)
						)
						(arc
							(start -0.2794 0.1778)
							(mid -0.249642 0.249642)
							(end -0.1778 0.2794)
						)
						(arc
							(start 0.1778 0.2794)
							(mid 0.249642 0.249642)
							(end 0.2794 0.1778)
						)
						(arc
							(start 0.2794 -0.1778)
							(mid 0.249642 -0.249642)
							(end 0.1778 -0.2794)
						)
					)
					(width 0)
					(fill yes)
				)
			)
		)
	)
	(footprint ""
		(layer "F.Cu")
		(at 39.064184 -359.41 90)
		(property "Reference" "PR58"
			(at 0 0 90)
			(layer "F.SilkS")
			(hide yes)
			(effects
				(font
					(size 1.27 1.27)
				)
			)
		)
		(property "Value" "10KR2F-2-GP"
			(at 0.064008 -3.993896 90)
			(unlocked yes)
			(layer "F.Fab")
			(hide yes)
			(effects
				(font
					(size 1.016 1.016)
					(thickness 0.1524)
				)
			)
		)
		(property "Device Type" "R402H16"
			(at 0.064008 -5.517896 90)
			(unlocked yes)
			(layer "F.Fab")
			(hide yes)
			(effects
				(font
					(size 1.016 1.016)
					(thickness 0.1524)
				)
			)
		)
		(duplicate_pad_numbers_are_jumpers no)
		(fp_line
			(start 0.508 -0.9398)
			(end -0.508 -0.9398)
			(stroke
				(width 0.1524)
				(type default)
			)
			(layer "F.SilkS")
		)
		(fp_line
			(start -0.508 -0.9398)
			(end -0.508 0.9398)
			(stroke
				(width 0.1524)
				(type default)
			)
			(layer "F.SilkS")
		)
		(fp_rect
			(start -0.508 0.9398)
			(end 0.508 -0.9398)
			(stroke
				(width 0)
				(type default)
			)
			(fill no)
			(layer "F.CrtYd")
		)
		(fp_rect
			(start -0.508 0.9398)
			(end 0.508 -0.9398)
			(stroke
				(width 0)
				(type default)
			)
			(fill no)
			(layer "F.Fab")
		)
		(pad "1" smd custom
			(at 0 -0.4445 90)
			(size 0.1397 0.1397)
			(layers "F.Cu" "F.Mask" "F.Paste")
			(net "P12V_AUX")
			(options
				(clearance outline)
				(anchor circle)
			)
			(primitives
				(gr_poly
					(pts
						(arc
							(start -0.1778 -0.2794)
							(mid -0.249642 -0.249642)
							(end -0.2794 -0.1778)
						)
						(arc
							(start -0.2794 0.1778)
							(mid -0.249642 0.249642)
							(end -0.1778 0.2794)
						)
						(arc
							(start 0.1778 0.2794)
							(mid 0.249642 0.249642)
							(end 0.2794 0.1778)
						)
						(arc
							(start 0.2794 -0.1778)
							(mid 0.249642 -0.249642)
							(end 0.1778 -0.2794)
						)
					)
					(width 0)
					(fill yes)
				)
			)
		)
		(pad "2" smd custom
			(at 0 0.4445 90)
			(size 0.1397 0.1397)
			(layers "F.Cu" "F.Mask" "F.Paste")
			(net "OTP_RETRY_C")
			(options
				(clearance outline)
				(anchor circle)
			)
			(primitives
				(gr_poly
					(pts
						(arc
							(start -0.1778 -0.2794)
							(mid -0.249642 -0.249642)
							(end -0.2794 -0.1778)
						)
						(arc
							(start -0.2794 0.1778)
							(mid -0.249642 0.249642)
							(end -0.1778 0.2794)
						)
						(arc
							(start 0.1778 0.2794)
							(mid 0.249642 0.249642)
							(end 0.2794 0.1778)
						)
						(arc
							(start 0.2794 -0.1778)
							(mid 0.249642 -0.249642)
							(end 0.1778 -0.2794)
						)
					)
					(width 0)
					(fill yes)
				)
			)
		)
	)
	(footprint ""
		(layer "F.Cu")
		(at 33.401 -363.728 -90)
		(property "Reference" "C51"
			(at 0 0 270)
			(layer "F.SilkS")
			(hide yes)
			(effects
				(font
					(size 1.27 1.27)
				)
			)
		)
		(property "Value" "SCD1U10V2KX-4-LL-GP"
			(at 1.1811 -2.7051 270)
			(unlocked yes)
			(layer "F.Fab")
			(hide yes)
			(effects
				(font
					(size 1.016 1.016)
					(thickness 0.1524)
				)
			)
		)
		(property "Device Type" "C402H22"
			(at 1.1811 -4.2291 270)
			(unlocked yes)
			(layer "F.Fab")
			(hide yes)
			(effects
				(font
					(size 1.016 1.016)
					(thickness 0.1524)
				)
			)
		)
		(duplicate_pad_numbers_are_jumpers no)
		(fp_rect
			(start -0.4318 0.9525)
			(end 0.4318 -0.9525)
			(stroke
				(width 0)
				(type default)
			)
			(fill no)
			(layer "F.CrtYd")
		)
		(fp_rect
			(start -0.4318 0.9525)
			(end 0.4318 -0.9525)
			(stroke
				(width 0)
				(type default)
			)
			(fill no)
			(layer "F.Fab")
		)
		(pad "1" smd custom
			(at 0 -0.4445 270)
			(size 0.1524 0.1524)
			(layers "F.Cu" "F.Mask" "F.Paste")
			(net "TEMP_ALM#_REVERSE_R")
			(options
				(clearance outline)
				(anchor circle)
			)
			(primitives
				(gr_poly
					(pts
						(arc
							(start 0.3048 -0.2032)
							(mid 0.275042 -0.275042)
							(end 0.2032 -0.3048)
						)
						(arc
							(start -0.2032 -0.3048)
							(mid -0.275042 -0.275042)
							(end -0.3048 -0.2032)
						)
						(arc
							(start -0.3048 0.2032)
							(mid -0.275042 0.275042)
							(end -0.2032 0.3048)
						)
						(arc
							(start 0.2032 0.3048)
							(mid 0.275042 0.275042)
							(end 0.3048 0.2032)
						)
					)
					(width 0)
					(fill yes)
				)
			)
		)
		(pad "2" smd custom
			(at 0 0.4445 270)
			(size 0.1524 0.1524)
			(layers "F.Cu" "F.Mask" "F.Paste")
			(net "GND")
			(options
				(clearance outline)
				(anchor circle)
			)
			(primitives
				(gr_poly
					(pts
						(arc
							(start 0.3048 -0.2032)
							(mid 0.275042 -0.275042)
							(end 0.2032 -0.3048)
						)
						(arc
							(start -0.2032 -0.3048)
							(mid -0.275042 -0.275042)
							(end -0.3048 -0.2032)
						)
						(arc
							(start -0.3048 0.2032)
							(mid -0.275042 0.275042)
							(end -0.2032 0.3048)
						)
						(arc
							(start 0.2032 0.3048)
							(mid 0.275042 0.275042)
							(end 0.3048 0.2032)
						)
					)
					(width 0)
					(fill yes)
				)
			)
		)
	)
	(footprint ""
		(layer "F.Cu")
		(at 21.844 -376.936 90)
		(property "Reference" "PR34"
			(at 0 0 90)
			(layer "F.SilkS")
			(hide yes)
			(effects
				(font
					(size 1.27 1.27)
				)
			)
		)
		(property "Value" "51KR2F-L-GP"
			(at 0.064008 -3.993896 90)
			(unlocked yes)
			(layer "F.Fab")
			(hide yes)
			(effects
				(font
					(size 1.016 1.016)
					(thickness 0.1524)
				)
			)
		)
		(property "Device Type" "R402H16"
			(at 0.064008 -5.517896 90)
			(unlocked yes)
			(layer "F.Fab")
			(hide yes)
			(effects
				(font
					(size 1.016 1.016)
					(thickness 0.1524)
				)
			)
		)
		(duplicate_pad_numbers_are_jumpers no)
		(fp_line
			(start 0.508 -0.9398)
			(end -0.508 -0.9398)
			(stroke
				(width 0.1524)
				(type default)
			)
			(layer "F.SilkS")
		)
		(fp_line
			(start -0.508 -0.9398)
			(end -0.508 0.9398)
			(stroke
				(width 0.1524)
				(type default)
			)
			(layer "F.SilkS")
		)
		(fp_rect
			(start -0.508 0.9398)
			(end 0.508 -0.9398)
			(stroke
				(width 0)
				(type default)
			)
			(fill no)
			(layer "F.CrtYd")
		)
		(fp_rect
			(start -0.508 0.9398)
			(end 0.508 -0.9398)
			(stroke
				(width 0)
				(type default)
			)
			(fill no)
			(layer "F.Fab")
		)
		(pad "1" smd custom
			(at 0 -0.4445 90)
			(size 0.1397 0.1397)
			(layers "F.Cu" "F.Mask" "F.Paste")
			(net "P12V_AUX")
			(options
				(clearance outline)
				(anchor circle)
			)
			(primitives
				(gr_poly
					(pts
						(arc
							(start -0.1778 -0.2794)
							(mid -0.249642 -0.249642)
							(end -0.2794 -0.1778)
						)
						(arc
							(start -0.2794 0.1778)
							(mid -0.249642 0.249642)
							(end -0.1778 0.2794)
						)
						(arc
							(start 0.1778 0.2794)
							(mid 0.249642 0.249642)
							(end 0.2794 0.1778)
						)
						(arc
							(start 0.2794 -0.1778)
							(mid 0.249642 -0.249642)
							(end 0.1778 -0.2794)
						)
					)
					(width 0)
					(fill yes)
				)
			)
		)
		(pad "2" smd custom
			(at 0 0.4445 90)
			(size 0.1397 0.1397)
			(layers "F.Cu" "F.Mask" "F.Paste")
			(net "ADM1276_UV")
			(options
				(clearance outline)
				(anchor circle)
			)
			(primitives
				(gr_poly
					(pts
						(arc
							(start -0.1778 -0.2794)
							(mid -0.249642 -0.249642)
							(end -0.2794 -0.1778)
						)
						(arc
							(start -0.2794 0.1778)
							(mid -0.249642 0.249642)
							(end -0.1778 0.2794)
						)
						(arc
							(start 0.1778 0.2794)
							(mid 0.249642 0.249642)
							(end 0.2794 0.1778)
						)
						(arc
							(start 0.2794 -0.1778)
							(mid 0.249642 -0.249642)
							(end 0.1778 -0.2794)
						)
					)
					(width 0)
					(fill yes)
				)
			)
		)
	)
	(footprint ""
		(layer "F.Cu")
		(at 37.17671 -154.818334)
		(property "Reference" "C2"
			(at 0 0 0)
			(layer "F.SilkS")
			(hide yes)
			(effects
				(font
					(size 1.27 1.27)
				)
			)
		)
		(property "Value" "SCD1U16V2KX-3GP"
			(at 1.1811 -2.7051 0)
			(unlocked yes)
			(layer "F.Fab")
			(hide yes)
			(effects
				(font
					(size 1.016 1.016)
					(thickness 0.1524)
				)
			)
		)
		(property "Device Type" "C402H22"
			(at 1.1811 -4.2291 0)
			(unlocked yes)
			(layer "F.Fab")
			(hide yes)
			(effects
				(font
					(size 1.016 1.016)
					(thickness 0.1524)
				)
			)
		)
		(duplicate_pad_numbers_are_jumpers no)
		(fp_rect
			(start -0.4318 0.9525)
			(end 0.4318 -0.9525)
			(stroke
				(width 0)
				(type default)
			)
			(fill no)
			(layer "F.CrtYd")
		)
		(fp_rect
			(start -0.4318 0.9525)
			(end 0.4318 -0.9525)
			(stroke
				(width 0)
				(type default)
			)
			(fill no)
			(layer "F.Fab")
		)
		(pad "1" smd custom
			(at 0 -0.4445)
			(size 0.1524 0.1524)
			(layers "F.Cu" "F.Mask" "F.Paste")
			(net "NCT7904_3VDD")
			(options
				(clearance outline)
				(anchor circle)
			)
			(primitives
				(gr_poly
					(pts
						(arc
							(start 0.3048 -0.2032)
							(mid 0.275042 -0.275042)
							(end 0.2032 -0.3048)
						)
						(arc
							(start -0.2032 -0.3048)
							(mid -0.275042 -0.275042)
							(end -0.3048 -0.2032)
						)
						(arc
							(start -0.3048 0.2032)
							(mid -0.275042 0.275042)
							(end -0.2032 0.3048)
						)
						(arc
							(start 0.2032 0.3048)
							(mid 0.275042 0.275042)
							(end 0.3048 0.2032)
						)
					)
					(width 0)
					(fill yes)
				)
			)
		)
		(pad "2" smd custom
			(at 0 0.4445)
			(size 0.1524 0.1524)
			(layers "F.Cu" "F.Mask" "F.Paste")
			(net "GND")
			(options
				(clearance outline)
				(anchor circle)
			)
			(primitives
				(gr_poly
					(pts
						(arc
							(start 0.3048 -0.2032)
							(mid 0.275042 -0.275042)
							(end 0.2032 -0.3048)
						)
						(arc
							(start -0.2032 -0.3048)
							(mid -0.275042 -0.275042)
							(end -0.3048 -0.2032)
						)
						(arc
							(start -0.3048 0.2032)
							(mid -0.275042 0.275042)
							(end -0.2032 0.3048)
						)
						(arc
							(start 0.2032 0.3048)
							(mid 0.275042 0.275042)
							(end 0.3048 0.2032)
						)
					)
					(width 0)
					(fill yes)
				)
			)
		)
	)
	(footprint ""
		(layer "F.Cu")
		(at 34.925 -366.268)
		(property "Reference" "PR38"
			(at 0 0 0)
			(layer "F.SilkS")
			(hide yes)
			(effects
				(font
					(size 1.27 1.27)
				)
			)
		)
		(property "Value" "1KR2F-3-GP"
			(at 0.064008 -3.993896 0)
			(unlocked yes)
			(layer "F.Fab")
			(hide yes)
			(effects
				(font
					(size 1.016 1.016)
					(thickness 0.1524)
				)
			)
		)
		(property "Device Type" "R402H16"
			(at 0.064008 -5.517896 0)
			(unlocked yes)
			(layer "F.Fab")
			(hide yes)
			(effects
				(font
					(size 1.016 1.016)
					(thickness 0.1524)
				)
			)
		)
		(duplicate_pad_numbers_are_jumpers no)
		(fp_line
			(start -0.508 -0.9398)
			(end -0.508 0.9398)
			(stroke
				(width 0.1524)
				(type default)
			)
			(layer "F.SilkS")
		)
		(fp_line
			(start 0.508 -0.9398)
			(end -0.508 -0.9398)
			(stroke
				(width 0.1524)
				(type default)
			)
			(layer "F.SilkS")
		)
		(fp_rect
			(start -0.508 0.9398)
			(end 0.508 -0.9398)
			(stroke
				(width 0)
				(type default)
			)
			(fill no)
			(layer "F.CrtYd")
		)
		(fp_rect
			(start -0.508 0.9398)
			(end 0.508 -0.9398)
			(stroke
				(width 0)
				(type default)
			)
			(fill no)
			(layer "F.Fab")
		)
		(pad "1" smd custom
			(at 0 -0.4445)
			(size 0.1397 0.1397)
			(layers "F.Cu" "F.Mask" "F.Paste")
			(net "ADM1276_EN_NET")
			(options
				(clearance outline)
				(anchor circle)
			)
			(primitives
				(gr_poly
					(pts
						(arc
							(start -0.1778 -0.2794)
							(mid -0.249642 -0.249642)
							(end -0.2794 -0.1778)
						)
						(arc
							(start -0.2794 0.1778)
							(mid -0.249642 0.249642)
							(end -0.1778 0.2794)
						)
						(arc
							(start 0.1778 0.2794)
							(mid 0.249642 0.249642)
							(end 0.2794 0.1778)
						)
						(arc
							(start 0.2794 -0.1778)
							(mid 0.249642 -0.249642)
							(end 0.1778 -0.2794)
						)
					)
					(width 0)
					(fill yes)
				)
			)
		)
		(pad "2" smd custom
			(at 0 0.4445)
			(size 0.1397 0.1397)
			(layers "F.Cu" "F.Mask" "F.Paste")
			(net "ADM1276_EN")
			(options
				(clearance outline)
				(anchor circle)
			)
			(primitives
				(gr_poly
					(pts
						(arc
							(start -0.1778 -0.2794)
							(mid -0.249642 -0.249642)
							(end -0.2794 -0.1778)
						)
						(arc
							(start -0.2794 0.1778)
							(mid -0.249642 0.249642)
							(end -0.1778 0.2794)
						)
						(arc
							(start 0.1778 0.2794)
							(mid 0.249642 0.249642)
							(end 0.2794 0.1778)
						)
						(arc
							(start 0.2794 -0.1778)
							(mid 0.249642 -0.249642)
							(end 0.1778 -0.2794)
						)
					)
					(width 0)
					(fill yes)
				)
			)
		)
	)
	(footprint ""
		(layer "F.Cu")
		(at 7.949946 -232.134918 -90)
		(property "Reference" "LED4"
			(at 0 0 270)
			(layer "F.SilkS")
			(hide yes)
			(effects
				(font
					(size 1.27 1.27)
				)
			)
		)
		(property "Value" "LED-RB-6-GP"
			(at -4.6736 3.8354 270)
			(unlocked yes)
			(layer "F.Fab")
			(hide yes)
			(effects
				(font
					(size 1.016 1.016)
					(thickness 0.1524)
				)
			)
		)
		(property "Device Type" "LED-100-3P-067106H325"
			(at -4.6736 2.3114 270)
			(unlocked yes)
			(layer "F.Fab")
			(hide yes)
			(effects
				(font
					(size 1.016 1.016)
					(thickness 0.1524)
				)
			)
		)
		(duplicate_pad_numbers_are_jumpers no)
		(fp_line
			(start -1.7526 10.414)
			(end -1.7526 6.6548)
			(stroke
				(width 0.1524)
				(type default)
			)
			(layer "F.SilkS")
		)
		(fp_line
			(start 1.7526 10.414)
			(end -1.7526 10.414)
			(stroke
				(width 0.1524)
				(type default)
			)
			(layer "F.SilkS")
		)
		(fp_line
			(start -3.6068 6.6548)
			(end -3.6068 -0.889)
			(stroke
				(width 0.1524)
				(type default)
			)
			(layer "F.SilkS")
		)
		(fp_line
			(start -1.7526 6.6548)
			(end -3.6068 6.6548)
			(stroke
				(width 0.1524)
				(type default)
			)
			(layer "F.SilkS")
		)
		(fp_line
			(start 1.7526 6.6548)
			(end 1.7526 10.414)
			(stroke
				(width 0.1524)
				(type default)
			)
			(layer "F.SilkS")
		)
		(fp_line
			(start 3.6068 6.6548)
			(end 1.7526 6.6548)
			(stroke
				(width 0.1524)
				(type default)
			)
			(layer "F.SilkS")
		)
		(fp_line
			(start -3.6068 -0.889)
			(end 3.6068 -0.889)
			(stroke
				(width 0.1524)
				(type default)
			)
			(layer "F.SilkS")
		)
		(fp_line
			(start 3.6068 -0.889)
			(end 3.6068 6.6548)
			(stroke
				(width 0.1524)
				(type default)
			)
			(layer "F.SilkS")
		)
		(fp_circle
			(center -2.54 0)
			(end -2.54 -0.9906)
			(stroke
				(width 0.3048)
				(type default)
			)
			(fill no)
			(layer "F.SilkS")
		)
		(fp_circle
			(center 0 0)
			(end 0 -0.9906)
			(stroke
				(width 0.3048)
				(type default)
			)
			(fill no)
			(layer "F.SilkS")
		)
		(fp_circle
			(center 2.54 0)
			(end 2.54 -0.9906)
			(stroke
				(width 0.3048)
				(type default)
			)
			(fill no)
			(layer "F.SilkS")
		)
		(fp_poly
			(pts
				(xy -1.4986 10.1473) (xy -1.4986 6.4008) (xy -3.3528 6.4008) (xy -3.3528 -0.3937) (xy 3.3528 -0.3937)
				(xy 3.3528 6.4008) (xy 1.4986 6.4008) (xy 1.4986 10.1473)
			)
			(stroke
				(width 0)
				(type default)
			)
			(fill no)
			(layer "F.CrtYd")
		)
		(fp_poly
			(pts
				(xy -2.0066 10.668) (xy 2.0066 10.668) (xy 2.0066 6.9088) (xy 3.8608 6.9088) (xy 3.8608 2.2098)
				(xy 3.3528 2.2098) (xy 3.3528 6.4008) (xy 1.4986 6.4008) (xy 1.4986 10.1473) (xy -1.4986 10.1473)
				(xy -1.4986 6.4008) (xy -3.3528 6.4008) (xy -3.3528 -0.3937) (xy 3.3528 -0.3937) (xy 3.3528 2.1971)
				(xy 3.8608 2.1971) (xy 3.8608 -1.143) (xy -3.8608 -1.143) (xy -3.8608 6.9088) (xy -2.0066 6.9088)
			)
			(stroke
				(width 0)
				(type default)
			)
			(fill no)
			(layer "F.CrtYd")
		)
		(fp_poly
			(pts
				(xy -2.0066 10.668) (xy -2.0066 6.9088) (xy -3.8608 6.9088) (xy -3.8608 -1.143) (xy 3.8608 -1.143)
				(xy 3.8608 6.9088) (xy 2.0066 6.9088) (xy 2.0066 10.668)
			)
			(stroke
				(width 0)
				(type default)
			)
			(fill no)
			(layer "F.Fab")
		)
		(pad "1" thru_hole circle
			(at 2.54 0 270)
			(size 1.27 1.27)
			(drill 0.889)
			(layers "*.Cu" "*.Mask")
			(remove_unused_layers no)
			(net "LED_DR_LED3_BLUE")
			(clearance 0.1651)
			(thermal_gap 0.1651)
		)
		(pad "2" thru_hole circle
			(at 0 0 270)
			(size 1.27 1.27)
			(drill 0.889)
			(layers "*.Cu" "*.Mask")
			(remove_unused_layers no)
			(net "LED_DR_LED3_K")
			(clearance 0.1651)
			(thermal_gap 0.1651)
		)
		(pad "3" thru_hole circle
			(at -2.54 0 270)
			(size 1.27 1.27)
			(drill 0.889)
			(layers "*.Cu" "*.Mask")
			(remove_unused_layers no)
			(net "LED_DR_LED3")
			(clearance 0.1651)
			(thermal_gap 0.1651)
		)
	)
	(footprint ""
		(layer "F.Cu")
		(at 14.8082 -66.4464 180)
		(property "Reference" "R150"
			(at 0 0 180)
			(layer "F.SilkS")
			(hide yes)
			(effects
				(font
					(size 1.27 1.27)
				)
			)
		)
		(property "Value" "10R2F-L-GP"
			(at 0.064008 -3.993896 180)
			(unlocked yes)
			(layer "F.Fab")
			(hide yes)
			(effects
				(font
					(size 1.016 1.016)
					(thickness 0.1524)
				)
			)
		)
		(property "Device Type" "R402H14"
			(at 0.064008 -5.517896 180)
			(unlocked yes)
			(layer "F.Fab")
			(hide yes)
			(effects
				(font
					(size 1.016 1.016)
					(thickness 0.1524)
				)
			)
		)
		(duplicate_pad_numbers_are_jumpers no)
		(fp_line
			(start 0.508 -0.9398)
			(end -0.508 -0.9398)
			(stroke
				(width 0.1524)
				(type default)
			)
			(layer "F.SilkS")
		)
		(fp_line
			(start -0.508 -0.9398)
			(end -0.508 0.9398)
			(stroke
				(width 0.1524)
				(type default)
			)
			(layer "F.SilkS")
		)
		(fp_rect
			(start -0.508 0.9398)
			(end 0.508 -0.9398)
			(stroke
				(width 0)
				(type default)
			)
			(fill no)
			(layer "F.CrtYd")
		)
		(fp_rect
			(start -0.508 0.9398)
			(end 0.508 -0.9398)
			(stroke
				(width 0)
				(type default)
			)
			(fill no)
			(layer "F.Fab")
		)
		(pad "1" smd custom
			(at 0 -0.4445 180)
			(size 0.1397 0.1397)
			(layers "F.Cu" "F.Mask" "F.Paste")
			(net "I2C_C_SDA_CONN_R")
			(options
				(clearance outline)
				(anchor circle)
			)
			(primitives
				(gr_poly
					(pts
						(arc
							(start -0.1778 -0.2794)
							(mid -0.249642 -0.249642)
							(end -0.2794 -0.1778)
						)
						(arc
							(start -0.2794 0.1778)
							(mid -0.249642 0.249642)
							(end -0.1778 0.2794)
						)
						(arc
							(start 0.1778 0.2794)
							(mid 0.249642 0.249642)
							(end 0.2794 0.1778)
						)
						(arc
							(start 0.2794 -0.1778)
							(mid 0.249642 -0.249642)
							(end 0.1778 -0.2794)
						)
					)
					(width 0)
					(fill yes)
				)
			)
		)
		(pad "2" smd custom
			(at 0 0.4445 180)
			(size 0.1397 0.1397)
			(layers "F.Cu" "F.Mask" "F.Paste")
			(net "I2C_C_SDA")
			(options
				(clearance outline)
				(anchor circle)
			)
			(primitives
				(gr_poly
					(pts
						(arc
							(start -0.1778 -0.2794)
							(mid -0.249642 -0.249642)
							(end -0.2794 -0.1778)
						)
						(arc
							(start -0.2794 0.1778)
							(mid -0.249642 0.249642)
							(end -0.1778 0.2794)
						)
						(arc
							(start 0.1778 0.2794)
							(mid 0.249642 0.249642)
							(end 0.2794 0.1778)
						)
						(arc
							(start 0.2794 -0.1778)
							(mid 0.249642 -0.249642)
							(end 0.1778 -0.2794)
						)
					)
					(width 0)
					(fill yes)
				)
			)
		)
	)
	(footprint ""
		(layer "F.Cu")
		(at 41.529 -252.984)
		(property "Reference" "R149"
			(at 0 0 0)
			(layer "F.SilkS")
			(hide yes)
			(effects
				(font
					(size 1.27 1.27)
				)
			)
		)
		(property "Value" "330R2J-3-GP"
			(at 0.064008 -3.993896 0)
			(unlocked yes)
			(layer "F.Fab")
			(hide yes)
			(effects
				(font
					(size 1.016 1.016)
					(thickness 0.1524)
				)
			)
		)
		(property "Device Type" "R402H16"
			(at 0.064008 -5.517896 0)
			(unlocked yes)
			(layer "F.Fab")
			(hide yes)
			(effects
				(font
					(size 1.016 1.016)
					(thickness 0.1524)
				)
			)
		)
		(duplicate_pad_numbers_are_jumpers no)
		(fp_line
			(start -0.508 -0.9398)
			(end -0.508 0.9398)
			(stroke
				(width 0.1524)
				(type default)
			)
			(layer "F.SilkS")
		)
		(fp_line
			(start 0.508 -0.9398)
			(end -0.508 -0.9398)
			(stroke
				(width 0.1524)
				(type default)
			)
			(layer "F.SilkS")
		)
		(fp_rect
			(start -0.508 0.9398)
			(end 0.508 -0.9398)
			(stroke
				(width 0)
				(type default)
			)
			(fill no)
			(layer "F.CrtYd")
		)
		(fp_rect
			(start -0.508 0.9398)
			(end 0.508 -0.9398)
			(stroke
				(width 0)
				(type default)
			)
			(fill no)
			(layer "F.Fab")
		)
		(pad "1" smd custom
			(at 0 -0.4445)
			(size 0.1397 0.1397)
			(layers "F.Cu" "F.Mask" "F.Paste")
			(net "P3V3")
			(options
				(clearance outline)
				(anchor circle)
			)
			(primitives
				(gr_poly
					(pts
						(arc
							(start -0.1778 -0.2794)
							(mid -0.249642 -0.249642)
							(end -0.2794 -0.1778)
						)
						(arc
							(start -0.2794 0.1778)
							(mid -0.249642 0.249642)
							(end -0.1778 0.2794)
						)
						(arc
							(start 0.1778 0.2794)
							(mid 0.249642 0.249642)
							(end 0.2794 0.1778)
						)
						(arc
							(start 0.2794 -0.1778)
							(mid 0.249642 -0.249642)
							(end 0.1778 -0.2794)
						)
					)
					(width 0)
					(fill yes)
				)
			)
		)
		(pad "2" smd custom
			(at 0 0.4445)
			(size 0.1397 0.1397)
			(layers "F.Cu" "F.Mask" "F.Paste")
			(net "LED_DR_LED4")
			(options
				(clearance outline)
				(anchor circle)
			)
			(primitives
				(gr_poly
					(pts
						(arc
							(start -0.1778 -0.2794)
							(mid -0.249642 -0.249642)
							(end -0.2794 -0.1778)
						)
						(arc
							(start -0.2794 0.1778)
							(mid -0.249642 0.249642)
							(end -0.1778 0.2794)
						)
						(arc
							(start 0.1778 0.2794)
							(mid 0.249642 0.249642)
							(end 0.2794 0.1778)
						)
						(arc
							(start 0.2794 -0.1778)
							(mid 0.249642 -0.249642)
							(end 0.1778 -0.2794)
						)
					)
					(width 0)
					(fill yes)
				)
			)
		)
	)
	(footprint ""
		(layer "F.Cu")
		(at 20.675092 -288.278062 180)
		(property "Reference" "R99"
			(at 0 0 180)
			(layer "F.SilkS")
			(hide yes)
			(effects
				(font
					(size 1.27 1.27)
				)
			)
		)
		(property "Value" "27KR3F-GP"
			(at -0.0254 -2.5146 180)
			(unlocked yes)
			(layer "F.Fab")
			(hide yes)
			(effects
				(font
					(size 1.016 1.016)
					(thickness 0.1524)
				)
			)
		)
		(property "Device Type" "R603H22"
			(at -0.0254 -4.0386 180)
			(unlocked yes)
			(layer "F.Fab")
			(hide yes)
			(effects
				(font
					(size 1.016 1.016)
					(thickness 0.1524)
				)
			)
		)
		(duplicate_pad_numbers_are_jumpers no)
		(fp_line
			(start 0.2032 0)
			(end 0.4826 0)
			(stroke
				(width 0.2032)
				(type default)
			)
			(layer "F.SilkS")
		)
		(fp_line
			(start -0.4826 0)
			(end -0.2032 0)
			(stroke
				(width 0.2032)
				(type default)
			)
			(layer "F.SilkS")
		)
		(fp_rect
			(start -0.5842 1.3335)
			(end 0.5842 -1.3335)
			(stroke
				(width 0)
				(type default)
			)
			(fill no)
			(layer "F.CrtYd")
		)
		(fp_rect
			(start -0.5842 1.3335)
			(end 0.5842 -1.3335)
			(stroke
				(width 0)
				(type default)
			)
			(fill no)
			(layer "F.Fab")
		)
		(pad "1" smd custom
			(at 0 -0.762 180)
			(size 0.2159 0.2159)
			(layers "F.Cu" "F.Mask" "F.Paste")
			(net "FAN_TACH4")
			(options
				(clearance outline)
				(anchor circle)
			)
			(primitives
				(gr_poly
					(pts
						(arc
							(start -0.3302 -0.4318)
							(mid -0.402042 -0.402042)
							(end -0.4318 -0.3302)
						)
						(arc
							(start -0.4318 0.3302)
							(mid -0.402042 0.402042)
							(end -0.3302 0.4318)
						)
						(arc
							(start 0.3302 0.4318)
							(mid 0.402042 0.402042)
							(end 0.4318 0.3302)
						)
						(arc
							(start 0.4318 -0.3302)
							(mid 0.402042 -0.402042)
							(end 0.3302 -0.4318)
						)
					)
					(width 0)
					(fill yes)
				)
			)
		)
		(pad "2" smd custom
			(at 0 0.762 180)
			(size 0.2159 0.2159)
			(layers "F.Cu" "F.Mask" "F.Paste")
			(net "FANIN_4")
			(options
				(clearance outline)
				(anchor circle)
			)
			(primitives
				(gr_poly
					(pts
						(arc
							(start -0.3302 -0.4318)
							(mid -0.402042 -0.402042)
							(end -0.4318 -0.3302)
						)
						(arc
							(start -0.4318 0.3302)
							(mid -0.402042 0.402042)
							(end -0.3302 0.4318)
						)
						(arc
							(start 0.3302 0.4318)
							(mid 0.402042 0.402042)
							(end 0.4318 0.3302)
						)
						(arc
							(start 0.4318 -0.3302)
							(mid 0.402042 -0.402042)
							(end 0.3302 -0.4318)
						)
					)
					(width 0)
					(fill yes)
				)
			)
		)
	)
	(footprint ""
		(layer "F.Cu")
		(at 23.749 -101.219 90)
		(property "Reference" "TC4"
			(at 0 0 90)
			(layer "F.SilkS")
			(hide yes)
			(effects
				(font
					(size 1.27 1.27)
				)
			)
		)
		(property "Value" "ST15U25VDM-1-GP"
			(at 0 -9.6012 90)
			(unlocked yes)
			(layer "F.Fab")
			(hide yes)
			(effects
				(font
					(size 1.016 1.016)
					(thickness 0.1524)
				)
			)
		)
		(property "Device Type" "CT7343H79"
			(at 0 -11.1252 90)
			(unlocked yes)
			(layer "F.Fab")
			(hide yes)
			(effects
				(font
					(size 1.016 1.016)
					(thickness 0.1524)
				)
			)
		)
		(duplicate_pad_numbers_are_jumpers no)
		(fp_line
			(start 2.286 -4.8768)
			(end -2.286 -4.8768)
			(stroke
				(width 0.1524)
				(type default)
			)
			(layer "F.SilkS")
		)
		(fp_line
			(start -2.286 -4.8768)
			(end -2.286 -2.032)
			(stroke
				(width 0.1524)
				(type default)
			)
			(layer "F.SilkS")
		)
		(fp_line
			(start 2.1082 -4.699)
			(end -2.1082 -4.699)
			(stroke
				(width 0.508)
				(type default)
			)
			(layer "F.SilkS")
		)
		(fp_line
			(start 2.286 -2.032)
			(end 2.286 -4.8768)
			(stroke
				(width 0.1524)
				(type default)
			)
			(layer "F.SilkS")
		)
		(fp_line
			(start 2.286 2.032)
			(end 2.286 4.8768)
			(stroke
				(width 0.1524)
				(type default)
			)
			(layer "F.SilkS")
		)
		(fp_line
			(start 2.286 4.8768)
			(end -2.286 4.8768)
			(stroke
				(width 0.1524)
				(type default)
			)
			(layer "F.SilkS")
		)
		(fp_line
			(start -2.286 4.8768)
			(end -2.286 2.032)
			(stroke
				(width 0.1524)
				(type default)
			)
			(layer "F.SilkS")
		)
		(fp_rect
			(start -2.1463 3.6449)
			(end 2.1463 -3.6449)
			(stroke
				(width 0)
				(type default)
			)
			(fill no)
			(layer "F.CrtYd")
		)
		(fp_poly
			(pts
				(xy -2.54 4.953) (xy -2.54 4.2926) (xy -3.81 4.2926) (xy -3.81 -4.2926) (xy -2.54 -4.2926) (xy -2.54 -4.953)
				(xy 2.54 -4.953) (xy 2.54 -4.2926) (xy 3.81 -4.2926) (xy 3.81 -1.6256) (xy 2.1463 -1.6256) (xy 2.1463 -3.6449)
				(xy -2.1463 -3.6449) (xy -2.1463 3.6449) (xy 2.1463 3.6449) (xy 2.1463 -1.6129) (xy 3.81 -1.6129)
				(xy 3.81 4.2926) (xy 2.54 4.2926) (xy 2.54 4.953)
			)
			(stroke
				(width 0)
				(type default)
			)
			(fill no)
			(layer "F.CrtYd")
		)
		(fp_rect
			(start 2.54 4.2926)
			(end 3.81 -4.2926)
			(stroke
				(width 0)
				(type default)
			)
			(fill no)
			(layer "F.Fab")
		)
		(fp_rect
			(start -3.81 4.2926)
			(end -2.54 -4.2926)
			(stroke
				(width 0)
				(type default)
			)
			(fill no)
			(layer "F.Fab")
		)
		(fp_rect
			(start -2.54 4.953)
			(end 2.54 -4.953)
			(stroke
				(width 0)
				(type default)
			)
			(fill no)
			(layer "F.Fab")
		)
		(pad "1" smd rect
			(at 0 -3.1496 90)
			(size 2.413 2.286)
			(layers "F.Cu" "F.Mask" "F.Paste")
			(net "P12VU")
		)
		(pad "2" smd rect
			(at 0 3.1496 90)
			(size 2.413 2.286)
			(layers "F.Cu" "F.Mask" "F.Paste")
			(net "GND")
		)
		(zone
			(layer "F.Cu")
			(hatch none 0.5)
			(connect_pads
				(clearance 0)
			)
			(min_thickness 0.25)
			(keepout
				(tracks allowed)
				(vias not_allowed)
				(pads allowed)
				(copperpour not_allowed)
				(footprints allowed)
			)
			(placement
				(enabled no)
				(sheetname "")
			)
			(fill
				(thermal_gap 0.5)
				(thermal_bridge_width 0.5)
				(island_removal_mode 0)
			)
			(polygon
				(pts
					(xy 22.0599 -102.7303) (xy 19.1516 -102.7303) (xy 19.1516 -99.7077) (xy 22.0472 -99.7077) (xy 22.3774 -99.7077)
					(xy 22.3774 -102.7303)
				)
			)
		)
		(zone
			(layer "F.Cu")
			(hatch none 0.5)
			(connect_pads
				(clearance 0)
			)
			(min_thickness 0.25)
			(keepout
				(tracks allowed)
				(vias not_allowed)
				(pads allowed)
				(copperpour not_allowed)
				(footprints allowed)
			)
			(placement
				(enabled no)
				(sheetname "")
			)
			(fill
				(thermal_gap 0.5)
				(thermal_bridge_width 0.5)
				(island_removal_mode 0)
			)
			(polygon
				(pts
					(xy 28.3464 -99.7077) (xy 28.3464 -102.7303) (xy 25.4508 -102.7303) (xy 25.1206 -102.7303) (xy 25.1206 -99.7077)
					(xy 25.4508 -99.7077)
				)
			)
		)
	)
	(footprint ""
		(layer "F.Cu")
		(at 13.6652 -256.8702)
		(property "Reference" "C38"
			(at 0 0 0)
			(layer "F.SilkS")
			(hide yes)
			(effects
				(font
					(size 1.27 1.27)
				)
			)
		)
		(property "Value" "SCD1U16V2KX-3GP"
			(at 1.1811 -2.7051 0)
			(unlocked yes)
			(layer "F.Fab")
			(hide yes)
			(effects
				(font
					(size 1.016 1.016)
					(thickness 0.1524)
				)
			)
		)
		(property "Device Type" "C402H22"
			(at 1.1811 -4.2291 0)
			(unlocked yes)
			(layer "F.Fab")
			(hide yes)
			(effects
				(font
					(size 1.016 1.016)
					(thickness 0.1524)
				)
			)
		)
		(duplicate_pad_numbers_are_jumpers no)
		(fp_rect
			(start -0.4318 0.9525)
			(end 0.4318 -0.9525)
			(stroke
				(width 0)
				(type default)
			)
			(fill no)
			(layer "F.CrtYd")
		)
		(fp_rect
			(start -0.4318 0.9525)
			(end 0.4318 -0.9525)
			(stroke
				(width 0)
				(type default)
			)
			(fill no)
			(layer "F.Fab")
		)
		(pad "1" smd custom
			(at 0 -0.4445)
			(size 0.1524 0.1524)
			(layers "F.Cu" "F.Mask" "F.Paste")
			(net "FAN_TACH5")
			(options
				(clearance outline)
				(anchor circle)
			)
			(primitives
				(gr_poly
					(pts
						(arc
							(start 0.3048 -0.2032)
							(mid 0.275042 -0.275042)
							(end 0.2032 -0.3048)
						)
						(arc
							(start -0.2032 -0.3048)
							(mid -0.275042 -0.275042)
							(end -0.3048 -0.2032)
						)
						(arc
							(start -0.3048 0.2032)
							(mid -0.275042 0.275042)
							(end -0.2032 0.3048)
						)
						(arc
							(start 0.2032 0.3048)
							(mid 0.275042 0.275042)
							(end 0.3048 0.2032)
						)
					)
					(width 0)
					(fill yes)
				)
			)
		)
		(pad "2" smd custom
			(at 0 0.4445)
			(size 0.1524 0.1524)
			(layers "F.Cu" "F.Mask" "F.Paste")
			(net "GND")
			(options
				(clearance outline)
				(anchor circle)
			)
			(primitives
				(gr_poly
					(pts
						(arc
							(start 0.3048 -0.2032)
							(mid 0.275042 -0.275042)
							(end 0.2032 -0.3048)
						)
						(arc
							(start -0.2032 -0.3048)
							(mid -0.275042 -0.275042)
							(end -0.3048 -0.2032)
						)
						(arc
							(start -0.3048 0.2032)
							(mid -0.275042 0.275042)
							(end -0.2032 0.3048)
						)
						(arc
							(start 0.2032 0.3048)
							(mid 0.275042 0.275042)
							(end 0.3048 0.2032)
						)
					)
					(width 0)
					(fill yes)
				)
			)
		)
	)
	(footprint ""
		(layer "F.Cu")
		(at 38.361366 -159.40151 90)
		(property "Reference" "TP15"
			(at 0 0 90)
			(layer "F.SilkS")
			(hide yes)
			(effects
				(font
					(size 1.27 1.27)
				)
			)
		)
		(property "Value" "TPAD32-GP"
			(at 0 -3.166364 90)
			(unlocked yes)
			(layer "F.Fab")
			(hide yes)
			(effects
				(font
					(size 1.016 1.016)
					(thickness 0.1524)
				)
			)
		)
		(property "Device Type" "TPAD32"
			(at 0 -4.690618 90)
			(unlocked yes)
			(layer "F.Fab")
			(hide yes)
			(effects
				(font
					(size 1.016 1.016)
					(thickness 0.1524)
				)
			)
		)
		(duplicate_pad_numbers_are_jumpers no)
		(fp_poly
			(pts
				(arc
					(start 0 0.7112)
					(mid 0 -0.7112)
					(end 0 0.7112)
				)
			)
			(stroke
				(width 0)
				(type default)
			)
			(fill no)
			(layer "F.CrtYd")
		)
		(fp_poly
			(pts
				(arc
					(start 0 0.7112)
					(mid 0 -0.7112)
					(end 0 0.7112)
				)
			)
			(stroke
				(width 0)
				(type default)
			)
			(fill no)
			(layer "F.Fab")
		)
		(pad "1" smd circle
			(at 0 0 90)
			(size 0.8128 0.8128)
			(layers "F.Cu" "F.Mask" "F.Paste")
			(net "NCT7904_THERMTRIP")
		)
	)
	(footprint ""
		(layer "F.Cu")
		(at 26.1366 -210.844384 180)
		(property "Reference" "R136"
			(at 0 0 180)
			(layer "F.SilkS")
			(hide yes)
			(effects
				(font
					(size 1.27 1.27)
				)
			)
		)
		(property "Value" "0R2J-2-GP"
			(at 0.064008 -3.993896 180)
			(unlocked yes)
			(layer "F.Fab")
			(hide yes)
			(effects
				(font
					(size 1.016 1.016)
					(thickness 0.1524)
				)
			)
		)
		(property "Device Type" "R402H16"
			(at 0.064008 -5.517896 180)
			(unlocked yes)
			(layer "F.Fab")
			(hide yes)
			(effects
				(font
					(size 1.016 1.016)
					(thickness 0.1524)
				)
			)
		)
		(duplicate_pad_numbers_are_jumpers no)
		(fp_line
			(start 0.508 -0.9398)
			(end -0.508 -0.9398)
			(stroke
				(width 0.1524)
				(type default)
			)
			(layer "F.SilkS")
		)
		(fp_line
			(start -0.508 -0.9398)
			(end -0.508 0.9398)
			(stroke
				(width 0.1524)
				(type default)
			)
			(layer "F.SilkS")
		)
		(fp_rect
			(start -0.508 0.9398)
			(end 0.508 -0.9398)
			(stroke
				(width 0)
				(type default)
			)
			(fill no)
			(layer "F.CrtYd")
		)
		(fp_rect
			(start -0.508 0.9398)
			(end 0.508 -0.9398)
			(stroke
				(width 0)
				(type default)
			)
			(fill no)
			(layer "F.Fab")
		)
		(pad "1" smd custom
			(at 0 -0.4445 180)
			(size 0.1397 0.1397)
			(layers "F.Cu" "F.Mask" "F.Paste")
			(net "PWM_OUT_FAN6_NET")
			(options
				(clearance outline)
				(anchor circle)
			)
			(primitives
				(gr_poly
					(pts
						(arc
							(start -0.1778 -0.2794)
							(mid -0.249642 -0.249642)
							(end -0.2794 -0.1778)
						)
						(arc
							(start -0.2794 0.1778)
							(mid -0.249642 0.249642)
							(end -0.1778 0.2794)
						)
						(arc
							(start 0.1778 0.2794)
							(mid 0.249642 0.249642)
							(end 0.2794 0.1778)
						)
						(arc
							(start 0.2794 -0.1778)
							(mid 0.249642 -0.249642)
							(end 0.1778 -0.2794)
						)
					)
					(width 0)
					(fill yes)
				)
			)
		)
		(pad "2" smd custom
			(at 0 0.4445 180)
			(size 0.1397 0.1397)
			(layers "F.Cu" "F.Mask" "F.Paste")
			(net "PWM_OUT_FAN6")
			(options
				(clearance outline)
				(anchor circle)
			)
			(primitives
				(gr_poly
					(pts
						(arc
							(start -0.1778 -0.2794)
							(mid -0.249642 -0.249642)
							(end -0.2794 -0.1778)
						)
						(arc
							(start -0.2794 0.1778)
							(mid -0.249642 0.249642)
							(end -0.1778 0.2794)
						)
						(arc
							(start 0.1778 0.2794)
							(mid 0.249642 0.249642)
							(end 0.2794 0.1778)
						)
						(arc
							(start 0.2794 -0.1778)
							(mid 0.249642 -0.249642)
							(end 0.1778 -0.2794)
						)
					)
					(width 0)
					(fill yes)
				)
			)
		)
	)
	(footprint ""
		(layer "F.Cu")
		(at 36.6522 -282.9814)
		(property "Reference" "C48"
			(at 0 0 0)
			(layer "F.SilkS")
			(hide yes)
			(effects
				(font
					(size 1.27 1.27)
				)
			)
		)
		(property "Value" "SC1U25V3KX-1-GP"
			(at 0 -2.8194 0)
			(unlocked yes)
			(layer "F.Fab")
			(hide yes)
			(effects
				(font
					(size 1.016 1.016)
					(thickness 0.1524)
				)
			)
		)
		(property "Device Type" "C603H36"
			(at 0 -4.3434 0)
			(unlocked yes)
			(layer "F.Fab")
			(hide yes)
			(effects
				(font
					(size 1.016 1.016)
					(thickness 0.1524)
				)
			)
		)
		(duplicate_pad_numbers_are_jumpers no)
		(fp_line
			(start 0.508 0)
			(end -0.508 0)
			(stroke
				(width 0.2032)
				(type default)
			)
			(layer "F.SilkS")
		)
		(fp_rect
			(start -0.5842 1.3335)
			(end 0.5842 -1.3335)
			(stroke
				(width 0)
				(type default)
			)
			(fill no)
			(layer "F.CrtYd")
		)
		(fp_rect
			(start -0.5842 1.3335)
			(end 0.5842 -1.3335)
			(stroke
				(width 0)
				(type default)
			)
			(fill no)
			(layer "F.Fab")
		)
		(pad "1" smd custom
			(at 0 -0.762)
			(size 0.2159 0.2159)
			(layers "F.Cu" "F.Mask" "F.Paste")
			(net "P12V")
			(options
				(clearance outline)
				(anchor circle)
			)
			(primitives
				(gr_poly
					(pts
						(arc
							(start -0.3302 -0.4318)
							(mid -0.402042 -0.402042)
							(end -0.4318 -0.3302)
						)
						(arc
							(start -0.4318 0.3302)
							(mid -0.402042 0.402042)
							(end -0.3302 0.4318)
						)
						(arc
							(start 0.3302 0.4318)
							(mid 0.402042 0.402042)
							(end 0.4318 0.3302)
						)
						(arc
							(start 0.4318 -0.3302)
							(mid 0.402042 -0.402042)
							(end 0.3302 -0.4318)
						)
					)
					(width 0)
					(fill yes)
				)
			)
		)
		(pad "2" smd custom
			(at 0 0.762)
			(size 0.2159 0.2159)
			(layers "F.Cu" "F.Mask" "F.Paste")
			(net "GND")
			(options
				(clearance outline)
				(anchor circle)
			)
			(primitives
				(gr_poly
					(pts
						(arc
							(start -0.3302 -0.4318)
							(mid -0.402042 -0.402042)
							(end -0.4318 -0.3302)
						)
						(arc
							(start -0.4318 0.3302)
							(mid -0.402042 0.402042)
							(end -0.3302 0.4318)
						)
						(arc
							(start 0.3302 0.4318)
							(mid 0.402042 0.402042)
							(end 0.4318 0.3302)
						)
						(arc
							(start 0.4318 -0.3302)
							(mid 0.402042 -0.402042)
							(end 0.3302 -0.4318)
						)
					)
					(width 0)
					(fill yes)
				)
			)
		)
	)
	(footprint ""
		(layer "F.Cu")
		(at 14.8844 -41.4782 90)
		(property "Reference" "R116"
			(at 0 0 90)
			(layer "F.SilkS")
			(hide yes)
			(effects
				(font
					(size 1.27 1.27)
				)
			)
		)
		(property "Value" "470R2F-GP"
			(at 0.064008 -3.993896 90)
			(unlocked yes)
			(layer "F.Fab")
			(hide yes)
			(effects
				(font
					(size 1.016 1.016)
					(thickness 0.1524)
				)
			)
		)
		(property "Device Type" "R402H16"
			(at 0.064008 -5.517896 90)
			(unlocked yes)
			(layer "F.Fab")
			(hide yes)
			(effects
				(font
					(size 1.016 1.016)
					(thickness 0.1524)
				)
			)
		)
		(duplicate_pad_numbers_are_jumpers no)
		(fp_line
			(start 0.508 -0.9398)
			(end -0.508 -0.9398)
			(stroke
				(width 0.1524)
				(type default)
			)
			(layer "F.SilkS")
		)
		(fp_line
			(start -0.508 -0.9398)
			(end -0.508 0.9398)
			(stroke
				(width 0.1524)
				(type default)
			)
			(layer "F.SilkS")
		)
		(fp_rect
			(start -0.508 0.9398)
			(end 0.508 -0.9398)
			(stroke
				(width 0)
				(type default)
			)
			(fill no)
			(layer "F.CrtYd")
		)
		(fp_rect
			(start -0.508 0.9398)
			(end 0.508 -0.9398)
			(stroke
				(width 0)
				(type default)
			)
			(fill no)
			(layer "F.Fab")
		)
		(pad "1" smd custom
			(at 0 -0.4445 90)
			(size 0.1397 0.1397)
			(layers "F.Cu" "F.Mask" "F.Paste")
			(net "SEB_PEER_1B_HB")
			(options
				(clearance outline)
				(anchor circle)
			)
			(primitives
				(gr_poly
					(pts
						(arc
							(start -0.1778 -0.2794)
							(mid -0.249642 -0.249642)
							(end -0.2794 -0.1778)
						)
						(arc
							(start -0.2794 0.1778)
							(mid -0.249642 0.249642)
							(end -0.1778 0.2794)
						)
						(arc
							(start 0.1778 0.2794)
							(mid 0.249642 0.249642)
							(end 0.2794 0.1778)
						)
						(arc
							(start 0.2794 -0.1778)
							(mid 0.249642 -0.249642)
							(end 0.1778 -0.2794)
						)
					)
					(width 0)
					(fill yes)
				)
			)
		)
		(pad "2" smd custom
			(at 0 0.4445 90)
			(size 0.1397 0.1397)
			(layers "F.Cu" "F.Mask" "F.Paste")
			(net "GND")
			(options
				(clearance outline)
				(anchor circle)
			)
			(primitives
				(gr_poly
					(pts
						(arc
							(start -0.1778 -0.2794)
							(mid -0.249642 -0.249642)
							(end -0.2794 -0.1778)
						)
						(arc
							(start -0.2794 0.1778)
							(mid -0.249642 0.249642)
							(end -0.1778 0.2794)
						)
						(arc
							(start 0.1778 0.2794)
							(mid 0.249642 0.249642)
							(end 0.2794 0.1778)
						)
						(arc
							(start 0.2794 -0.1778)
							(mid 0.249642 -0.249642)
							(end 0.1778 -0.2794)
						)
					)
					(width 0)
					(fill yes)
				)
			)
		)
	)
	(footprint ""
		(layer "F.Cu")
		(at 36.1188 -371.4496 -90)
		(property "Reference" "PR6"
			(at 0 0 270)
			(layer "F.SilkS")
			(hide yes)
			(effects
				(font
					(size 1.27 1.27)
				)
			)
		)
		(property "Value" "100KR2F-L1-GP"
			(at 0.064008 -3.993896 270)
			(unlocked yes)
			(layer "F.Fab")
			(hide yes)
			(effects
				(font
					(size 1.016 1.016)
					(thickness 0.1524)
				)
			)
		)
		(property "Device Type" "R402H16"
			(at 0.064008 -5.517896 270)
			(unlocked yes)
			(layer "F.Fab")
			(hide yes)
			(effects
				(font
					(size 1.016 1.016)
					(thickness 0.1524)
				)
			)
		)
		(duplicate_pad_numbers_are_jumpers no)
		(fp_line
			(start -0.508 -0.9398)
			(end -0.508 0.9398)
			(stroke
				(width 0.1524)
				(type default)
			)
			(layer "F.SilkS")
		)
		(fp_line
			(start 0.508 -0.9398)
			(end -0.508 -0.9398)
			(stroke
				(width 0.1524)
				(type default)
			)
			(layer "F.SilkS")
		)
		(fp_rect
			(start -0.508 0.9398)
			(end 0.508 -0.9398)
			(stroke
				(width 0)
				(type default)
			)
			(fill no)
			(layer "F.CrtYd")
		)
		(fp_rect
			(start -0.508 0.9398)
			(end 0.508 -0.9398)
			(stroke
				(width 0)
				(type default)
			)
			(fill no)
			(layer "F.Fab")
		)
		(pad "1" smd custom
			(at 0 -0.4445 270)
			(size 0.1397 0.1397)
			(layers "F.Cu" "F.Mask" "F.Paste")
			(net "P12V")
			(options
				(clearance outline)
				(anchor circle)
			)
			(primitives
				(gr_poly
					(pts
						(arc
							(start -0.1778 -0.2794)
							(mid -0.249642 -0.249642)
							(end -0.2794 -0.1778)
						)
						(arc
							(start -0.2794 0.1778)
							(mid -0.249642 0.249642)
							(end -0.1778 0.2794)
						)
						(arc
							(start 0.1778 0.2794)
							(mid 0.249642 0.249642)
							(end 0.2794 0.1778)
						)
						(arc
							(start 0.2794 -0.1778)
							(mid 0.249642 -0.249642)
							(end 0.1778 -0.2794)
						)
					)
					(width 0)
					(fill yes)
				)
			)
		)
		(pad "2" smd custom
			(at 0 0.4445 270)
			(size 0.1397 0.1397)
			(layers "F.Cu" "F.Mask" "F.Paste")
			(net "ADM1276_FLB")
			(options
				(clearance outline)
				(anchor circle)
			)
			(primitives
				(gr_poly
					(pts
						(arc
							(start -0.1778 -0.2794)
							(mid -0.249642 -0.249642)
							(end -0.2794 -0.1778)
						)
						(arc
							(start -0.2794 0.1778)
							(mid -0.249642 0.249642)
							(end -0.1778 0.2794)
						)
						(arc
							(start 0.1778 0.2794)
							(mid 0.249642 0.249642)
							(end 0.2794 0.1778)
						)
						(arc
							(start 0.2794 -0.1778)
							(mid 0.249642 -0.249642)
							(end 0.1778 -0.2794)
						)
					)
					(width 0)
					(fill yes)
				)
			)
		)
	)
	(footprint ""
		(layer "F.Cu")
		(at 32.004 -180.467 90)
		(property "Reference" "D13"
			(at 0 0 90)
			(layer "F.SilkS")
			(hide yes)
			(effects
				(font
					(size 1.27 1.27)
				)
			)
		)
		(property "Value" "BZG05C3V9-GP"
			(at 0.027178 -8.482076 90)
			(unlocked yes)
			(layer "F.Fab")
			(hide yes)
			(effects
				(font
					(size 1.016 1.016)
					(thickness 0.1524)
				)
			)
		)
		(property "Device Type" "D5226155AKH91"
			(at 0.027178 -10.006076 90)
			(unlocked yes)
			(layer "F.Fab")
			(hide yes)
			(effects
				(font
					(size 1.016 1.016)
					(thickness 0.1524)
				)
			)
		)
		(duplicate_pad_numbers_are_jumpers no)
		(fp_line
			(start 1.524 -3.4798)
			(end -1.524 -3.4798)
			(stroke
				(width 0.1524)
				(type default)
			)
			(layer "F.SilkS")
		)
		(fp_line
			(start -1.524 -3.4798)
			(end -1.524 3.4798)
			(stroke
				(width 0.1524)
				(type default)
			)
			(layer "F.SilkS")
		)
		(fp_line
			(start 1.524 3.4798)
			(end 1.524 -3.4798)
			(stroke
				(width 0.1524)
				(type default)
			)
			(layer "F.SilkS")
		)
		(fp_line
			(start -1.524 3.4798)
			(end 1.524 3.4798)
			(stroke
				(width 0.1524)
				(type default)
			)
			(layer "F.SilkS")
		)
		(fp_line
			(start -1.524 3.6576)
			(end 1.524 3.6576)
			(stroke
				(width 0.508)
				(type default)
			)
			(layer "F.SilkS")
		)
		(fp_rect
			(start -1.27 2.6035)
			(end 1.27 -2.6035)
			(stroke
				(width 0)
				(type default)
			)
			(fill no)
			(layer "F.CrtYd")
		)
		(fp_poly
			(pts
				(xy 1.778 -0.2921) (xy 1.27 -0.2921) (xy 1.27 -2.6035) (xy -1.27 -2.6035) (xy -1.27 2.6035) (xy 1.27 2.6035)
				(xy 1.27 -0.2794) (xy 1.778 -0.2794) (xy 1.778 3.556) (xy -1.778 3.556) (xy -1.778 -3.556) (xy 1.778 -3.556)
			)
			(stroke
				(width 0)
				(type default)
			)
			(fill no)
			(layer "F.CrtYd")
		)
		(fp_rect
			(start -1.778 3.556)
			(end 1.778 -3.556)
			(stroke
				(width 0)
				(type default)
			)
			(fill no)
			(layer "F.Fab")
		)
		(pad "A" smd rect
			(at 0 -2.212086 90)
			(size 1.8034 2.032)
			(layers "F.Cu" "F.Mask" "F.Paste")
			(net "GND")
		)
		(pad "K" smd rect
			(at 0 2.212086 90)
			(size 1.8034 2.032)
			(layers "F.Cu" "F.Mask" "F.Paste")
			(net "P3V3_AUX_BJT_B")
		)
	)
	(footprint ""
		(layer "F.Cu")
		(at 15.113 -55.118 90)
		(property "Reference" "R358"
			(at 0 0 90)
			(layer "F.SilkS")
			(hide yes)
			(effects
				(font
					(size 1.27 1.27)
				)
			)
		)
		(property "Value" "10KR2F-2-GP"
			(at 0.064008 -3.993896 90)
			(unlocked yes)
			(layer "F.Fab")
			(hide yes)
			(effects
				(font
					(size 1.016 1.016)
					(thickness 0.1524)
				)
			)
		)
		(property "Device Type" "R402H16"
			(at 0.064008 -5.517896 90)
			(unlocked yes)
			(layer "F.Fab")
			(hide yes)
			(effects
				(font
					(size 1.016 1.016)
					(thickness 0.1524)
				)
			)
		)
		(duplicate_pad_numbers_are_jumpers no)
		(fp_line
			(start 0.508 -0.9398)
			(end -0.508 -0.9398)
			(stroke
				(width 0.1524)
				(type default)
			)
			(layer "F.SilkS")
		)
		(fp_line
			(start -0.508 -0.9398)
			(end -0.508 0.9398)
			(stroke
				(width 0.1524)
				(type default)
			)
			(layer "F.SilkS")
		)
		(fp_rect
			(start -0.508 0.9398)
			(end 0.508 -0.9398)
			(stroke
				(width 0)
				(type default)
			)
			(fill no)
			(layer "F.CrtYd")
		)
		(fp_rect
			(start -0.508 0.9398)
			(end 0.508 -0.9398)
			(stroke
				(width 0)
				(type default)
			)
			(fill no)
			(layer "F.Fab")
		)
		(pad "1" smd custom
			(at 0 -0.4445 90)
			(size 0.1397 0.1397)
			(layers "F.Cu" "F.Mask" "F.Paste")
			(net "P3V3")
			(options
				(clearance outline)
				(anchor circle)
			)
			(primitives
				(gr_poly
					(pts
						(arc
							(start -0.1778 -0.2794)
							(mid -0.249642 -0.249642)
							(end -0.2794 -0.1778)
						)
						(arc
							(start -0.2794 0.1778)
							(mid -0.249642 0.249642)
							(end -0.1778 0.2794)
						)
						(arc
							(start 0.1778 0.2794)
							(mid 0.249642 0.249642)
							(end 0.2794 0.1778)
						)
						(arc
							(start 0.2794 -0.1778)
							(mid 0.249642 -0.249642)
							(end 0.1778 -0.2794)
						)
					)
					(width 0)
					(fill yes)
				)
			)
		)
		(pad "2" smd custom
			(at 0 0.4445 90)
			(size 0.1397 0.1397)
			(layers "F.Cu" "F.Mask" "F.Paste")
			(net "LOWER_TRAY_ID")
			(options
				(clearance outline)
				(anchor circle)
			)
			(primitives
				(gr_poly
					(pts
						(arc
							(start -0.1778 -0.2794)
							(mid -0.249642 -0.249642)
							(end -0.2794 -0.1778)
						)
						(arc
							(start -0.2794 0.1778)
							(mid -0.249642 0.249642)
							(end -0.1778 0.2794)
						)
						(arc
							(start 0.1778 0.2794)
							(mid 0.249642 0.249642)
							(end 0.2794 0.1778)
						)
						(arc
							(start 0.2794 -0.1778)
							(mid 0.249642 -0.249642)
							(end 0.1778 -0.2794)
						)
					)
					(width 0)
					(fill yes)
				)
			)
		)
	)
	(footprint ""
		(layer "F.Cu")
		(at 39.243 -178.054 180)
		(property "Reference" "PR45"
			(at 0 0 180)
			(layer "F.SilkS")
			(hide yes)
			(effects
				(font
					(size 1.27 1.27)
				)
			)
		)
		(property "Value" "10KR2F-2-GP"
			(at 0.064008 -3.993896 180)
			(unlocked yes)
			(layer "F.Fab")
			(hide yes)
			(effects
				(font
					(size 1.016 1.016)
					(thickness 0.1524)
				)
			)
		)
		(property "Device Type" "R402H16"
			(at 0.064008 -5.517896 180)
			(unlocked yes)
			(layer "F.Fab")
			(hide yes)
			(effects
				(font
					(size 1.016 1.016)
					(thickness 0.1524)
				)
			)
		)
		(duplicate_pad_numbers_are_jumpers no)
		(fp_line
			(start 0.508 -0.9398)
			(end -0.508 -0.9398)
			(stroke
				(width 0.1524)
				(type default)
			)
			(layer "F.SilkS")
		)
		(fp_line
			(start -0.508 -0.9398)
			(end -0.508 0.9398)
			(stroke
				(width 0.1524)
				(type default)
			)
			(layer "F.SilkS")
		)
		(fp_rect
			(start -0.508 0.9398)
			(end 0.508 -0.9398)
			(stroke
				(width 0)
				(type default)
			)
			(fill no)
			(layer "F.CrtYd")
		)
		(fp_rect
			(start -0.508 0.9398)
			(end 0.508 -0.9398)
			(stroke
				(width 0)
				(type default)
			)
			(fill no)
			(layer "F.Fab")
		)
		(pad "1" smd custom
			(at 0 -0.4445 180)
			(size 0.1397 0.1397)
			(layers "F.Cu" "F.Mask" "F.Paste")
			(net "P3V3_AUX")
			(options
				(clearance outline)
				(anchor circle)
			)
			(primitives
				(gr_poly
					(pts
						(arc
							(start -0.1778 -0.2794)
							(mid -0.249642 -0.249642)
							(end -0.2794 -0.1778)
						)
						(arc
							(start -0.2794 0.1778)
							(mid -0.249642 0.249642)
							(end -0.1778 0.2794)
						)
						(arc
							(start 0.1778 0.2794)
							(mid 0.249642 0.249642)
							(end 0.2794 0.1778)
						)
						(arc
							(start 0.2794 -0.1778)
							(mid 0.249642 -0.249642)
							(end 0.1778 -0.2794)
						)
					)
					(width 0)
					(fill yes)
				)
			)
		)
		(pad "2" smd custom
			(at 0 0.4445 180)
			(size 0.1397 0.1397)
			(layers "F.Cu" "F.Mask" "F.Paste")
			(net "TEMP_ALM#_IN_D")
			(options
				(clearance outline)
				(anchor circle)
			)
			(primitives
				(gr_poly
					(pts
						(arc
							(start -0.1778 -0.2794)
							(mid -0.249642 -0.249642)
							(end -0.2794 -0.1778)
						)
						(arc
							(start -0.2794 0.1778)
							(mid -0.249642 0.249642)
							(end -0.1778 0.2794)
						)
						(arc
							(start 0.1778 0.2794)
							(mid 0.249642 0.249642)
							(end 0.2794 0.1778)
						)
						(arc
							(start 0.2794 -0.1778)
							(mid 0.249642 -0.249642)
							(end 0.1778 -0.2794)
						)
					)
					(width 0)
					(fill yes)
				)
			)
		)
	)
	(footprint ""
		(layer "F.Cu")
		(at 16.67129 -175.540924 180)
		(property "Reference" "C9"
			(at 0 0 180)
			(layer "F.SilkS")
			(hide yes)
			(effects
				(font
					(size 1.27 1.27)
				)
			)
		)
		(property "Value" "SC1U16V3KX-5GP"
			(at 0 -2.8194 180)
			(unlocked yes)
			(layer "F.Fab")
			(hide yes)
			(effects
				(font
					(size 1.016 1.016)
					(thickness 0.1524)
				)
			)
		)
		(property "Device Type" "C603H36"
			(at 0 -4.3434 180)
			(unlocked yes)
			(layer "F.Fab")
			(hide yes)
			(effects
				(font
					(size 1.016 1.016)
					(thickness 0.1524)
				)
			)
		)
		(duplicate_pad_numbers_are_jumpers no)
		(fp_line
			(start 0.508 0)
			(end -0.508 0)
			(stroke
				(width 0.2032)
				(type default)
			)
			(layer "F.SilkS")
		)
		(fp_rect
			(start -0.5842 1.3335)
			(end 0.5842 -1.3335)
			(stroke
				(width 0)
				(type default)
			)
			(fill no)
			(layer "F.CrtYd")
		)
		(fp_rect
			(start -0.5842 1.3335)
			(end 0.5842 -1.3335)
			(stroke
				(width 0)
				(type default)
			)
			(fill no)
			(layer "F.Fab")
		)
		(pad "1" smd custom
			(at 0 -0.762 180)
			(size 0.2159 0.2159)
			(layers "F.Cu" "F.Mask" "F.Paste")
			(net "P3V3")
			(options
				(clearance outline)
				(anchor circle)
			)
			(primitives
				(gr_poly
					(pts
						(arc
							(start -0.3302 -0.4318)
							(mid -0.402042 -0.402042)
							(end -0.4318 -0.3302)
						)
						(arc
							(start -0.4318 0.3302)
							(mid -0.402042 0.402042)
							(end -0.3302 0.4318)
						)
						(arc
							(start 0.3302 0.4318)
							(mid 0.402042 0.402042)
							(end 0.4318 0.3302)
						)
						(arc
							(start 0.4318 -0.3302)
							(mid 0.402042 -0.402042)
							(end 0.3302 -0.4318)
						)
					)
					(width 0)
					(fill yes)
				)
			)
		)
		(pad "2" smd custom
			(at 0 0.762 180)
			(size 0.2159 0.2159)
			(layers "F.Cu" "F.Mask" "F.Paste")
			(net "GND")
			(options
				(clearance outline)
				(anchor circle)
			)
			(primitives
				(gr_poly
					(pts
						(arc
							(start -0.3302 -0.4318)
							(mid -0.402042 -0.402042)
							(end -0.4318 -0.3302)
						)
						(arc
							(start -0.4318 0.3302)
							(mid -0.402042 0.402042)
							(end -0.3302 0.4318)
						)
						(arc
							(start 0.3302 0.4318)
							(mid 0.402042 0.402042)
							(end 0.4318 0.3302)
						)
						(arc
							(start 0.4318 -0.3302)
							(mid 0.402042 -0.402042)
							(end 0.3302 -0.4318)
						)
					)
					(width 0)
					(fill yes)
				)
			)
		)
	)
	(footprint ""
		(layer "F.Cu")
		(at 38.67531 -153.713434)
		(property "Reference" "C1"
			(at 0 0 0)
			(layer "F.SilkS")
			(hide yes)
			(effects
				(font
					(size 1.27 1.27)
				)
			)
		)
		(property "Value" "SC10U25V5KX-GP"
			(at -0.0762 -6.1214 0)
			(unlocked yes)
			(layer "F.Fab")
			(hide yes)
			(effects
				(font
					(size 1.016 1.016)
					(thickness 0.1524)
				)
			)
		)
		(property "Device Type" "C805H56"
			(at -0.0762 -8.1534 0)
			(unlocked yes)
			(layer "F.Fab")
			(hide yes)
			(effects
				(font
					(size 1.016 1.016)
					(thickness 0.1524)
				)
			)
		)
		(duplicate_pad_numbers_are_jumpers no)
		(fp_line
			(start 0.635 0)
			(end -0.635 0)
			(stroke
				(width 0.508)
				(type default)
			)
			(layer "F.SilkS")
		)
		(fp_rect
			(start -0.9652 1.778)
			(end 0.9652 -1.778)
			(stroke
				(width 0)
				(type default)
			)
			(fill no)
			(layer "F.CrtYd")
		)
		(fp_poly
			(pts
				(xy -0.9652 -1.778) (xy 0.9652 -1.778) (xy 0.9652 1.778) (xy -0.9652 1.778)
			)
			(stroke
				(width 0)
				(type default)
			)
			(fill no)
			(layer "F.Fab")
		)
		(pad "1" smd rect
			(at 0 -0.9652)
			(size 1.397 1.143)
			(layers "F.Cu" "F.Mask" "F.Paste")
			(net "NCT7904_3VDD")
		)
		(pad "2" smd rect
			(at 0 0.9652)
			(size 1.397 1.143)
			(layers "F.Cu" "F.Mask" "F.Paste")
			(net "GND")
		)
	)
	(footprint ""
		(layer "F.Cu")
		(at 45.500036 -19.99996)
		(property "Reference" "H1"
			(at 0 0 0)
			(layer "F.SilkS")
			(hide yes)
			(effects
				(font
					(size 1.27 1.27)
				)
			)
		)
		(property "Value" "HOLE315R138"
			(at 0 -7.0612 0)
			(unlocked yes)
			(layer "F.Fab")
			(hide yes)
			(effects
				(font
					(size 1.016 1.016)
					(thickness 0.1524)
				)
			)
		)
		(property "Device Type" "HOLE315R138"
			(at 0 -8.5852 0)
			(unlocked yes)
			(layer "F.Fab")
			(hide yes)
			(effects
				(font
					(size 1.016 1.016)
					(thickness 0.1524)
				)
			)
		)
		(duplicate_pad_numbers_are_jumpers no)
		(fp_poly
			(pts
				(xy 0 4.3053) (xy -0.13462 4.30276) (xy -0.27051 4.29641) (xy -0.40513 4.28625) (xy -0.53975 4.27101)
				(xy -0.6731 4.25196) (xy -0.80645 4.2291) (xy -0.9398 4.20116) (xy -1.07061 4.17068) (xy -1.20142 4.13385)
				(xy -1.33096 4.09448) (xy -1.45796 4.0513) (xy -1.58496 4.00304) (xy -1.70942 3.95097) (xy -1.83261 3.89509)
				(xy -1.95453 3.83667) (xy -2.07391 3.77317) (xy -2.19202 3.70586) (xy -2.30632 3.63474) (xy -2.41935 3.56108)
				(xy -2.53111 3.48361) (xy -2.63906 3.40233) (xy -2.74447 3.31724) (xy -2.84734 3.22961) (xy -2.94767 3.13817)
				(xy -3.04419 3.04419) (xy -3.13817 2.94767) (xy -3.22961 2.84734) (xy -3.31724 2.74447) (xy -3.40233 2.63906)
				(xy -3.48361 2.53111) (xy -3.56108 2.41935) (xy -3.63474 2.30632) (xy -3.70586 2.19202) (xy -3.77317 2.07391)
				(xy -3.83667 1.95453) (xy -3.89509 1.83261) (xy -3.95097 1.70942) (xy -4.00304 1.58496) (xy -4.0513 1.45796)
				(xy -4.09448 1.33096) (xy -4.13385 1.20142) (xy -4.17068 1.07061) (xy -4.20116 0.9398) (xy -4.2291 0.80645)
				(xy -4.25196 0.6731) (xy -4.27101 0.53975) (xy -4.28625 0.40513) (xy -4.29641 0.27051) (xy -4.30276 0.13462)
				(xy -4.3053 0) (xy -4.30276 -0.13462) (xy -4.29641 -0.27051) (xy -4.28625 -0.40513) (xy -4.27101 -0.53975)
				(xy -4.25196 -0.6731) (xy -4.2291 -0.80645) (xy -4.20116 -0.9398) (xy -4.17068 -1.07061) (xy -4.13385 -1.20142)
				(xy -4.09448 -1.33096) (xy -4.0513 -1.45796) (xy -4.00304 -1.58496) (xy -3.95097 -1.70942) (xy -3.89509 -1.83261)
				(xy -3.83667 -1.95453) (xy -3.77317 -2.07391) (xy -3.70586 -2.19202) (xy -3.63474 -2.30632) (xy -3.56108 -2.41935)
				(xy -3.48361 -2.53111) (xy -3.40233 -2.63906) (xy -3.31724 -2.74447) (xy -3.22961 -2.84734) (xy -3.13817 -2.94767)
				(xy -3.04419 -3.04419) (xy -2.94767 -3.13817) (xy -2.84734 -3.22961) (xy -2.74447 -3.31724) (xy -2.63906 -3.40233)
				(xy -2.53111 -3.48361) (xy -2.41935 -3.56108) (xy -2.30632 -3.63474) (xy -2.19202 -3.70586) (xy -2.07391 -3.77317)
				(xy -1.95453 -3.83667) (xy -1.83261 -3.89509) (xy -1.70942 -3.95097) (xy -1.58496 -4.00304) (xy -1.45796 -4.0513)
				(xy -1.33096 -4.09448) (xy -1.20142 -4.13385) (xy -1.07061 -4.17068) (xy -0.9398 -4.20116) (xy -0.80645 -4.2291)
				(xy -0.6731 -4.25196) (xy -0.53975 -4.27101) (xy -0.40513 -4.28625) (xy -0.27051 -4.29641) (xy -0.13462 -4.30276)
				(xy 0 -4.3053) (xy 0.13462 -4.30276) (xy 0.27051 -4.29641) (xy 0.40513 -4.28625) (xy 0.53975 -4.27101)
				(xy 0.6731 -4.25196) (xy 0.80645 -4.2291) (xy 0.9398 -4.20116) (xy 1.07061 -4.17068) (xy 1.20142 -4.13385)
				(xy 1.33096 -4.09448) (xy 1.45796 -4.0513) (xy 1.58496 -4.00304) (xy 1.70942 -3.95097) (xy 1.83261 -3.89509)
				(xy 1.95453 -3.83667) (xy 2.07391 -3.77317) (xy 2.19202 -3.70586) (xy 2.30632 -3.63474) (xy 2.41935 -3.56108)
				(xy 2.53111 -3.48361) (xy 2.63906 -3.40233) (xy 2.74447 -3.31724) (xy 2.84734 -3.22961) (xy 2.94767 -3.13817)
				(xy 3.04419 -3.04419) (xy 3.13817 -2.94767) (xy 3.22961 -2.84734) (xy 3.31724 -2.74447) (xy 3.40233 -2.63906)
				(xy 3.48361 -2.53111) (xy 3.56108 -2.41935) (xy 3.63474 -2.30632) (xy 3.70586 -2.19202) (xy 3.77317 -2.07391)
				(xy 3.83667 -1.95453) (xy 3.89509 -1.83261) (xy 3.95097 -1.70942) (xy 4.00304 -1.58496) (xy 4.0513 -1.45796)
				(xy 4.09448 -1.33096) (xy 4.13385 -1.20142) (xy 4.17068 -1.07061) (xy 4.20116 -0.9398) (xy 4.2291 -0.80645)
				(xy 4.25196 -0.6731) (xy 4.27101 -0.53975) (xy 4.28625 -0.40513) (xy 4.29641 -0.27051) (xy 4.30276 -0.13462)
				(xy 4.3053 0) (xy 4.30276 0.13462) (xy 4.29641 0.27051) (xy 4.28625 0.40513) (xy 4.27101 0.53975)
				(xy 4.25196 0.6731) (xy 4.2291 0.80645) (xy 4.20116 0.9398) (xy 4.17068 1.07061) (xy 4.13385 1.20142)
				(xy 4.09448 1.33096) (xy 4.0513 1.45796) (xy 4.00304 1.58496) (xy 3.95097 1.70942) (xy 3.89509 1.83261)
				(xy 3.83667 1.95453) (xy 3.77317 2.07391) (xy 3.70586 2.19202) (xy 3.63474 2.30632) (xy 3.56108 2.41935)
				(xy 3.48361 2.53111) (xy 3.40233 2.63906) (xy 3.31724 2.74447) (xy 3.22961 2.84734) (xy 3.13817 2.94767)
				(xy 3.04419 3.04419) (xy 2.94767 3.13817) (xy 2.84734 3.22961) (xy 2.74447 3.31724) (xy 2.63906 3.40233)
				(xy 2.53111 3.48361) (xy 2.41935 3.56108) (xy 2.30632 3.63474) (xy 2.19202 3.70586) (xy 2.07391 3.77317)
				(xy 1.95453 3.83667) (xy 1.83261 3.89509) (xy 1.70942 3.95097) (xy 1.58496 4.00304) (xy 1.45796 4.0513)
				(xy 1.33096 4.09448) (xy 1.20142 4.13385) (xy 1.07061 4.17068) (xy 0.9398 4.20116) (xy 0.80645 4.2291)
				(xy 0.6731 4.25196) (xy 0.53975 4.27101) (xy 0.40513 4.28625) (xy 0.27051 4.29641) (xy 0.13462 4.30276)
			)
			(stroke
				(width 0)
				(type default)
			)
			(fill no)
			(layer "F.CrtYd")
		)
		(fp_poly
			(pts
				(xy 0 4.3053) (xy -0.13462 4.30276) (xy -0.27051 4.29641) (xy -0.40513 4.28625) (xy -0.53975 4.27101)
				(xy -0.6731 4.25196) (xy -0.80645 4.2291) (xy -0.9398 4.20116) (xy -1.07061 4.17068) (xy -1.20142 4.13385)
				(xy -1.33096 4.09448) (xy -1.45796 4.0513) (xy -1.58496 4.00304) (xy -1.70942 3.95097) (xy -1.83261 3.89509)
				(xy -1.95453 3.83667) (xy -2.07391 3.77317) (xy -2.19202 3.70586) (xy -2.30632 3.63474) (xy -2.41935 3.56108)
				(xy -2.53111 3.48361) (xy -2.63906 3.40233) (xy -2.74447 3.31724) (xy -2.84734 3.22961) (xy -2.94767 3.13817)
				(xy -3.04419 3.04419) (xy -3.13817 2.94767) (xy -3.22961 2.84734) (xy -3.31724 2.74447) (xy -3.40233 2.63906)
				(xy -3.48361 2.53111) (xy -3.56108 2.41935) (xy -3.63474 2.30632) (xy -3.70586 2.19202) (xy -3.77317 2.07391)
				(xy -3.83667 1.95453) (xy -3.89509 1.83261) (xy -3.95097 1.70942) (xy -4.00304 1.58496) (xy -4.0513 1.45796)
				(xy -4.09448 1.33096) (xy -4.13385 1.20142) (xy -4.17068 1.07061) (xy -4.20116 0.9398) (xy -4.2291 0.80645)
				(xy -4.25196 0.6731) (xy -4.27101 0.53975) (xy -4.28625 0.40513) (xy -4.29641 0.27051) (xy -4.30276 0.13462)
				(xy -4.3053 0) (xy -4.30276 -0.13462) (xy -4.29641 -0.27051) (xy -4.28625 -0.40513) (xy -4.27101 -0.53975)
				(xy -4.25196 -0.6731) (xy -4.2291 -0.80645) (xy -4.20116 -0.9398) (xy -4.17068 -1.07061) (xy -4.13385 -1.20142)
				(xy -4.09448 -1.33096) (xy -4.0513 -1.45796) (xy -4.00304 -1.58496) (xy -3.95097 -1.70942) (xy -3.89509 -1.83261)
				(xy -3.83667 -1.95453) (xy -3.77317 -2.07391) (xy -3.70586 -2.19202) (xy -3.63474 -2.30632) (xy -3.56108 -2.41935)
				(xy -3.48361 -2.53111) (xy -3.40233 -2.63906) (xy -3.31724 -2.74447) (xy -3.22961 -2.84734) (xy -3.13817 -2.94767)
				(xy -3.04419 -3.04419) (xy -2.94767 -3.13817) (xy -2.84734 -3.22961) (xy -2.74447 -3.31724) (xy -2.63906 -3.40233)
				(xy -2.53111 -3.48361) (xy -2.41935 -3.56108) (xy -2.30632 -3.63474) (xy -2.19202 -3.70586) (xy -2.07391 -3.77317)
				(xy -1.95453 -3.83667) (xy -1.83261 -3.89509) (xy -1.70942 -3.95097) (xy -1.58496 -4.00304) (xy -1.45796 -4.0513)
				(xy -1.33096 -4.09448) (xy -1.20142 -4.13385) (xy -1.07061 -4.17068) (xy -0.9398 -4.20116) (xy -0.80645 -4.2291)
				(xy -0.6731 -4.25196) (xy -0.53975 -4.27101) (xy -0.40513 -4.28625) (xy -0.27051 -4.29641) (xy -0.13462 -4.30276)
				(xy 0 -4.3053) (xy 0.13462 -4.30276) (xy 0.27051 -4.29641) (xy 0.40513 -4.28625) (xy 0.53975 -4.27101)
				(xy 0.6731 -4.25196) (xy 0.80645 -4.2291) (xy 0.9398 -4.20116) (xy 1.07061 -4.17068) (xy 1.20142 -4.13385)
				(xy 1.33096 -4.09448) (xy 1.45796 -4.0513) (xy 1.58496 -4.00304) (xy 1.70942 -3.95097) (xy 1.83261 -3.89509)
				(xy 1.95453 -3.83667) (xy 2.07391 -3.77317) (xy 2.19202 -3.70586) (xy 2.30632 -3.63474) (xy 2.41935 -3.56108)
				(xy 2.53111 -3.48361) (xy 2.63906 -3.40233) (xy 2.74447 -3.31724) (xy 2.84734 -3.22961) (xy 2.94767 -3.13817)
				(xy 3.04419 -3.04419) (xy 3.13817 -2.94767) (xy 3.22961 -2.84734) (xy 3.31724 -2.74447) (xy 3.40233 -2.63906)
				(xy 3.48361 -2.53111) (xy 3.56108 -2.41935) (xy 3.63474 -2.30632) (xy 3.70586 -2.19202) (xy 3.77317 -2.07391)
				(xy 3.83667 -1.95453) (xy 3.89509 -1.83261) (xy 3.95097 -1.70942) (xy 4.00304 -1.58496) (xy 4.0513 -1.45796)
				(xy 4.09448 -1.33096) (xy 4.13385 -1.20142) (xy 4.17068 -1.07061) (xy 4.20116 -0.9398) (xy 4.2291 -0.80645)
				(xy 4.25196 -0.6731) (xy 4.27101 -0.53975) (xy 4.28625 -0.40513) (xy 4.29641 -0.27051) (xy 4.30276 -0.13462)
				(xy 4.3053 0) (xy 4.30276 0.13462) (xy 4.29641 0.27051) (xy 4.28625 0.40513) (xy 4.27101 0.53975)
				(xy 4.25196 0.6731) (xy 4.2291 0.80645) (xy 4.20116 0.9398) (xy 4.17068 1.07061) (xy 4.13385 1.20142)
				(xy 4.09448 1.33096) (xy 4.0513 1.45796) (xy 4.00304 1.58496) (xy 3.95097 1.70942) (xy 3.89509 1.83261)
				(xy 3.83667 1.95453) (xy 3.77317 2.07391) (xy 3.70586 2.19202) (xy 3.63474 2.30632) (xy 3.56108 2.41935)
				(xy 3.48361 2.53111) (xy 3.40233 2.63906) (xy 3.31724 2.74447) (xy 3.22961 2.84734) (xy 3.13817 2.94767)
				(xy 3.04419 3.04419) (xy 2.94767 3.13817) (xy 2.84734 3.22961) (xy 2.74447 3.31724) (xy 2.63906 3.40233)
				(xy 2.53111 3.48361) (xy 2.41935 3.56108) (xy 2.30632 3.63474) (xy 2.19202 3.70586) (xy 2.07391 3.77317)
				(xy 1.95453 3.83667) (xy 1.83261 3.89509) (xy 1.70942 3.95097) (xy 1.58496 4.00304) (xy 1.45796 4.0513)
				(xy 1.33096 4.09448) (xy 1.20142 4.13385) (xy 1.07061 4.17068) (xy 0.9398 4.20116) (xy 0.80645 4.2291)
				(xy 0.6731 4.25196) (xy 0.53975 4.27101) (xy 0.40513 4.28625) (xy 0.27051 4.29641) (xy 0.13462 4.30276)
			)
			(stroke
				(width 0)
				(type default)
			)
			(fill no)
			(layer "F.Fab")
		)
		(pad "1" thru_hole circle
			(at 0 0)
			(size 8.001 8.001)
			(drill 3.5052)
			(layers "*.Cu" "*.Mask")
			(remove_unused_layers no)
			(net "GND")
			(clearance -1.7399)
			(thermal_gap 0.3048)
			(padstack
				(mode front_inner_back)
				(layer "Inner"
					(shape circle)
					(size 3.9116 3.9116)
					(clearance 0.3048)
				)
				(layer "B.Cu"
					(shape circle)
					(size 8.001 8.001)
					(clearance -1.7399)
				)
			)
		)
	)
	(footprint ""
		(layer "F.Cu")
		(at 20.385024 -175.37811 90)
		(property "Reference" "R23"
			(at 0 0 90)
			(layer "F.SilkS")
			(hide yes)
			(effects
				(font
					(size 1.27 1.27)
				)
			)
		)
		(property "Value" "4K7R2F-GP"
			(at 0.064008 -3.993896 90)
			(unlocked yes)
			(layer "F.Fab")
			(hide yes)
			(effects
				(font
					(size 1.016 1.016)
					(thickness 0.1524)
				)
			)
		)
		(property "Device Type" "R402H16"
			(at 0.064008 -5.517896 90)
			(unlocked yes)
			(layer "F.Fab")
			(hide yes)
			(effects
				(font
					(size 1.016 1.016)
					(thickness 0.1524)
				)
			)
		)
		(duplicate_pad_numbers_are_jumpers no)
		(fp_line
			(start 0.508 -0.9398)
			(end -0.508 -0.9398)
			(stroke
				(width 0.1524)
				(type default)
			)
			(layer "F.SilkS")
		)
		(fp_line
			(start -0.508 -0.9398)
			(end -0.508 0.9398)
			(stroke
				(width 0.1524)
				(type default)
			)
			(layer "F.SilkS")
		)
		(fp_rect
			(start -0.508 0.9398)
			(end 0.508 -0.9398)
			(stroke
				(width 0)
				(type default)
			)
			(fill no)
			(layer "F.CrtYd")
		)
		(fp_rect
			(start -0.508 0.9398)
			(end 0.508 -0.9398)
			(stroke
				(width 0)
				(type default)
			)
			(fill no)
			(layer "F.Fab")
		)
		(pad "1" smd custom
			(at 0 -0.4445 90)
			(size 0.1397 0.1397)
			(layers "F.Cu" "F.Mask" "F.Paste")
			(net "P3V3")
			(options
				(clearance outline)
				(anchor circle)
			)
			(primitives
				(gr_poly
					(pts
						(arc
							(start -0.1778 -0.2794)
							(mid -0.249642 -0.249642)
							(end -0.2794 -0.1778)
						)
						(arc
							(start -0.2794 0.1778)
							(mid -0.249642 0.249642)
							(end -0.1778 0.2794)
						)
						(arc
							(start 0.1778 0.2794)
							(mid 0.249642 0.249642)
							(end 0.2794 0.1778)
						)
						(arc
							(start 0.2794 -0.1778)
							(mid 0.249642 -0.249642)
							(end 0.1778 -0.2794)
						)
					)
					(width 0)
					(fill yes)
				)
			)
		)
		(pad "2" smd custom
			(at 0 0.4445 90)
			(size 0.1397 0.1397)
			(layers "F.Cu" "F.Mask" "F.Paste")
			(net "NCT7368S_SEL")
			(options
				(clearance outline)
				(anchor circle)
			)
			(primitives
				(gr_poly
					(pts
						(arc
							(start -0.1778 -0.2794)
							(mid -0.249642 -0.249642)
							(end -0.2794 -0.1778)
						)
						(arc
							(start -0.2794 0.1778)
							(mid -0.249642 0.249642)
							(end -0.1778 0.2794)
						)
						(arc
							(start 0.1778 0.2794)
							(mid 0.249642 0.249642)
							(end 0.2794 0.1778)
						)
						(arc
							(start 0.2794 -0.1778)
							(mid 0.249642 -0.249642)
							(end 0.1778 -0.2794)
						)
					)
					(width 0)
					(fill yes)
				)
			)
		)
	)
	(footprint ""
		(layer "F.Cu")
		(at 15.9258 -145.542 -90)
		(property "Reference" "C30"
			(at 0 0 270)
			(layer "F.SilkS")
			(hide yes)
			(effects
				(font
					(size 1.27 1.27)
				)
			)
		)
		(property "Value" "SCD1U16V2KX-3GP"
			(at 1.1811 -2.7051 270)
			(unlocked yes)
			(layer "F.Fab")
			(hide yes)
			(effects
				(font
					(size 1.016 1.016)
					(thickness 0.1524)
				)
			)
		)
		(property "Device Type" "C402H22"
			(at 1.1811 -4.2291 270)
			(unlocked yes)
			(layer "F.Fab")
			(hide yes)
			(effects
				(font
					(size 1.016 1.016)
					(thickness 0.1524)
				)
			)
		)
		(duplicate_pad_numbers_are_jumpers no)
		(fp_rect
			(start -0.4318 0.9525)
			(end 0.4318 -0.9525)
			(stroke
				(width 0)
				(type default)
			)
			(fill no)
			(layer "F.CrtYd")
		)
		(fp_rect
			(start -0.4318 0.9525)
			(end 0.4318 -0.9525)
			(stroke
				(width 0)
				(type default)
			)
			(fill no)
			(layer "F.Fab")
		)
		(pad "1" smd custom
			(at 0 -0.4445 270)
			(size 0.1524 0.1524)
			(layers "F.Cu" "F.Mask" "F.Paste")
			(net "FAN_TACH9")
			(options
				(clearance outline)
				(anchor circle)
			)
			(primitives
				(gr_poly
					(pts
						(arc
							(start 0.3048 -0.2032)
							(mid 0.275042 -0.275042)
							(end 0.2032 -0.3048)
						)
						(arc
							(start -0.2032 -0.3048)
							(mid -0.275042 -0.275042)
							(end -0.3048 -0.2032)
						)
						(arc
							(start -0.3048 0.2032)
							(mid -0.275042 0.275042)
							(end -0.2032 0.3048)
						)
						(arc
							(start 0.2032 0.3048)
							(mid 0.275042 0.275042)
							(end 0.3048 0.2032)
						)
					)
					(width 0)
					(fill yes)
				)
			)
		)
		(pad "2" smd custom
			(at 0 0.4445 270)
			(size 0.1524 0.1524)
			(layers "F.Cu" "F.Mask" "F.Paste")
			(net "GND")
			(options
				(clearance outline)
				(anchor circle)
			)
			(primitives
				(gr_poly
					(pts
						(arc
							(start 0.3048 -0.2032)
							(mid 0.275042 -0.275042)
							(end 0.2032 -0.3048)
						)
						(arc
							(start -0.2032 -0.3048)
							(mid -0.275042 -0.275042)
							(end -0.3048 -0.2032)
						)
						(arc
							(start -0.3048 0.2032)
							(mid -0.275042 0.275042)
							(end -0.2032 0.3048)
						)
						(arc
							(start 0.2032 0.3048)
							(mid 0.275042 0.275042)
							(end 0.3048 0.2032)
						)
					)
					(width 0)
					(fill yes)
				)
			)
		)
	)
	(footprint ""
		(layer "F.Cu")
		(at 21.7678 -218.821 90)
		(property "Reference" "R134"
			(at 0 0 90)
			(layer "F.SilkS")
			(hide yes)
			(effects
				(font
					(size 1.27 1.27)
				)
			)
		)
		(property "Value" "4K7R2F-GP"
			(at 0.064008 -3.993896 90)
			(unlocked yes)
			(layer "F.Fab")
			(hide yes)
			(effects
				(font
					(size 1.016 1.016)
					(thickness 0.1524)
				)
			)
		)
		(property "Device Type" "R402H16"
			(at 0.064008 -5.517896 90)
			(unlocked yes)
			(layer "F.Fab")
			(hide yes)
			(effects
				(font
					(size 1.016 1.016)
					(thickness 0.1524)
				)
			)
		)
		(duplicate_pad_numbers_are_jumpers no)
		(fp_line
			(start 0.508 -0.9398)
			(end -0.508 -0.9398)
			(stroke
				(width 0.1524)
				(type default)
			)
			(layer "F.SilkS")
		)
		(fp_line
			(start -0.508 -0.9398)
			(end -0.508 0.9398)
			(stroke
				(width 0.1524)
				(type default)
			)
			(layer "F.SilkS")
		)
		(fp_rect
			(start -0.508 0.9398)
			(end 0.508 -0.9398)
			(stroke
				(width 0)
				(type default)
			)
			(fill no)
			(layer "F.CrtYd")
		)
		(fp_rect
			(start -0.508 0.9398)
			(end 0.508 -0.9398)
			(stroke
				(width 0)
				(type default)
			)
			(fill no)
			(layer "F.Fab")
		)
		(pad "1" smd custom
			(at 0 -0.4445 90)
			(size 0.1397 0.1397)
			(layers "F.Cu" "F.Mask" "F.Paste")
			(net "P3V3")
			(options
				(clearance outline)
				(anchor circle)
			)
			(primitives
				(gr_poly
					(pts
						(arc
							(start -0.1778 -0.2794)
							(mid -0.249642 -0.249642)
							(end -0.2794 -0.1778)
						)
						(arc
							(start -0.2794 0.1778)
							(mid -0.249642 0.249642)
							(end -0.1778 0.2794)
						)
						(arc
							(start 0.1778 0.2794)
							(mid 0.249642 0.249642)
							(end 0.2794 0.1778)
						)
						(arc
							(start 0.2794 -0.1778)
							(mid 0.249642 -0.249642)
							(end 0.1778 -0.2794)
						)
					)
					(width 0)
					(fill yes)
				)
			)
		)
		(pad "2" smd custom
			(at 0 0.4445 90)
			(size 0.1397 0.1397)
			(layers "F.Cu" "F.Mask" "F.Paste")
			(net "PWM_OUT_FAN2")
			(options
				(clearance outline)
				(anchor circle)
			)
			(primitives
				(gr_poly
					(pts
						(arc
							(start -0.1778 -0.2794)
							(mid -0.249642 -0.249642)
							(end -0.2794 -0.1778)
						)
						(arc
							(start -0.2794 0.1778)
							(mid -0.249642 0.249642)
							(end -0.1778 0.2794)
						)
						(arc
							(start 0.1778 0.2794)
							(mid 0.249642 0.249642)
							(end 0.2794 0.1778)
						)
						(arc
							(start 0.2794 -0.1778)
							(mid 0.249642 -0.249642)
							(end 0.1778 -0.2794)
						)
					)
					(width 0)
					(fill yes)
				)
			)
		)
	)
	(footprint ""
		(layer "F.Cu")
		(at 18.8214 -145.6436 180)
		(property "Reference" "PC91"
			(at 0 0 180)
			(layer "F.SilkS")
			(hide yes)
			(effects
				(font
					(size 1.27 1.27)
				)
			)
		)
		(property "Value" "SCD01U50V3KX-4GP"
			(at 0 -2.8194 180)
			(unlocked yes)
			(layer "F.Fab")
			(hide yes)
			(effects
				(font
					(size 1.016 1.016)
					(thickness 0.1524)
				)
			)
		)
		(property "Device Type" "C603H36"
			(at 0 -4.3434 180)
			(unlocked yes)
			(layer "F.Fab")
			(hide yes)
			(effects
				(font
					(size 1.016 1.016)
					(thickness 0.1524)
				)
			)
		)
		(duplicate_pad_numbers_are_jumpers no)
		(fp_line
			(start 0.508 0)
			(end -0.508 0)
			(stroke
				(width 0.2032)
				(type default)
			)
			(layer "F.SilkS")
		)
		(fp_rect
			(start -0.5842 1.3335)
			(end 0.5842 -1.3335)
			(stroke
				(width 0)
				(type default)
			)
			(fill no)
			(layer "F.CrtYd")
		)
		(fp_rect
			(start -0.5842 1.3335)
			(end 0.5842 -1.3335)
			(stroke
				(width 0)
				(type default)
			)
			(fill no)
			(layer "F.Fab")
		)
		(pad "1" smd custom
			(at 0 -0.762 180)
			(size 0.2159 0.2159)
			(layers "F.Cu" "F.Mask" "F.Paste")
			(net "P12VU_2490_TIMER")
			(options
				(clearance outline)
				(anchor circle)
			)
			(primitives
				(gr_poly
					(pts
						(arc
							(start -0.3302 -0.4318)
							(mid -0.402042 -0.402042)
							(end -0.4318 -0.3302)
						)
						(arc
							(start -0.4318 0.3302)
							(mid -0.402042 0.402042)
							(end -0.3302 0.4318)
						)
						(arc
							(start 0.3302 0.4318)
							(mid 0.402042 0.402042)
							(end 0.4318 0.3302)
						)
						(arc
							(start 0.4318 -0.3302)
							(mid 0.402042 -0.402042)
							(end 0.3302 -0.4318)
						)
					)
					(width 0)
					(fill yes)
				)
			)
		)
		(pad "2" smd custom
			(at 0 0.762 180)
			(size 0.2159 0.2159)
			(layers "F.Cu" "F.Mask" "F.Paste")
			(net "GND")
			(options
				(clearance outline)
				(anchor circle)
			)
			(primitives
				(gr_poly
					(pts
						(arc
							(start -0.3302 -0.4318)
							(mid -0.402042 -0.402042)
							(end -0.4318 -0.3302)
						)
						(arc
							(start -0.4318 0.3302)
							(mid -0.402042 0.402042)
							(end -0.3302 0.4318)
						)
						(arc
							(start 0.3302 0.4318)
							(mid 0.402042 0.402042)
							(end 0.4318 0.3302)
						)
						(arc
							(start 0.4318 -0.3302)
							(mid 0.402042 -0.402042)
							(end 0.3302 -0.4318)
						)
					)
					(width 0)
					(fill yes)
				)
			)
		)
	)
	(footprint ""
		(layer "F.Cu")
		(at 9.906 -261.112 180)
		(property "Reference" "R125"
			(at 0 0 180)
			(layer "F.SilkS")
			(hide yes)
			(effects
				(font
					(size 1.27 1.27)
				)
			)
		)
		(property "Value" "1K8R6J-GP"
			(at -0.0508 -4.8514 180)
			(unlocked yes)
			(layer "F.Fab")
			(hide yes)
			(effects
				(font
					(size 1.016 1.016)
					(thickness 0.1524)
				)
			)
		)
		(property "Device Type" "R1206H28"
			(at 0 -6.3754 180)
			(unlocked yes)
			(layer "F.Fab")
			(hide yes)
			(effects
				(font
					(size 1.016 1.016)
					(thickness 0.1524)
				)
			)
		)
		(duplicate_pad_numbers_are_jumpers no)
		(fp_line
			(start 1.016 2.2352)
			(end -1.016 2.2352)
			(stroke
				(width 0.1524)
				(type default)
			)
			(layer "F.SilkS")
		)
		(fp_line
			(start 1.016 -2.2352)
			(end 1.016 2.2352)
			(stroke
				(width 0.1524)
				(type default)
			)
			(layer "F.SilkS")
		)
		(fp_line
			(start -1.016 2.2352)
			(end -1.016 -2.2352)
			(stroke
				(width 0.1524)
				(type default)
			)
			(layer "F.SilkS")
		)
		(fp_line
			(start -1.016 -2.2352)
			(end 1.016 -2.2352)
			(stroke
				(width 0.1524)
				(type default)
			)
			(layer "F.SilkS")
		)
		(fp_rect
			(start -1.0922 2.3114)
			(end 1.0922 -2.3114)
			(stroke
				(width 0)
				(type default)
			)
			(fill no)
			(layer "F.CrtYd")
		)
		(fp_poly
			(pts
				(xy -1.0922 -2.3114) (xy 1.0922 -2.3114) (xy 1.0922 2.3114) (xy -1.0922 2.3114)
			)
			(stroke
				(width 0)
				(type default)
			)
			(fill no)
			(layer "F.Fab")
		)
		(pad "1" smd rect
			(at 0 -1.397 180)
			(size 1.651 1.27)
			(layers "F.Cu" "F.Mask" "F.Paste")
			(net "P12V")
		)
		(pad "2" smd rect
			(at 0 1.397 180)
			(size 1.651 1.27)
			(layers "F.Cu" "F.Mask" "F.Paste")
			(net "LED_DR_LED2_BLUE")
		)
	)
	(footprint ""
		(layer "F.Cu")
		(at 35.687 -240.3094 180)
		(property "Reference" "R56"
			(at 0 0 180)
			(layer "F.SilkS")
			(hide yes)
			(effects
				(font
					(size 1.27 1.27)
				)
			)
		)
		(property "Value" "4K7R2J-2-GP"
			(at 0.064008 -3.993896 180)
			(unlocked yes)
			(layer "F.Fab")
			(hide yes)
			(effects
				(font
					(size 1.016 1.016)
					(thickness 0.1524)
				)
			)
		)
		(property "Device Type" "R402H16"
			(at 0.064008 -5.517896 180)
			(unlocked yes)
			(layer "F.Fab")
			(hide yes)
			(effects
				(font
					(size 1.016 1.016)
					(thickness 0.1524)
				)
			)
		)
		(duplicate_pad_numbers_are_jumpers no)
		(fp_line
			(start 0.508 -0.9398)
			(end -0.508 -0.9398)
			(stroke
				(width 0.1524)
				(type default)
			)
			(layer "F.SilkS")
		)
		(fp_line
			(start -0.508 -0.9398)
			(end -0.508 0.9398)
			(stroke
				(width 0.1524)
				(type default)
			)
			(layer "F.SilkS")
		)
		(fp_rect
			(start -0.508 0.9398)
			(end 0.508 -0.9398)
			(stroke
				(width 0)
				(type default)
			)
			(fill no)
			(layer "F.CrtYd")
		)
		(fp_rect
			(start -0.508 0.9398)
			(end 0.508 -0.9398)
			(stroke
				(width 0)
				(type default)
			)
			(fill no)
			(layer "F.Fab")
		)
		(pad "1" smd custom
			(at 0 -0.4445 180)
			(size 0.1397 0.1397)
			(layers "F.Cu" "F.Mask" "F.Paste")
			(net "GND")
			(options
				(clearance outline)
				(anchor circle)
			)
			(primitives
				(gr_poly
					(pts
						(arc
							(start -0.1778 -0.2794)
							(mid -0.249642 -0.249642)
							(end -0.2794 -0.1778)
						)
						(arc
							(start -0.2794 0.1778)
							(mid -0.249642 0.249642)
							(end -0.1778 0.2794)
						)
						(arc
							(start 0.1778 0.2794)
							(mid 0.249642 0.249642)
							(end 0.2794 0.1778)
						)
						(arc
							(start 0.2794 -0.1778)
							(mid 0.249642 -0.249642)
							(end 0.1778 -0.2794)
						)
					)
					(width 0)
					(fill yes)
				)
			)
		)
		(pad "2" smd custom
			(at 0 0.4445 180)
			(size 0.1397 0.1397)
			(layers "F.Cu" "F.Mask" "F.Paste")
			(net "LED_DRV_A2")
			(options
				(clearance outline)
				(anchor circle)
			)
			(primitives
				(gr_poly
					(pts
						(arc
							(start -0.1778 -0.2794)
							(mid -0.249642 -0.249642)
							(end -0.2794 -0.1778)
						)
						(arc
							(start -0.2794 0.1778)
							(mid -0.249642 0.249642)
							(end -0.1778 0.2794)
						)
						(arc
							(start 0.1778 0.2794)
							(mid 0.249642 0.249642)
							(end 0.2794 0.1778)
						)
						(arc
							(start 0.2794 -0.1778)
							(mid 0.249642 -0.249642)
							(end 0.1778 -0.2794)
						)
					)
					(width 0)
					(fill yes)
				)
			)
		)
	)
	(footprint ""
		(layer "F.Cu")
		(at 16.4592 -260.35 -90)
		(property "Reference" "R84"
			(at 0 0 270)
			(layer "F.SilkS")
			(hide yes)
			(effects
				(font
					(size 1.27 1.27)
				)
			)
		)
		(property "Value" "27KR3F-GP"
			(at -0.0254 -2.5146 270)
			(unlocked yes)
			(layer "F.Fab")
			(hide yes)
			(effects
				(font
					(size 1.016 1.016)
					(thickness 0.1524)
				)
			)
		)
		(property "Device Type" "R603H22"
			(at -0.0254 -4.0386 270)
			(unlocked yes)
			(layer "F.Fab")
			(hide yes)
			(effects
				(font
					(size 1.016 1.016)
					(thickness 0.1524)
				)
			)
		)
		(duplicate_pad_numbers_are_jumpers no)
		(fp_line
			(start -0.4826 0)
			(end -0.2032 0)
			(stroke
				(width 0.2032)
				(type default)
			)
			(layer "F.SilkS")
		)
		(fp_line
			(start 0.2032 0)
			(end 0.4826 0)
			(stroke
				(width 0.2032)
				(type default)
			)
			(layer "F.SilkS")
		)
		(fp_rect
			(start -0.5842 1.3335)
			(end 0.5842 -1.3335)
			(stroke
				(width 0)
				(type default)
			)
			(fill no)
			(layer "F.CrtYd")
		)
		(fp_rect
			(start -0.5842 1.3335)
			(end 0.5842 -1.3335)
			(stroke
				(width 0)
				(type default)
			)
			(fill no)
			(layer "F.Fab")
		)
		(pad "1" smd custom
			(at 0 -0.762 270)
			(size 0.2159 0.2159)
			(layers "F.Cu" "F.Mask" "F.Paste")
			(net "FAN_TACH6")
			(options
				(clearance outline)
				(anchor circle)
			)
			(primitives
				(gr_poly
					(pts
						(arc
							(start -0.3302 -0.4318)
							(mid -0.402042 -0.402042)
							(end -0.4318 -0.3302)
						)
						(arc
							(start -0.4318 0.3302)
							(mid -0.402042 0.402042)
							(end -0.3302 0.4318)
						)
						(arc
							(start 0.3302 0.4318)
							(mid 0.402042 0.402042)
							(end 0.4318 0.3302)
						)
						(arc
							(start 0.4318 -0.3302)
							(mid 0.402042 -0.402042)
							(end 0.3302 -0.4318)
						)
					)
					(width 0)
					(fill yes)
				)
			)
		)
		(pad "2" smd custom
			(at 0 0.762 270)
			(size 0.2159 0.2159)
			(layers "F.Cu" "F.Mask" "F.Paste")
			(net "FANIN_6")
			(options
				(clearance outline)
				(anchor circle)
			)
			(primitives
				(gr_poly
					(pts
						(arc
							(start -0.3302 -0.4318)
							(mid -0.402042 -0.402042)
							(end -0.4318 -0.3302)
						)
						(arc
							(start -0.4318 0.3302)
							(mid -0.402042 0.402042)
							(end -0.3302 0.4318)
						)
						(arc
							(start 0.3302 0.4318)
							(mid 0.402042 0.402042)
							(end 0.4318 0.3302)
						)
						(arc
							(start 0.4318 -0.3302)
							(mid 0.402042 -0.402042)
							(end 0.3302 -0.4318)
						)
					)
					(width 0)
					(fill yes)
				)
			)
		)
	)
	(footprint ""
		(layer "F.Cu")
		(at 14.4526 -60.5282)
		(property "Reference" "R362"
			(at 0 0 0)
			(layer "F.SilkS")
			(hide yes)
			(effects
				(font
					(size 1.27 1.27)
				)
			)
		)
		(property "Value" "100R2J-2-GP"
			(at 0.064008 -3.993896 0)
			(unlocked yes)
			(layer "F.Fab")
			(hide yes)
			(effects
				(font
					(size 1.016 1.016)
					(thickness 0.1524)
				)
			)
		)
		(property "Device Type" "R402H14"
			(at 0.064008 -5.517896 0)
			(unlocked yes)
			(layer "F.Fab")
			(hide yes)
			(effects
				(font
					(size 1.016 1.016)
					(thickness 0.1524)
				)
			)
		)
		(duplicate_pad_numbers_are_jumpers no)
		(fp_line
			(start -0.508 -0.9398)
			(end -0.508 0.9398)
			(stroke
				(width 0.1524)
				(type default)
			)
			(layer "F.SilkS")
		)
		(fp_line
			(start 0.508 -0.9398)
			(end -0.508 -0.9398)
			(stroke
				(width 0.1524)
				(type default)
			)
			(layer "F.SilkS")
		)
		(fp_rect
			(start -0.508 0.9398)
			(end 0.508 -0.9398)
			(stroke
				(width 0)
				(type default)
			)
			(fill no)
			(layer "F.CrtYd")
		)
		(fp_rect
			(start -0.508 0.9398)
			(end 0.508 -0.9398)
			(stroke
				(width 0)
				(type default)
			)
			(fill no)
			(layer "F.Fab")
		)
		(pad "1" smd custom
			(at 0 -0.4445)
			(size 0.1397 0.1397)
			(layers "F.Cu" "F.Mask" "F.Paste")
			(net "UPPER_TRAY_ID")
			(options
				(clearance outline)
				(anchor circle)
			)
			(primitives
				(gr_poly
					(pts
						(arc
							(start -0.1778 -0.2794)
							(mid -0.249642 -0.249642)
							(end -0.2794 -0.1778)
						)
						(arc
							(start -0.2794 0.1778)
							(mid -0.249642 0.249642)
							(end -0.1778 0.2794)
						)
						(arc
							(start 0.1778 0.2794)
							(mid 0.249642 0.249642)
							(end 0.2794 0.1778)
						)
						(arc
							(start 0.2794 -0.1778)
							(mid 0.249642 -0.249642)
							(end 0.1778 -0.2794)
						)
					)
					(width 0)
					(fill yes)
				)
			)
		)
		(pad "2" smd custom
			(at 0 0.4445)
			(size 0.1397 0.1397)
			(layers "F.Cu" "F.Mask" "F.Paste")
			(net "GND")
			(options
				(clearance outline)
				(anchor circle)
			)
			(primitives
				(gr_poly
					(pts
						(arc
							(start -0.1778 -0.2794)
							(mid -0.249642 -0.249642)
							(end -0.2794 -0.1778)
						)
						(arc
							(start -0.2794 0.1778)
							(mid -0.249642 0.249642)
							(end -0.1778 0.2794)
						)
						(arc
							(start 0.1778 0.2794)
							(mid 0.249642 0.249642)
							(end 0.2794 0.1778)
						)
						(arc
							(start 0.2794 -0.1778)
							(mid 0.249642 -0.249642)
							(end 0.1778 -0.2794)
						)
					)
					(width 0)
					(fill yes)
				)
			)
		)
	)
	(footprint ""
		(layer "F.Cu")
		(at 7.8232 -83.439 90)
		(property "Reference" "R123"
			(at 0 0 90)
			(layer "F.SilkS")
			(hide yes)
			(effects
				(font
					(size 1.27 1.27)
				)
			)
		)
		(property "Value" "1K8R6J-GP"
			(at -0.0508 -4.8514 90)
			(unlocked yes)
			(layer "F.Fab")
			(hide yes)
			(effects
				(font
					(size 1.016 1.016)
					(thickness 0.1524)
				)
			)
		)
		(property "Device Type" "R1206H28"
			(at 0 -6.3754 90)
			(unlocked yes)
			(layer "F.Fab")
			(hide yes)
			(effects
				(font
					(size 1.016 1.016)
					(thickness 0.1524)
				)
			)
		)
		(duplicate_pad_numbers_are_jumpers no)
		(fp_line
			(start 1.016 -2.2352)
			(end 1.016 2.2352)
			(stroke
				(width 0.1524)
				(type default)
			)
			(layer "F.SilkS")
		)
		(fp_line
			(start -1.016 -2.2352)
			(end 1.016 -2.2352)
			(stroke
				(width 0.1524)
				(type default)
			)
			(layer "F.SilkS")
		)
		(fp_line
			(start 1.016 2.2352)
			(end -1.016 2.2352)
			(stroke
				(width 0.1524)
				(type default)
			)
			(layer "F.SilkS")
		)
		(fp_line
			(start -1.016 2.2352)
			(end -1.016 -2.2352)
			(stroke
				(width 0.1524)
				(type default)
			)
			(layer "F.SilkS")
		)
		(fp_rect
			(start -1.0922 2.3114)
			(end 1.0922 -2.3114)
			(stroke
				(width 0)
				(type default)
			)
			(fill no)
			(layer "F.CrtYd")
		)
		(fp_poly
			(pts
				(xy -1.0922 -2.3114) (xy 1.0922 -2.3114) (xy 1.0922 2.3114) (xy -1.0922 2.3114)
			)
			(stroke
				(width 0)
				(type default)
			)
			(fill no)
			(layer "F.Fab")
		)
		(pad "1" smd rect
			(at 0 -1.397 90)
			(size 1.651 1.27)
			(layers "F.Cu" "F.Mask" "F.Paste")
			(net "P12V")
		)
		(pad "2" smd rect
			(at 0 1.397 90)
			(size 1.651 1.27)
			(layers "F.Cu" "F.Mask" "F.Paste")
			(net "LED_DR_LED4_BLUE")
		)
	)
	(footprint ""
		(layer "F.Cu")
		(at 23.48611 -154.602434)
		(property "Reference" "R4"
			(at 0 0 0)
			(layer "F.SilkS")
			(hide yes)
			(effects
				(font
					(size 1.27 1.27)
				)
			)
		)
		(property "Value" "0R2J-2-GP"
			(at 0.064008 -3.993896 0)
			(unlocked yes)
			(layer "F.Fab")
			(hide yes)
			(effects
				(font
					(size 1.016 1.016)
					(thickness 0.1524)
				)
			)
		)
		(property "Device Type" "R402H16"
			(at 0.064008 -5.517896 0)
			(unlocked yes)
			(layer "F.Fab")
			(hide yes)
			(effects
				(font
					(size 1.016 1.016)
					(thickness 0.1524)
				)
			)
		)
		(duplicate_pad_numbers_are_jumpers no)
		(fp_line
			(start -0.508 -0.9398)
			(end -0.508 0.9398)
			(stroke
				(width 0.1524)
				(type default)
			)
			(layer "F.SilkS")
		)
		(fp_line
			(start 0.508 -0.9398)
			(end -0.508 -0.9398)
			(stroke
				(width 0.1524)
				(type default)
			)
			(layer "F.SilkS")
		)
		(fp_rect
			(start -0.508 0.9398)
			(end 0.508 -0.9398)
			(stroke
				(width 0)
				(type default)
			)
			(fill no)
			(layer "F.CrtYd")
		)
		(fp_rect
			(start -0.508 0.9398)
			(end 0.508 -0.9398)
			(stroke
				(width 0)
				(type default)
			)
			(fill no)
			(layer "F.Fab")
		)
		(pad "1" smd custom
			(at 0 -0.4445)
			(size 0.1397 0.1397)
			(layers "F.Cu" "F.Mask" "F.Paste")
			(net "NCT7904_TMPALM")
			(options
				(clearance outline)
				(anchor circle)
			)
			(primitives
				(gr_poly
					(pts
						(arc
							(start -0.1778 -0.2794)
							(mid -0.249642 -0.249642)
							(end -0.2794 -0.1778)
						)
						(arc
							(start -0.2794 0.1778)
							(mid -0.249642 0.249642)
							(end -0.1778 0.2794)
						)
						(arc
							(start 0.1778 0.2794)
							(mid 0.249642 0.249642)
							(end 0.2794 0.1778)
						)
						(arc
							(start 0.2794 -0.1778)
							(mid 0.249642 -0.249642)
							(end 0.1778 -0.2794)
						)
					)
					(width 0)
					(fill yes)
				)
			)
		)
		(pad "2" smd custom
			(at 0 0.4445)
			(size 0.1397 0.1397)
			(layers "F.Cu" "F.Mask" "F.Paste")
			(net "TEMP_ALM#")
			(options
				(clearance outline)
				(anchor circle)
			)
			(primitives
				(gr_poly
					(pts
						(arc
							(start -0.1778 -0.2794)
							(mid -0.249642 -0.249642)
							(end -0.2794 -0.1778)
						)
						(arc
							(start -0.2794 0.1778)
							(mid -0.249642 0.249642)
							(end -0.1778 0.2794)
						)
						(arc
							(start 0.1778 0.2794)
							(mid 0.249642 0.249642)
							(end 0.2794 0.1778)
						)
						(arc
							(start 0.2794 -0.1778)
							(mid 0.249642 -0.249642)
							(end 0.1778 -0.2794)
						)
					)
					(width 0)
					(fill yes)
				)
			)
		)
	)
	(footprint ""
		(layer "F.Cu")
		(at 44.704 -158.5722 -90)
		(property "Reference" "R14"
			(at 0 0 270)
			(layer "F.SilkS")
			(hide yes)
			(effects
				(font
					(size 1.27 1.27)
				)
			)
		)
		(property "Value" "110KR2F-L-GP"
			(at 0.064008 -3.993896 270)
			(unlocked yes)
			(layer "F.Fab")
			(hide yes)
			(effects
				(font
					(size 1.016 1.016)
					(thickness 0.1524)
				)
			)
		)
		(property "Device Type" "R402H16"
			(at 0.064008 -5.517896 270)
			(unlocked yes)
			(layer "F.Fab")
			(hide yes)
			(effects
				(font
					(size 1.016 1.016)
					(thickness 0.1524)
				)
			)
		)
		(duplicate_pad_numbers_are_jumpers no)
		(fp_line
			(start -0.508 -0.9398)
			(end -0.508 0.9398)
			(stroke
				(width 0.1524)
				(type default)
			)
			(layer "F.SilkS")
		)
		(fp_line
			(start 0.508 -0.9398)
			(end -0.508 -0.9398)
			(stroke
				(width 0.1524)
				(type default)
			)
			(layer "F.SilkS")
		)
		(fp_rect
			(start -0.508 0.9398)
			(end 0.508 -0.9398)
			(stroke
				(width 0)
				(type default)
			)
			(fill no)
			(layer "F.CrtYd")
		)
		(fp_rect
			(start -0.508 0.9398)
			(end 0.508 -0.9398)
			(stroke
				(width 0)
				(type default)
			)
			(fill no)
			(layer "F.Fab")
		)
		(pad "1" smd custom
			(at 0 -0.4445 270)
			(size 0.1397 0.1397)
			(layers "F.Cu" "F.Mask" "F.Paste")
			(net "P12V_AUX")
			(options
				(clearance outline)
				(anchor circle)
			)
			(primitives
				(gr_poly
					(pts
						(arc
							(start -0.1778 -0.2794)
							(mid -0.249642 -0.249642)
							(end -0.2794 -0.1778)
						)
						(arc
							(start -0.2794 0.1778)
							(mid -0.249642 0.249642)
							(end -0.1778 0.2794)
						)
						(arc
							(start 0.1778 0.2794)
							(mid 0.249642 0.249642)
							(end 0.2794 0.1778)
						)
						(arc
							(start 0.2794 -0.1778)
							(mid 0.249642 -0.249642)
							(end 0.1778 -0.2794)
						)
					)
					(width 0)
					(fill yes)
				)
			)
		)
		(pad "2" smd custom
			(at 0 0.4445 270)
			(size 0.1397 0.1397)
			(layers "F.Cu" "F.Mask" "F.Paste")
			(net "NCT7904_VSEN_P12V_AUX")
			(options
				(clearance outline)
				(anchor circle)
			)
			(primitives
				(gr_poly
					(pts
						(arc
							(start -0.1778 -0.2794)
							(mid -0.249642 -0.249642)
							(end -0.2794 -0.1778)
						)
						(arc
							(start -0.2794 0.1778)
							(mid -0.249642 0.249642)
							(end -0.1778 0.2794)
						)
						(arc
							(start 0.1778 0.2794)
							(mid 0.249642 0.249642)
							(end 0.2794 0.1778)
						)
						(arc
							(start 0.2794 -0.1778)
							(mid 0.249642 -0.249642)
							(end 0.1778 -0.2794)
						)
					)
					(width 0)
					(fill yes)
				)
			)
		)
	)
	(footprint ""
		(layer "F.Cu")
		(at 31.242 -361.315 180)
		(property "Reference" "R109"
			(at 0 0 180)
			(layer "F.SilkS")
			(hide yes)
			(effects
				(font
					(size 1.27 1.27)
				)
			)
		)
		(property "Value" "0R2J-2-GP"
			(at 0.064008 -3.993896 180)
			(unlocked yes)
			(layer "F.Fab")
			(hide yes)
			(effects
				(font
					(size 1.016 1.016)
					(thickness 0.1524)
				)
			)
		)
		(property "Device Type" "R402H16"
			(at 0.064008 -5.517896 180)
			(unlocked yes)
			(layer "F.Fab")
			(hide yes)
			(effects
				(font
					(size 1.016 1.016)
					(thickness 0.1524)
				)
			)
		)
		(duplicate_pad_numbers_are_jumpers no)
		(fp_line
			(start 0.508 -0.9398)
			(end -0.508 -0.9398)
			(stroke
				(width 0.1524)
				(type default)
			)
			(layer "F.SilkS")
		)
		(fp_line
			(start -0.508 -0.9398)
			(end -0.508 0.9398)
			(stroke
				(width 0.1524)
				(type default)
			)
			(layer "F.SilkS")
		)
		(fp_rect
			(start -0.508 0.9398)
			(end 0.508 -0.9398)
			(stroke
				(width 0)
				(type default)
			)
			(fill no)
			(layer "F.CrtYd")
		)
		(fp_rect
			(start -0.508 0.9398)
			(end 0.508 -0.9398)
			(stroke
				(width 0)
				(type default)
			)
			(fill no)
			(layer "F.Fab")
		)
		(pad "1" smd custom
			(at 0 -0.4445 180)
			(size 0.1397 0.1397)
			(layers "F.Cu" "F.Mask" "F.Paste")
			(net "I2C_C_SDA")
			(options
				(clearance outline)
				(anchor circle)
			)
			(primitives
				(gr_poly
					(pts
						(arc
							(start -0.1778 -0.2794)
							(mid -0.249642 -0.249642)
							(end -0.2794 -0.1778)
						)
						(arc
							(start -0.2794 0.1778)
							(mid -0.249642 0.249642)
							(end -0.1778 0.2794)
						)
						(arc
							(start 0.1778 0.2794)
							(mid 0.249642 0.249642)
							(end 0.2794 0.1778)
						)
						(arc
							(start 0.2794 -0.1778)
							(mid 0.249642 -0.249642)
							(end 0.1778 -0.2794)
						)
					)
					(width 0)
					(fill yes)
				)
			)
		)
		(pad "2" smd custom
			(at 0 0.4445 180)
			(size 0.1397 0.1397)
			(layers "F.Cu" "F.Mask" "F.Paste")
			(net "I2C_C_SDA_ADM1276")
			(options
				(clearance outline)
				(anchor circle)
			)
			(primitives
				(gr_poly
					(pts
						(arc
							(start -0.1778 -0.2794)
							(mid -0.249642 -0.249642)
							(end -0.2794 -0.1778)
						)
						(arc
							(start -0.2794 0.1778)
							(mid -0.249642 0.249642)
							(end -0.1778 0.2794)
						)
						(arc
							(start 0.1778 0.2794)
							(mid 0.249642 0.249642)
							(end 0.2794 0.1778)
						)
						(arc
							(start 0.2794 -0.1778)
							(mid 0.249642 -0.249642)
							(end 0.1778 -0.2794)
						)
					)
					(width 0)
					(fill yes)
				)
			)
		)
	)
	(footprint ""
		(layer "F.Cu")
		(at 42.0116 -362.839 180)
		(property "Reference" "PR49"
			(at 0 0 180)
			(layer "F.SilkS")
			(hide yes)
			(effects
				(font
					(size 1.27 1.27)
				)
			)
		)
		(property "Value" "4K7R2J-2-GP"
			(at 0.064008 -3.993896 180)
			(unlocked yes)
			(layer "F.Fab")
			(hide yes)
			(effects
				(font
					(size 1.016 1.016)
					(thickness 0.1524)
				)
			)
		)
		(property "Device Type" "R402H16"
			(at 0.064008 -5.517896 180)
			(unlocked yes)
			(layer "F.Fab")
			(hide yes)
			(effects
				(font
					(size 1.016 1.016)
					(thickness 0.1524)
				)
			)
		)
		(duplicate_pad_numbers_are_jumpers no)
		(fp_line
			(start 0.508 -0.9398)
			(end -0.508 -0.9398)
			(stroke
				(width 0.1524)
				(type default)
			)
			(layer "F.SilkS")
		)
		(fp_line
			(start -0.508 -0.9398)
			(end -0.508 0.9398)
			(stroke
				(width 0.1524)
				(type default)
			)
			(layer "F.SilkS")
		)
		(fp_rect
			(start -0.508 0.9398)
			(end 0.508 -0.9398)
			(stroke
				(width 0)
				(type default)
			)
			(fill no)
			(layer "F.CrtYd")
		)
		(fp_rect
			(start -0.508 0.9398)
			(end 0.508 -0.9398)
			(stroke
				(width 0)
				(type default)
			)
			(fill no)
			(layer "F.Fab")
		)
		(pad "1" smd custom
			(at 0 -0.4445 180)
			(size 0.1397 0.1397)
			(layers "F.Cu" "F.Mask" "F.Paste")
			(net "GND")
			(options
				(clearance outline)
				(anchor circle)
			)
			(primitives
				(gr_poly
					(pts
						(arc
							(start -0.1778 -0.2794)
							(mid -0.249642 -0.249642)
							(end -0.2794 -0.1778)
						)
						(arc
							(start -0.2794 0.1778)
							(mid -0.249642 0.249642)
							(end -0.1778 0.2794)
						)
						(arc
							(start 0.1778 0.2794)
							(mid 0.249642 0.249642)
							(end 0.2794 0.1778)
						)
						(arc
							(start 0.2794 -0.1778)
							(mid 0.249642 -0.249642)
							(end 0.1778 -0.2794)
						)
					)
					(width 0)
					(fill yes)
				)
			)
		)
		(pad "2" smd custom
			(at 0 0.4445 180)
			(size 0.1397 0.1397)
			(layers "F.Cu" "F.Mask" "F.Paste")
			(net "ADM1276_LATCH#")
			(options
				(clearance outline)
				(anchor circle)
			)
			(primitives
				(gr_poly
					(pts
						(arc
							(start -0.1778 -0.2794)
							(mid -0.249642 -0.249642)
							(end -0.2794 -0.1778)
						)
						(arc
							(start -0.2794 0.1778)
							(mid -0.249642 0.249642)
							(end -0.1778 0.2794)
						)
						(arc
							(start 0.1778 0.2794)
							(mid 0.249642 0.249642)
							(end 0.2794 0.1778)
						)
						(arc
							(start 0.2794 -0.1778)
							(mid 0.249642 -0.249642)
							(end 0.1778 -0.2794)
						)
					)
					(width 0)
					(fill yes)
				)
			)
		)
	)
	(footprint ""
		(layer "F.Cu")
		(at 26.4922 -250.444 -90)
		(property "Reference" "C14"
			(at 0 0 270)
			(layer "F.SilkS")
			(hide yes)
			(effects
				(font
					(size 1.27 1.27)
				)
			)
		)
		(property "Value" "SCD1U50V3KX-GP"
			(at 0 -2.8194 270)
			(unlocked yes)
			(layer "F.Fab")
			(hide yes)
			(effects
				(font
					(size 1.016 1.016)
					(thickness 0.1524)
				)
			)
		)
		(property "Device Type" "C603H36"
			(at 0 -4.3434 270)
			(unlocked yes)
			(layer "F.Fab")
			(hide yes)
			(effects
				(font
					(size 1.016 1.016)
					(thickness 0.1524)
				)
			)
		)
		(duplicate_pad_numbers_are_jumpers no)
		(fp_line
			(start 0.508 0)
			(end -0.508 0)
			(stroke
				(width 0.2032)
				(type default)
			)
			(layer "F.SilkS")
		)
		(fp_rect
			(start -0.5842 1.3335)
			(end 0.5842 -1.3335)
			(stroke
				(width 0)
				(type default)
			)
			(fill no)
			(layer "F.CrtYd")
		)
		(fp_rect
			(start -0.5842 1.3335)
			(end 0.5842 -1.3335)
			(stroke
				(width 0)
				(type default)
			)
			(fill no)
			(layer "F.Fab")
		)
		(pad "1" smd custom
			(at 0 -0.762 270)
			(size 0.2159 0.2159)
			(layers "F.Cu" "F.Mask" "F.Paste")
			(net "P3V3")
			(options
				(clearance outline)
				(anchor circle)
			)
			(primitives
				(gr_poly
					(pts
						(arc
							(start -0.3302 -0.4318)
							(mid -0.402042 -0.402042)
							(end -0.4318 -0.3302)
						)
						(arc
							(start -0.4318 0.3302)
							(mid -0.402042 0.402042)
							(end -0.3302 0.4318)
						)
						(arc
							(start 0.3302 0.4318)
							(mid 0.402042 0.402042)
							(end 0.4318 0.3302)
						)
						(arc
							(start 0.4318 -0.3302)
							(mid 0.402042 -0.402042)
							(end 0.3302 -0.4318)
						)
					)
					(width 0)
					(fill yes)
				)
			)
		)
		(pad "2" smd custom
			(at 0 0.762 270)
			(size 0.2159 0.2159)
			(layers "F.Cu" "F.Mask" "F.Paste")
			(net "GND")
			(options
				(clearance outline)
				(anchor circle)
			)
			(primitives
				(gr_poly
					(pts
						(arc
							(start -0.3302 -0.4318)
							(mid -0.402042 -0.402042)
							(end -0.4318 -0.3302)
						)
						(arc
							(start -0.4318 0.3302)
							(mid -0.402042 0.402042)
							(end -0.3302 0.4318)
						)
						(arc
							(start 0.3302 0.4318)
							(mid 0.402042 0.402042)
							(end 0.4318 0.3302)
						)
						(arc
							(start 0.4318 -0.3302)
							(mid 0.402042 -0.402042)
							(end 0.3302 -0.4318)
						)
					)
					(width 0)
					(fill yes)
				)
			)
		)
	)
	(footprint ""
		(layer "F.Cu")
		(at 29.718 -381 180)
		(property "Reference" "PR19"
			(at 0 0 180)
			(layer "F.SilkS")
			(hide yes)
			(effects
				(font
					(size 1.27 1.27)
				)
			)
		)
		(property "Value" "10R2F-L-GP"
			(at 0.064008 -3.993896 180)
			(unlocked yes)
			(layer "F.Fab")
			(hide yes)
			(effects
				(font
					(size 1.016 1.016)
					(thickness 0.1524)
				)
			)
		)
		(property "Device Type" "R402H14"
			(at 0.064008 -5.517896 180)
			(unlocked yes)
			(layer "F.Fab")
			(hide yes)
			(effects
				(font
					(size 1.016 1.016)
					(thickness 0.1524)
				)
			)
		)
		(duplicate_pad_numbers_are_jumpers no)
		(fp_line
			(start 0.508 -0.9398)
			(end -0.508 -0.9398)
			(stroke
				(width 0.1524)
				(type default)
			)
			(layer "F.SilkS")
		)
		(fp_line
			(start -0.508 -0.9398)
			(end -0.508 0.9398)
			(stroke
				(width 0.1524)
				(type default)
			)
			(layer "F.SilkS")
		)
		(fp_rect
			(start -0.508 0.9398)
			(end 0.508 -0.9398)
			(stroke
				(width 0)
				(type default)
			)
			(fill no)
			(layer "F.CrtYd")
		)
		(fp_rect
			(start -0.508 0.9398)
			(end 0.508 -0.9398)
			(stroke
				(width 0)
				(type default)
			)
			(fill no)
			(layer "F.Fab")
		)
		(pad "1" smd custom
			(at 0 -0.4445 180)
			(size 0.1397 0.1397)
			(layers "F.Cu" "F.Mask" "F.Paste")
			(net "ADM1276_SENSE+")
			(options
				(clearance outline)
				(anchor circle)
			)
			(primitives
				(gr_poly
					(pts
						(arc
							(start -0.1778 -0.2794)
							(mid -0.249642 -0.249642)
							(end -0.2794 -0.1778)
						)
						(arc
							(start -0.2794 0.1778)
							(mid -0.249642 0.249642)
							(end -0.1778 0.2794)
						)
						(arc
							(start 0.1778 0.2794)
							(mid 0.249642 0.249642)
							(end 0.2794 0.1778)
						)
						(arc
							(start 0.2794 -0.1778)
							(mid 0.249642 -0.249642)
							(end 0.1778 -0.2794)
						)
					)
					(width 0)
					(fill yes)
				)
			)
		)
		(pad "2" smd custom
			(at 0 0.4445 180)
			(size 0.1397 0.1397)
			(layers "F.Cu" "F.Mask" "F.Paste")
			(net "SENSE+_R2")
			(options
				(clearance outline)
				(anchor circle)
			)
			(primitives
				(gr_poly
					(pts
						(arc
							(start -0.1778 -0.2794)
							(mid -0.249642 -0.249642)
							(end -0.2794 -0.1778)
						)
						(arc
							(start -0.2794 0.1778)
							(mid -0.249642 0.249642)
							(end -0.1778 0.2794)
						)
						(arc
							(start 0.1778 0.2794)
							(mid 0.249642 0.249642)
							(end 0.2794 0.1778)
						)
						(arc
							(start 0.2794 -0.1778)
							(mid 0.249642 -0.249642)
							(end 0.1778 -0.2794)
						)
					)
					(width 0)
					(fill yes)
				)
			)
		)
	)
	(footprint ""
		(layer "F.Cu")
		(at 39.064184 -360.4768 90)
		(property "Reference" "PR59"
			(at 0 0 90)
			(layer "F.SilkS")
			(hide yes)
			(effects
				(font
					(size 1.27 1.27)
				)
			)
		)
		(property "Value" "4K7R2F-GP"
			(at 0.064008 -3.993896 90)
			(unlocked yes)
			(layer "F.Fab")
			(hide yes)
			(effects
				(font
					(size 1.016 1.016)
					(thickness 0.1524)
				)
			)
		)
		(property "Device Type" "R402H16"
			(at 0.064008 -5.517896 90)
			(unlocked yes)
			(layer "F.Fab")
			(hide yes)
			(effects
				(font
					(size 1.016 1.016)
					(thickness 0.1524)
				)
			)
		)
		(duplicate_pad_numbers_are_jumpers no)
		(fp_line
			(start 0.508 -0.9398)
			(end -0.508 -0.9398)
			(stroke
				(width 0.1524)
				(type default)
			)
			(layer "F.SilkS")
		)
		(fp_line
			(start -0.508 -0.9398)
			(end -0.508 0.9398)
			(stroke
				(width 0.1524)
				(type default)
			)
			(layer "F.SilkS")
		)
		(fp_rect
			(start -0.508 0.9398)
			(end 0.508 -0.9398)
			(stroke
				(width 0)
				(type default)
			)
			(fill no)
			(layer "F.CrtYd")
		)
		(fp_rect
			(start -0.508 0.9398)
			(end 0.508 -0.9398)
			(stroke
				(width 0)
				(type default)
			)
			(fill no)
			(layer "F.Fab")
		)
		(pad "1" smd custom
			(at 0 -0.4445 90)
			(size 0.1397 0.1397)
			(layers "F.Cu" "F.Mask" "F.Paste")
			(net "P12V_AUX")
			(options
				(clearance outline)
				(anchor circle)
			)
			(primitives
				(gr_poly
					(pts
						(arc
							(start -0.1778 -0.2794)
							(mid -0.249642 -0.249642)
							(end -0.2794 -0.1778)
						)
						(arc
							(start -0.2794 0.1778)
							(mid -0.249642 0.249642)
							(end -0.1778 0.2794)
						)
						(arc
							(start 0.1778 0.2794)
							(mid 0.249642 0.249642)
							(end 0.2794 0.1778)
						)
						(arc
							(start 0.2794 -0.1778)
							(mid 0.249642 -0.249642)
							(end 0.1778 -0.2794)
						)
					)
					(width 0)
					(fill yes)
				)
			)
		)
		(pad "2" smd custom
			(at 0 0.4445 90)
			(size 0.1397 0.1397)
			(layers "F.Cu" "F.Mask" "F.Paste")
			(net "OTP_RETRY_B")
			(options
				(clearance outline)
				(anchor circle)
			)
			(primitives
				(gr_poly
					(pts
						(arc
							(start -0.1778 -0.2794)
							(mid -0.249642 -0.249642)
							(end -0.2794 -0.1778)
						)
						(arc
							(start -0.2794 0.1778)
							(mid -0.249642 0.249642)
							(end -0.1778 0.2794)
						)
						(arc
							(start 0.1778 0.2794)
							(mid 0.249642 0.249642)
							(end 0.2794 0.1778)
						)
						(arc
							(start 0.2794 -0.1778)
							(mid 0.249642 -0.249642)
							(end 0.1778 -0.2794)
						)
					)
					(width 0)
					(fill yes)
				)
			)
		)
	)
	(footprint ""
		(layer "F.Cu")
		(at 17.907 -298.4754 -90)
		(property "Reference" "R92"
			(at 0 0 270)
			(layer "F.SilkS")
			(hide yes)
			(effects
				(font
					(size 1.27 1.27)
				)
			)
		)
		(property "Value" "4K7R2F-GP"
			(at 0.064008 -3.993896 270)
			(unlocked yes)
			(layer "F.Fab")
			(hide yes)
			(effects
				(font
					(size 1.016 1.016)
					(thickness 0.1524)
				)
			)
		)
		(property "Device Type" "R402H16"
			(at 0.064008 -5.517896 270)
			(unlocked yes)
			(layer "F.Fab")
			(hide yes)
			(effects
				(font
					(size 1.016 1.016)
					(thickness 0.1524)
				)
			)
		)
		(duplicate_pad_numbers_are_jumpers no)
		(fp_line
			(start -0.508 -0.9398)
			(end -0.508 0.9398)
			(stroke
				(width 0.1524)
				(type default)
			)
			(layer "F.SilkS")
		)
		(fp_line
			(start 0.508 -0.9398)
			(end -0.508 -0.9398)
			(stroke
				(width 0.1524)
				(type default)
			)
			(layer "F.SilkS")
		)
		(fp_rect
			(start -0.508 0.9398)
			(end 0.508 -0.9398)
			(stroke
				(width 0)
				(type default)
			)
			(fill no)
			(layer "F.CrtYd")
		)
		(fp_rect
			(start -0.508 0.9398)
			(end 0.508 -0.9398)
			(stroke
				(width 0)
				(type default)
			)
			(fill no)
			(layer "F.Fab")
		)
		(pad "1" smd custom
			(at 0 -0.4445 270)
			(size 0.1397 0.1397)
			(layers "F.Cu" "F.Mask" "F.Paste")
			(net "P12V")
			(options
				(clearance outline)
				(anchor circle)
			)
			(primitives
				(gr_poly
					(pts
						(arc
							(start -0.1778 -0.2794)
							(mid -0.249642 -0.249642)
							(end -0.2794 -0.1778)
						)
						(arc
							(start -0.2794 0.1778)
							(mid -0.249642 0.249642)
							(end -0.1778 0.2794)
						)
						(arc
							(start 0.1778 0.2794)
							(mid 0.249642 0.249642)
							(end 0.2794 0.1778)
						)
						(arc
							(start 0.2794 -0.1778)
							(mid 0.249642 -0.249642)
							(end 0.1778 -0.2794)
						)
					)
					(width 0)
					(fill yes)
				)
			)
		)
		(pad "2" smd custom
			(at 0 0.4445 270)
			(size 0.1397 0.1397)
			(layers "F.Cu" "F.Mask" "F.Paste")
			(net "PWM_OUT_FAN2_NET")
			(options
				(clearance outline)
				(anchor circle)
			)
			(primitives
				(gr_poly
					(pts
						(arc
							(start -0.1778 -0.2794)
							(mid -0.249642 -0.249642)
							(end -0.2794 -0.1778)
						)
						(arc
							(start -0.2794 0.1778)
							(mid -0.249642 0.249642)
							(end -0.1778 0.2794)
						)
						(arc
							(start 0.1778 0.2794)
							(mid 0.249642 0.249642)
							(end 0.2794 0.1778)
						)
						(arc
							(start 0.2794 -0.1778)
							(mid 0.249642 -0.249642)
							(end 0.1778 -0.2794)
						)
					)
					(width 0)
					(fill yes)
				)
			)
		)
	)
	(footprint ""
		(layer "F.Cu")
		(at 16.9672 -256.9972 90)
		(property "Reference" "D7"
			(at 0 0 90)
			(layer "F.SilkS")
			(hide yes)
			(effects
				(font
					(size 1.27 1.27)
				)
			)
		)
		(property "Value" "BAS16H-GP"
			(at 0 -5.5372 90)
			(unlocked yes)
			(layer "F.Fab")
			(hide yes)
			(effects
				(font
					(size 1.016 1.016)
					(thickness 0.1524)
				)
			)
		)
		(property "Device Type" "SOD123AKH48"
			(at 0 -7.0612 90)
			(unlocked yes)
			(layer "F.Fab")
			(hide yes)
			(effects
				(font
					(size 1.016 1.016)
					(thickness 0.1524)
				)
			)
		)
		(duplicate_pad_numbers_are_jumpers no)
		(fp_line
			(start 1.016 -2.667)
			(end -1.016 -2.667)
			(stroke
				(width 0.1524)
				(type default)
			)
			(layer "F.SilkS")
		)
		(fp_line
			(start -1.016 -2.667)
			(end -1.016 2.667)
			(stroke
				(width 0.1524)
				(type default)
			)
			(layer "F.SilkS")
		)
		(fp_line
			(start 1.016 2.667)
			(end 1.016 -2.667)
			(stroke
				(width 0.1524)
				(type default)
			)
			(layer "F.SilkS")
		)
		(fp_line
			(start -1.016 2.667)
			(end 1.016 2.667)
			(stroke
				(width 0.1524)
				(type default)
			)
			(layer "F.SilkS")
		)
		(fp_line
			(start 0.889 2.921)
			(end -0.889 2.921)
			(stroke
				(width 0.508)
				(type default)
			)
			(layer "F.SilkS")
		)
		(fp_rect
			(start -1.143 3.175)
			(end 1.143 -2.794)
			(stroke
				(width 0)
				(type default)
			)
			(fill no)
			(layer "F.CrtYd")
		)
		(fp_poly
			(pts
				(xy -1.143 -2.794) (xy 1.143 -2.794) (xy 1.143 3.175) (xy -1.143 3.175)
			)
			(stroke
				(width 0)
				(type default)
			)
			(fill no)
			(layer "F.Fab")
		)
		(pad "A" smd rect
			(at 0 -1.6891 90)
			(size 0.889 1.397)
			(layers "F.Cu" "F.Mask" "F.Paste")
			(net "FAN_TACH5")
		)
		(pad "K" smd rect
			(at 0 1.6891 90)
			(size 0.889 1.397)
			(layers "F.Cu" "F.Mask" "F.Paste")
			(net "P12V")
		)
	)
	(footprint ""
		(layer "F.Cu")
		(at 26.035 -17.399 90)
		(property "Reference" "D1"
			(at 0 0 90)
			(layer "F.SilkS")
			(hide yes)
			(effects
				(font
					(size 1.27 1.27)
				)
			)
		)
		(property "Value" "BAS16H-GP"
			(at 0 -5.5372 90)
			(unlocked yes)
			(layer "F.Fab")
			(hide yes)
			(effects
				(font
					(size 1.016 1.016)
					(thickness 0.1524)
				)
			)
		)
		(property "Device Type" "SOD123AKH48"
			(at 0 -7.0612 90)
			(unlocked yes)
			(layer "F.Fab")
			(hide yes)
			(effects
				(font
					(size 1.016 1.016)
					(thickness 0.1524)
				)
			)
		)
		(duplicate_pad_numbers_are_jumpers no)
		(fp_line
			(start 1.016 -2.667)
			(end -1.016 -2.667)
			(stroke
				(width 0.1524)
				(type default)
			)
			(layer "F.SilkS")
		)
		(fp_line
			(start -1.016 -2.667)
			(end -1.016 2.667)
			(stroke
				(width 0.1524)
				(type default)
			)
			(layer "F.SilkS")
		)
		(fp_line
			(start 1.016 2.667)
			(end 1.016 -2.667)
			(stroke
				(width 0.1524)
				(type default)
			)
			(layer "F.SilkS")
		)
		(fp_line
			(start -1.016 2.667)
			(end 1.016 2.667)
			(stroke
				(width 0.1524)
				(type default)
			)
			(layer "F.SilkS")
		)
		(fp_line
			(start 0.889 2.921)
			(end -0.889 2.921)
			(stroke
				(width 0.508)
				(type default)
			)
			(layer "F.SilkS")
		)
		(fp_rect
			(start -1.143 3.175)
			(end 1.143 -2.794)
			(stroke
				(width 0)
				(type default)
			)
			(fill no)
			(layer "F.CrtYd")
		)
		(fp_poly
			(pts
				(xy -1.143 -2.794) (xy 1.143 -2.794) (xy 1.143 3.175) (xy -1.143 3.175)
			)
			(stroke
				(width 0)
				(type default)
			)
			(fill no)
			(layer "F.Fab")
		)
		(pad "A" smd rect
			(at 0 -1.6891 90)
			(size 0.889 1.397)
			(layers "F.Cu" "F.Mask" "F.Paste")
			(net "FAN_TACH12")
		)
		(pad "K" smd rect
			(at 0 1.6891 90)
			(size 0.889 1.397)
			(layers "F.Cu" "F.Mask" "F.Paste")
			(net "P12V")
		)
	)
	(footprint ""
		(layer "F.Cu")
		(at 40.64 -410.591)
		(property "Reference" "PR32"
			(at 0 0 0)
			(layer "F.SilkS")
			(hide yes)
			(effects
				(font
					(size 1.27 1.27)
				)
			)
		)
		(property "Value" "D0005RL1632F-GP-U"
			(at 3.2258 1.2954 0)
			(unlocked yes)
			(layer "F.Fab")
			(hide yes)
			(effects
				(font
					(size 1.016 1.016)
					(thickness 0.1524)
				)
			)
		)
		(property "Device Type" "RL3115-4PH45"
			(at 3.2258 -0.2286 0)
			(unlocked yes)
			(layer "F.Fab")
			(hide yes)
			(effects
				(font
					(size 1.016 1.016)
					(thickness 0.1524)
				)
			)
		)
		(duplicate_pad_numbers_are_jumpers no)
		(fp_line
			(start -2.0574 -1.7653)
			(end -2.0574 -0.4064)
			(stroke
				(width 0.3302)
				(type default)
			)
			(layer "F.SilkS")
		)
		(fp_line
			(start -1.9685 -1.651)
			(end 1.9685 -1.651)
			(stroke
				(width 0.1524)
				(type default)
			)
			(layer "F.SilkS")
		)
		(fp_line
			(start -1.9685 1.651)
			(end -1.9685 -1.651)
			(stroke
				(width 0.1524)
				(type default)
			)
			(layer "F.SilkS")
		)
		(fp_line
			(start -0.5334 -1.7653)
			(end -2.0574 -1.7653)
			(stroke
				(width 0.3302)
				(type default)
			)
			(layer "F.SilkS")
		)
		(fp_line
			(start 1.9685 -1.651)
			(end 1.9685 1.651)
			(stroke
				(width 0.1524)
				(type default)
			)
			(layer "F.SilkS")
		)
		(fp_line
			(start 1.9685 1.651)
			(end -1.9685 1.651)
			(stroke
				(width 0.1524)
				(type default)
			)
			(layer "F.SilkS")
		)
		(fp_poly
			(pts
				(xy -0.561594 -1.726946) (xy -0.053594 -2.234946) (xy -1.069594 -2.234946)
			)
			(stroke
				(width 0)
				(type default)
			)
			(fill yes)
			(layer "F.SilkS")
		)
		(fp_rect
			(start -1.524 0.7493)
			(end 1.524 -0.7493)
			(stroke
				(width 0)
				(type default)
			)
			(fill no)
			(layer "F.CrtYd")
		)
		(fp_poly
			(pts
				(xy -2.2225 1.905) (xy -2.2225 -1.905) (xy 2.2225 -1.905) (xy 2.2225 -0.7493) (xy -1.524 -0.7493)
				(xy -1.524 0.7493) (xy 1.524 0.7493) (xy 1.524 -0.7366) (xy 2.2225 -0.7366) (xy 2.2225 1.905)
			)
			(stroke
				(width 0)
				(type default)
			)
			(fill no)
			(layer "F.CrtYd")
		)
		(fp_rect
			(start -2.2225 1.905)
			(end 2.2225 -1.905)
			(stroke
				(width 0)
				(type default)
			)
			(fill no)
			(layer "F.Fab")
		)
		(pad "1" smd rect
			(at -0.5715 -0.813562)
			(size 2.286 1.143)
			(layers "F.Cu" "F.Mask" "F.Paste")
			(net "P12V_AUX")
		)
		(pad "2" smd rect
			(at -0.5715 0.813562)
			(size 2.286 1.143)
			(layers "F.Cu" "F.Mask" "F.Paste")
			(net "P12V_SENSE_TRACE")
		)
		(pad "3" smd rect
			(at 1.334008 -0.813562)
			(size 0.762 1.143)
			(layers "F.Cu" "F.Mask" "F.Paste")
			(net "SENSE+_R4")
		)
		(pad "4" smd rect
			(at 1.334008 0.813562)
			(size 0.762 1.143)
			(layers "F.Cu" "F.Mask" "F.Paste")
			(net "SENSE-_R4")
		)
		(zone
			(layer "F.Cu")
			(hatch none 0.5)
			(connect_pads
				(clearance 0)
			)
			(min_thickness 0.25)
			(keepout
				(tracks not_allowed)
				(vias allowed)
				(pads allowed)
				(copperpour not_allowed)
				(footprints allowed)
			)
			(placement
				(enabled no)
				(sheetname "")
			)
			(fill
				(thermal_gap 0.5)
				(thermal_bridge_width 0.5)
				(island_removal_mode 0)
			)
			(polygon
				(pts
					(xy 41.2115 -410.833062) (xy 41.593008 -410.833062) (xy 41.593008 -411.3403) (xy 41.2115 -411.3403)
				)
			)
		)
		(zone
			(layer "F.Cu")
			(hatch none 0.5)
			(connect_pads
				(clearance 0)
			)
			(min_thickness 0.25)
			(keepout
				(tracks allowed)
				(vias not_allowed)
				(pads allowed)
				(copperpour not_allowed)
				(footprints allowed)
			)
			(placement
				(enabled no)
				(sheetname "")
			)
			(fill
				(thermal_gap 0.5)
				(thermal_bridge_width 0.5)
				(island_removal_mode 0)
			)
			(polygon
				(pts
					(xy 41.2115 -410.833062) (xy 41.593008 -410.833062) (xy 41.593008 -411.3403) (xy 41.2115 -411.3403)
				)
			)
		)
		(zone
			(layer "F.Cu")
			(hatch none 0.5)
			(connect_pads
				(clearance 0)
			)
			(min_thickness 0.25)
			(keepout
				(tracks allowed)
				(vias not_allowed)
				(pads allowed)
				(copperpour not_allowed)
				(footprints allowed)
			)
			(placement
				(enabled no)
				(sheetname "")
			)
			(fill
				(thermal_gap 0.5)
				(thermal_bridge_width 0.5)
				(island_removal_mode 0)
			)
			(polygon
				(pts
					(xy 41.2115 -409.8417) (xy 41.593008 -409.8417) (xy 41.593008 -410.348938) (xy 41.2115 -410.348938)
				)
			)
		)
		(zone
			(layer "F.Cu")
			(hatch none 0.5)
			(connect_pads
				(clearance 0)
			)
			(min_thickness 0.25)
			(keepout
				(tracks not_allowed)
				(vias allowed)
				(pads allowed)
				(copperpour not_allowed)
				(footprints allowed)
			)
			(placement
				(enabled no)
				(sheetname "")
			)
			(fill
				(thermal_gap 0.5)
				(thermal_bridge_width 0.5)
				(island_removal_mode 0)
			)
			(polygon
				(pts
					(xy 41.2115 -409.8417) (xy 41.593008 -409.8417) (xy 41.593008 -410.348938) (xy 41.2115 -410.348938)
				)
			)
		)
	)
	(footprint ""
		(layer "F.Cu")
		(at 30.3022 -253.8984 180)
		(property "Reference" "R46"
			(at 0 0 180)
			(layer "F.SilkS")
			(hide yes)
			(effects
				(font
					(size 1.27 1.27)
				)
			)
		)
		(property "Value" "0R2J-2-GP"
			(at 0.064008 -3.993896 180)
			(unlocked yes)
			(layer "F.Fab")
			(hide yes)
			(effects
				(font
					(size 1.016 1.016)
					(thickness 0.1524)
				)
			)
		)
		(property "Device Type" "R402H16"
			(at 0.064008 -5.517896 180)
			(unlocked yes)
			(layer "F.Fab")
			(hide yes)
			(effects
				(font
					(size 1.016 1.016)
					(thickness 0.1524)
				)
			)
		)
		(duplicate_pad_numbers_are_jumpers no)
		(fp_line
			(start 0.508 -0.9398)
			(end -0.508 -0.9398)
			(stroke
				(width 0.1524)
				(type default)
			)
			(layer "F.SilkS")
		)
		(fp_line
			(start -0.508 -0.9398)
			(end -0.508 0.9398)
			(stroke
				(width 0.1524)
				(type default)
			)
			(layer "F.SilkS")
		)
		(fp_rect
			(start -0.508 0.9398)
			(end 0.508 -0.9398)
			(stroke
				(width 0)
				(type default)
			)
			(fill no)
			(layer "F.CrtYd")
		)
		(fp_rect
			(start -0.508 0.9398)
			(end 0.508 -0.9398)
			(stroke
				(width 0)
				(type default)
			)
			(fill no)
			(layer "F.Fab")
		)
		(pad "1" smd custom
			(at 0 -0.4445 180)
			(size 0.1397 0.1397)
			(layers "F.Cu" "F.Mask" "F.Paste")
			(net "I2C_C_SCL_EEPROM")
			(options
				(clearance outline)
				(anchor circle)
			)
			(primitives
				(gr_poly
					(pts
						(arc
							(start -0.1778 -0.2794)
							(mid -0.249642 -0.249642)
							(end -0.2794 -0.1778)
						)
						(arc
							(start -0.2794 0.1778)
							(mid -0.249642 0.249642)
							(end -0.1778 0.2794)
						)
						(arc
							(start 0.1778 0.2794)
							(mid 0.249642 0.249642)
							(end 0.2794 0.1778)
						)
						(arc
							(start 0.2794 -0.1778)
							(mid 0.249642 -0.249642)
							(end 0.1778 -0.2794)
						)
					)
					(width 0)
					(fill yes)
				)
			)
		)
		(pad "2" smd custom
			(at 0 0.4445 180)
			(size 0.1397 0.1397)
			(layers "F.Cu" "F.Mask" "F.Paste")
			(net "I2C_C_SCL")
			(options
				(clearance outline)
				(anchor circle)
			)
			(primitives
				(gr_poly
					(pts
						(arc
							(start -0.1778 -0.2794)
							(mid -0.249642 -0.249642)
							(end -0.2794 -0.1778)
						)
						(arc
							(start -0.2794 0.1778)
							(mid -0.249642 0.249642)
							(end -0.1778 0.2794)
						)
						(arc
							(start 0.1778 0.2794)
							(mid 0.249642 0.249642)
							(end 0.2794 0.1778)
						)
						(arc
							(start 0.2794 -0.1778)
							(mid 0.249642 -0.249642)
							(end 0.1778 -0.2794)
						)
					)
					(width 0)
					(fill yes)
				)
			)
		)
	)
	(footprint ""
		(layer "F.Cu")
		(at 17.9578 -150.114 -90)
		(property "Reference" "R72"
			(at 0 0 270)
			(layer "F.SilkS")
			(hide yes)
			(effects
				(font
					(size 1.27 1.27)
				)
			)
		)
		(property "Value" "27KR3F-GP"
			(at -0.0254 -2.5146 270)
			(unlocked yes)
			(layer "F.Fab")
			(hide yes)
			(effects
				(font
					(size 1.016 1.016)
					(thickness 0.1524)
				)
			)
		)
		(property "Device Type" "R603H22"
			(at -0.0254 -4.0386 270)
			(unlocked yes)
			(layer "F.Fab")
			(hide yes)
			(effects
				(font
					(size 1.016 1.016)
					(thickness 0.1524)
				)
			)
		)
		(duplicate_pad_numbers_are_jumpers no)
		(fp_line
			(start -0.4826 0)
			(end -0.2032 0)
			(stroke
				(width 0.2032)
				(type default)
			)
			(layer "F.SilkS")
		)
		(fp_line
			(start 0.2032 0)
			(end 0.4826 0)
			(stroke
				(width 0.2032)
				(type default)
			)
			(layer "F.SilkS")
		)
		(fp_rect
			(start -0.5842 1.3335)
			(end 0.5842 -1.3335)
			(stroke
				(width 0)
				(type default)
			)
			(fill no)
			(layer "F.CrtYd")
		)
		(fp_rect
			(start -0.5842 1.3335)
			(end 0.5842 -1.3335)
			(stroke
				(width 0)
				(type default)
			)
			(fill no)
			(layer "F.Fab")
		)
		(pad "1" smd custom
			(at 0 -0.762 270)
			(size 0.2159 0.2159)
			(layers "F.Cu" "F.Mask" "F.Paste")
			(net "FANIN_9")
			(options
				(clearance outline)
				(anchor circle)
			)
			(primitives
				(gr_poly
					(pts
						(arc
							(start -0.3302 -0.4318)
							(mid -0.402042 -0.402042)
							(end -0.4318 -0.3302)
						)
						(arc
							(start -0.4318 0.3302)
							(mid -0.402042 0.402042)
							(end -0.3302 0.4318)
						)
						(arc
							(start 0.3302 0.4318)
							(mid 0.402042 0.402042)
							(end 0.4318 0.3302)
						)
						(arc
							(start 0.4318 -0.3302)
							(mid 0.402042 -0.402042)
							(end 0.3302 -0.4318)
						)
					)
					(width 0)
					(fill yes)
				)
			)
		)
		(pad "2" smd custom
			(at 0 0.762 270)
			(size 0.2159 0.2159)
			(layers "F.Cu" "F.Mask" "F.Paste")
			(net "FAN_TACH9")
			(options
				(clearance outline)
				(anchor circle)
			)
			(primitives
				(gr_poly
					(pts
						(arc
							(start -0.3302 -0.4318)
							(mid -0.402042 -0.402042)
							(end -0.4318 -0.3302)
						)
						(arc
							(start -0.4318 0.3302)
							(mid -0.402042 0.402042)
							(end -0.3302 0.4318)
						)
						(arc
							(start 0.3302 0.4318)
							(mid 0.402042 0.402042)
							(end 0.4318 0.3302)
						)
						(arc
							(start 0.4318 -0.3302)
							(mid 0.402042 -0.402042)
							(end 0.3302 -0.4318)
						)
					)
					(width 0)
					(fill yes)
				)
			)
		)
	)
	(footprint ""
		(layer "F.Cu")
		(at 23.622 -364.4646 -90)
		(property "Reference" "PC3"
			(at 0 0 270)
			(layer "F.SilkS")
			(hide yes)
			(effects
				(font
					(size 1.27 1.27)
				)
			)
		)
		(property "Value" "SCD01U25V2KX-3GP"
			(at 1.1811 -2.7051 270)
			(unlocked yes)
			(layer "F.Fab")
			(hide yes)
			(effects
				(font
					(size 1.016 1.016)
					(thickness 0.1524)
				)
			)
		)
		(property "Device Type" "C402H22"
			(at 1.1811 -4.2291 270)
			(unlocked yes)
			(layer "F.Fab")
			(hide yes)
			(effects
				(font
					(size 1.016 1.016)
					(thickness 0.1524)
				)
			)
		)
		(duplicate_pad_numbers_are_jumpers no)
		(fp_rect
			(start -0.4318 0.9525)
			(end 0.4318 -0.9525)
			(stroke
				(width 0)
				(type default)
			)
			(fill no)
			(layer "F.CrtYd")
		)
		(fp_rect
			(start -0.4318 0.9525)
			(end 0.4318 -0.9525)
			(stroke
				(width 0)
				(type default)
			)
			(fill no)
			(layer "F.Fab")
		)
		(pad "1" smd custom
			(at 0 -0.4445 270)
			(size 0.1524 0.1524)
			(layers "F.Cu" "F.Mask" "F.Paste")
			(net "ADM1276_SS")
			(options
				(clearance outline)
				(anchor circle)
			)
			(primitives
				(gr_poly
					(pts
						(arc
							(start 0.3048 -0.2032)
							(mid 0.275042 -0.275042)
							(end 0.2032 -0.3048)
						)
						(arc
							(start -0.2032 -0.3048)
							(mid -0.275042 -0.275042)
							(end -0.3048 -0.2032)
						)
						(arc
							(start -0.3048 0.2032)
							(mid -0.275042 0.275042)
							(end -0.2032 0.3048)
						)
						(arc
							(start 0.2032 0.3048)
							(mid 0.275042 0.275042)
							(end 0.3048 0.2032)
						)
					)
					(width 0)
					(fill yes)
				)
			)
		)
		(pad "2" smd custom
			(at 0 0.4445 270)
			(size 0.1524 0.1524)
			(layers "F.Cu" "F.Mask" "F.Paste")
			(net "GND")
			(options
				(clearance outline)
				(anchor circle)
			)
			(primitives
				(gr_poly
					(pts
						(arc
							(start 0.3048 -0.2032)
							(mid 0.275042 -0.275042)
							(end 0.2032 -0.3048)
						)
						(arc
							(start -0.2032 -0.3048)
							(mid -0.275042 -0.275042)
							(end -0.3048 -0.2032)
						)
						(arc
							(start -0.3048 0.2032)
							(mid -0.275042 0.275042)
							(end -0.2032 0.3048)
						)
						(arc
							(start 0.2032 0.3048)
							(mid 0.275042 0.275042)
							(end 0.3048 0.2032)
						)
					)
					(width 0)
					(fill yes)
				)
			)
		)
	)
	(footprint ""
		(layer "F.Cu")
		(at 29.7942 -167.6908 -90)
		(property "Reference" "R165"
			(at 0 0 270)
			(layer "F.SilkS")
			(hide yes)
			(effects
				(font
					(size 1.27 1.27)
				)
			)
		)
		(property "Value" "0R2J-2-GP"
			(at 0.064008 -3.993896 270)
			(unlocked yes)
			(layer "F.Fab")
			(hide yes)
			(effects
				(font
					(size 1.016 1.016)
					(thickness 0.1524)
				)
			)
		)
		(property "Device Type" "R402H16"
			(at 0.064008 -5.517896 270)
			(unlocked yes)
			(layer "F.Fab")
			(hide yes)
			(effects
				(font
					(size 1.016 1.016)
					(thickness 0.1524)
				)
			)
		)
		(duplicate_pad_numbers_are_jumpers no)
		(fp_line
			(start -0.508 -0.9398)
			(end -0.508 0.9398)
			(stroke
				(width 0.1524)
				(type default)
			)
			(layer "F.SilkS")
		)
		(fp_line
			(start 0.508 -0.9398)
			(end -0.508 -0.9398)
			(stroke
				(width 0.1524)
				(type default)
			)
			(layer "F.SilkS")
		)
		(fp_rect
			(start -0.508 0.9398)
			(end 0.508 -0.9398)
			(stroke
				(width 0)
				(type default)
			)
			(fill no)
			(layer "F.CrtYd")
		)
		(fp_rect
			(start -0.508 0.9398)
			(end 0.508 -0.9398)
			(stroke
				(width 0)
				(type default)
			)
			(fill no)
			(layer "F.Fab")
		)
		(pad "1" smd custom
			(at 0 -0.4445 270)
			(size 0.1397 0.1397)
			(layers "F.Cu" "F.Mask" "F.Paste")
			(net "PWM_BUFFER_IN_FAN1_FAN2")
			(options
				(clearance outline)
				(anchor circle)
			)
			(primitives
				(gr_poly
					(pts
						(arc
							(start -0.1778 -0.2794)
							(mid -0.249642 -0.249642)
							(end -0.2794 -0.1778)
						)
						(arc
							(start -0.2794 0.1778)
							(mid -0.249642 0.249642)
							(end -0.1778 0.2794)
						)
						(arc
							(start 0.1778 0.2794)
							(mid 0.249642 0.249642)
							(end 0.2794 0.1778)
						)
						(arc
							(start 0.2794 -0.1778)
							(mid 0.249642 -0.249642)
							(end 0.1778 -0.2794)
						)
					)
					(width 0)
					(fill yes)
				)
			)
		)
		(pad "2" smd custom
			(at 0 0.4445 270)
			(size 0.1397 0.1397)
			(layers "F.Cu" "F.Mask" "F.Paste")
			(net "PWM_BUFFER_IN_FAN3_FAN4")
			(options
				(clearance outline)
				(anchor circle)
			)
			(primitives
				(gr_poly
					(pts
						(arc
							(start -0.1778 -0.2794)
							(mid -0.249642 -0.249642)
							(end -0.2794 -0.1778)
						)
						(arc
							(start -0.2794 0.1778)
							(mid -0.249642 0.249642)
							(end -0.1778 0.2794)
						)
						(arc
							(start 0.1778 0.2794)
							(mid 0.249642 0.249642)
							(end 0.2794 0.1778)
						)
						(arc
							(start 0.2794 -0.1778)
							(mid 0.249642 -0.249642)
							(end 0.1778 -0.2794)
						)
					)
					(width 0)
					(fill yes)
				)
			)
		)
	)
	(footprint ""
		(layer "F.Cu")
		(at 8.0518 -144.9832 -90)
		(property "Reference" "R64"
			(at 0 0 270)
			(layer "F.SilkS")
			(hide yes)
			(effects
				(font
					(size 1.27 1.27)
				)
			)
		)
		(property "Value" "4K7R2F-GP"
			(at 0.064008 -3.993896 270)
			(unlocked yes)
			(layer "F.Fab")
			(hide yes)
			(effects
				(font
					(size 1.016 1.016)
					(thickness 0.1524)
				)
			)
		)
		(property "Device Type" "R402H16"
			(at 0.064008 -5.517896 270)
			(unlocked yes)
			(layer "F.Fab")
			(hide yes)
			(effects
				(font
					(size 1.016 1.016)
					(thickness 0.1524)
				)
			)
		)
		(duplicate_pad_numbers_are_jumpers no)
		(fp_line
			(start -0.508 -0.9398)
			(end -0.508 0.9398)
			(stroke
				(width 0.1524)
				(type default)
			)
			(layer "F.SilkS")
		)
		(fp_line
			(start 0.508 -0.9398)
			(end -0.508 -0.9398)
			(stroke
				(width 0.1524)
				(type default)
			)
			(layer "F.SilkS")
		)
		(fp_rect
			(start -0.508 0.9398)
			(end 0.508 -0.9398)
			(stroke
				(width 0)
				(type default)
			)
			(fill no)
			(layer "F.CrtYd")
		)
		(fp_rect
			(start -0.508 0.9398)
			(end 0.508 -0.9398)
			(stroke
				(width 0)
				(type default)
			)
			(fill no)
			(layer "F.Fab")
		)
		(pad "1" smd custom
			(at 0 -0.4445 270)
			(size 0.1397 0.1397)
			(layers "F.Cu" "F.Mask" "F.Paste")
			(net "P12V")
			(options
				(clearance outline)
				(anchor circle)
			)
			(primitives
				(gr_poly
					(pts
						(arc
							(start -0.1778 -0.2794)
							(mid -0.249642 -0.249642)
							(end -0.2794 -0.1778)
						)
						(arc
							(start -0.2794 0.1778)
							(mid -0.249642 0.249642)
							(end -0.1778 0.2794)
						)
						(arc
							(start 0.1778 0.2794)
							(mid 0.249642 0.249642)
							(end 0.2794 0.1778)
						)
						(arc
							(start 0.2794 -0.1778)
							(mid 0.249642 -0.249642)
							(end 0.1778 -0.2794)
						)
					)
					(width 0)
					(fill yes)
				)
			)
		)
		(pad "2" smd custom
			(at 0 0.4445 270)
			(size 0.1397 0.1397)
			(layers "F.Cu" "F.Mask" "F.Paste")
			(net "PWM_OUT_FAN5_NET")
			(options
				(clearance outline)
				(anchor circle)
			)
			(primitives
				(gr_poly
					(pts
						(arc
							(start -0.1778 -0.2794)
							(mid -0.249642 -0.249642)
							(end -0.2794 -0.1778)
						)
						(arc
							(start -0.2794 0.1778)
							(mid -0.249642 0.249642)
							(end -0.1778 0.2794)
						)
						(arc
							(start 0.1778 0.2794)
							(mid 0.249642 0.249642)
							(end 0.2794 0.1778)
						)
						(arc
							(start 0.2794 -0.1778)
							(mid 0.249642 -0.249642)
							(end 0.1778 -0.2794)
						)
					)
					(width 0)
					(fill yes)
				)
			)
		)
	)
	(footprint ""
		(layer "F.Cu")
		(at 7.3152 -78.5114)
		(property "Reference" "Q4"
			(at 0 0 0)
			(layer "F.SilkS")
			(hide yes)
			(effects
				(font
					(size 1.27 1.27)
				)
			)
		)
		(property "Value" "PMBS3904-1-GP"
			(at 0 -9.0932 0)
			(unlocked yes)
			(layer "F.Fab")
			(hide yes)
			(effects
				(font
					(size 1.016 1.016)
					(thickness 0.1524)
				)
			)
		)
		(property "Device Type" "SOT-23-10H44"
			(at 0 -10.6172 0)
			(unlocked yes)
			(layer "F.Fab")
			(hide yes)
			(effects
				(font
					(size 1.016 1.016)
					(thickness 0.1524)
				)
			)
		)
		(duplicate_pad_numbers_are_jumpers no)
		(fp_line
			(start -1.7526 1.8796)
			(end -1.7526 0.9906)
			(stroke
				(width 0.3302)
				(type default)
			)
			(layer "F.SilkS")
		)
		(fp_line
			(start -1.651 -1.778)
			(end -1.651 1.778)
			(stroke
				(width 0.1524)
				(type default)
			)
			(layer "F.SilkS")
		)
		(fp_line
			(start -1.651 1.778)
			(end 1.651 1.778)
			(stroke
				(width 0.1524)
				(type default)
			)
			(layer "F.SilkS")
		)
		(fp_line
			(start -1.279398 2.152142)
			(end -0.9906 1.86309)
			(stroke
				(width 0.0127)
				(type default)
			)
			(layer "F.SilkS")
		)
		(fp_line
			(start -1.279144 2.15265)
			(end -0.701294 2.15265)
			(stroke
				(width 0.0127)
				(type default)
			)
			(layer "F.SilkS")
		)
		(fp_line
			(start -1.260856 2.1336)
			(end -0.720344 2.1336)
			(stroke
				(width 0.0127)
				(type default)
			)
			(layer "F.SilkS")
		)
		(fp_line
			(start -1.251458 2.124202)
			(end -0.729996 2.124202)
			(stroke
				(width 0.0127)
				(type default)
			)
			(layer "F.SilkS")
		)
		(fp_line
			(start -1.241806 2.11455)
			(end -0.739394 2.11455)
			(stroke
				(width 0.0127)
				(type default)
			)
			(layer "F.SilkS")
		)
		(fp_line
			(start -1.232408 2.105152)
			(end -0.749046 2.105152)
			(stroke
				(width 0.0127)
				(type default)
			)
			(layer "F.SilkS")
		)
		(fp_line
			(start -1.222756 2.0955)
			(end -0.758444 2.0955)
			(stroke
				(width 0.0127)
				(type default)
			)
			(layer "F.SilkS")
		)
		(fp_line
			(start -1.213358 2.086102)
			(end -0.768096 2.086102)
			(stroke
				(width 0.0127)
				(type default)
			)
			(layer "F.SilkS")
		)
		(fp_line
			(start -1.203706 2.07645)
			(end -0.777494 2.07645)
			(stroke
				(width 0.0127)
				(type default)
			)
			(layer "F.SilkS")
		)
		(fp_line
			(start -1.194308 2.067052)
			(end -0.787146 2.067052)
			(stroke
				(width 0.0127)
				(type default)
			)
			(layer "F.SilkS")
		)
		(fp_line
			(start -1.184656 2.0574)
			(end -0.796544 2.0574)
			(stroke
				(width 0.0127)
				(type default)
			)
			(layer "F.SilkS")
		)
		(fp_line
			(start -1.175258 2.048002)
			(end -0.806196 2.048002)
			(stroke
				(width 0.0127)
				(type default)
			)
			(layer "F.SilkS")
		)
		(fp_line
			(start -1.165606 2.03835)
			(end -0.815594 2.03835)
			(stroke
				(width 0.0127)
				(type default)
			)
			(layer "F.SilkS")
		)
		(fp_line
			(start -1.156208 2.028952)
			(end -0.825246 2.028952)
			(stroke
				(width 0.0127)
				(type default)
			)
			(layer "F.SilkS")
		)
		(fp_line
			(start -1.146556 2.0193)
			(end -0.834644 2.0193)
			(stroke
				(width 0.0127)
				(type default)
			)
			(layer "F.SilkS")
		)
		(fp_line
			(start -1.137158 2.009902)
			(end -0.844296 2.009902)
			(stroke
				(width 0.0127)
				(type default)
			)
			(layer "F.SilkS")
		)
		(fp_line
			(start -1.127506 2.00025)
			(end -0.853694 2.00025)
			(stroke
				(width 0.0127)
				(type default)
			)
			(layer "F.SilkS")
		)
		(fp_line
			(start -1.118108 1.990852)
			(end -0.863346 1.990852)
			(stroke
				(width 0.0127)
				(type default)
			)
			(layer "F.SilkS")
		)
		(fp_line
			(start -1.108456 1.9812)
			(end -0.872744 1.9812)
			(stroke
				(width 0.0127)
				(type default)
			)
			(layer "F.SilkS")
		)
		(fp_line
			(start -1.099058 1.971802)
			(end -0.882396 1.971802)
			(stroke
				(width 0.0127)
				(type default)
			)
			(layer "F.SilkS")
		)
		(fp_line
			(start -1.089406 1.96215)
			(end -0.891794 1.96215)
			(stroke
				(width 0.0127)
				(type default)
			)
			(layer "F.SilkS")
		)
		(fp_line
			(start -1.080008 1.952752)
			(end -0.901446 1.952752)
			(stroke
				(width 0.0127)
				(type default)
			)
			(layer "F.SilkS")
		)
		(fp_line
			(start -1.070356 1.9431)
			(end -0.910844 1.9431)
			(stroke
				(width 0.0127)
				(type default)
			)
			(layer "F.SilkS")
		)
		(fp_line
			(start -1.060958 1.933702)
			(end -0.920496 1.933702)
			(stroke
				(width 0.0127)
				(type default)
			)
			(layer "F.SilkS")
		)
		(fp_line
			(start -1.051306 1.92405)
			(end -0.929894 1.92405)
			(stroke
				(width 0.0127)
				(type default)
			)
			(layer "F.SilkS")
		)
		(fp_line
			(start -1.041908 1.914652)
			(end -0.939546 1.914652)
			(stroke
				(width 0.0127)
				(type default)
			)
			(layer "F.SilkS")
		)
		(fp_line
			(start -1.032256 1.905)
			(end -0.948944 1.905)
			(stroke
				(width 0.0127)
				(type default)
			)
			(layer "F.SilkS")
		)
		(fp_line
			(start -1.022858 1.895602)
			(end -0.958596 1.895602)
			(stroke
				(width 0.0127)
				(type default)
			)
			(layer "F.SilkS")
		)
		(fp_line
			(start -1.013206 1.88595)
			(end -0.967994 1.88595)
			(stroke
				(width 0.0127)
				(type default)
			)
			(layer "F.SilkS")
		)
		(fp_line
			(start -1.003808 1.876552)
			(end -0.977646 1.876552)
			(stroke
				(width 0.0127)
				(type default)
			)
			(layer "F.SilkS")
		)
		(fp_line
			(start -0.994156 1.8669)
			(end -0.987044 1.8669)
			(stroke
				(width 0.0127)
				(type default)
			)
			(layer "F.SilkS")
		)
		(fp_line
			(start -0.9906 1.86309)
			(end -0.701294 2.15265)
			(stroke
				(width 0.0127)
				(type default)
			)
			(layer "F.SilkS")
		)
		(fp_line
			(start -0.719074 2.145538)
			(end -1.265936 2.14122)
			(stroke
				(width 0.0127)
				(type default)
			)
			(layer "F.SilkS")
		)
		(fp_line
			(start -0.71628 2.15265)
			(end -1.26492 2.15265)
			(stroke
				(width 0.0127)
				(type default)
			)
			(layer "F.SilkS")
		)
		(fp_line
			(start -0.635 1.8796)
			(end -1.7526 1.8796)
			(stroke
				(width 0.3302)
				(type default)
			)
			(layer "F.SilkS")
		)
		(fp_line
			(start 1.651 -1.778)
			(end -1.651 -1.778)
			(stroke
				(width 0.1524)
				(type default)
			)
			(layer "F.SilkS")
		)
		(fp_line
			(start 1.651 1.778)
			(end 1.651 -1.778)
			(stroke
				(width 0.1524)
				(type default)
			)
			(layer "F.SilkS")
		)
		(fp_poly
			(pts
				(xy -1.285748 2.159) (xy -1.285748 1.8796) (xy -1.778 1.8796) (xy -1.778 -1.8796) (xy 1.778 -1.8796)
				(xy 1.778 1.8796) (xy -0.694944 1.8796) (xy -0.694944 2.159)
			)
			(stroke
				(width 0)
				(type default)
			)
			(fill no)
			(layer "F.CrtYd")
		)
		(fp_poly
			(pts
				(xy -1.285748 2.159) (xy -1.285748 1.8796) (xy -1.778 1.8796) (xy -1.778 -1.8796) (xy 1.778 -1.8796)
				(xy 1.778 1.8796) (xy -0.694944 1.8796) (xy -0.694944 2.159)
			)
			(stroke
				(width 0)
				(type default)
			)
			(fill no)
			(layer "F.Fab")
		)
		(pad "1" smd rect
			(at -0.98425 0.9525)
			(size 0.762 1.143)
			(layers "F.Cu" "F.Mask" "F.Paste")
			(net "LED_DR_LED4_B")
		)
		(pad "2" smd rect
			(at 0.98425 0.9525)
			(size 0.762 1.143)
			(layers "F.Cu" "F.Mask" "F.Paste")
			(net "GND")
		)
		(pad "3" smd rect
			(at 0 -0.9525)
			(size 0.762 1.143)
			(layers "F.Cu" "F.Mask" "F.Paste")
			(net "LED_DR_LED4_BLUE")
		)
	)
	(footprint ""
		(layer "F.Cu")
		(at 27.559 -217.780616)
		(property "Reference" "U7"
			(at 0 0 0)
			(layer "F.SilkS")
			(hide yes)
			(effects
				(font
					(size 1.27 1.27)
				)
			)
		)
		(property "Value" "TSLV07APWR-GP"
			(at -7.112 -6.0579 0)
			(unlocked yes)
			(layer "F.Fab")
			(hide yes)
			(effects
				(font
					(size 1.016 1.016)
					(thickness 0.1524)
				)
			)
		)
		(property "Device Type" "TSOIC14H48"
			(at -7.112 -7.5819 0)
			(unlocked yes)
			(layer "F.Fab")
			(hide yes)
			(effects
				(font
					(size 1.016 1.016)
					(thickness 0.1524)
				)
			)
		)
		(duplicate_pad_numbers_are_jumpers no)
		(fp_line
			(start -2.9718 -1.778)
			(end 2.1336 -1.778)
			(stroke
				(width 0.1524)
				(type default)
			)
			(layer "F.SilkS")
		)
		(fp_line
			(start -2.9718 1.778)
			(end -2.9718 -1.778)
			(stroke
				(width 0.1524)
				(type default)
			)
			(layer "F.SilkS")
		)
		(fp_line
			(start -2.9337 -0.4699)
			(end -2.9083 -0.4699)
			(stroke
				(width 0.1524)
				(type default)
			)
			(layer "F.SilkS")
		)
		(fp_line
			(start -2.9083 -0.4699)
			(end -2.4384 0)
			(stroke
				(width 0.1524)
				(type default)
			)
			(layer "F.SilkS")
		)
		(fp_line
			(start -2.8956 0.4572)
			(end -2.921 0.4572)
			(stroke
				(width 0.1524)
				(type default)
			)
			(layer "F.SilkS")
		)
		(fp_line
			(start -2.794 3.8227)
			(end -2.794 1.7018)
			(stroke
				(width 0.508)
				(type default)
			)
			(layer "F.SilkS")
		)
		(fp_line
			(start -2.4384 0)
			(end -2.8956 0.4572)
			(stroke
				(width 0.1524)
				(type default)
			)
			(layer "F.SilkS")
		)
		(fp_line
			(start 2.1336 -1.778)
			(end 2.1336 1.778)
			(stroke
				(width 0.1524)
				(type default)
			)
			(layer "F.SilkS")
		)
		(fp_line
			(start 2.1336 1.778)
			(end -2.9718 1.778)
			(stroke
				(width 0.1524)
				(type default)
			)
			(layer "F.SilkS")
		)
		(fp_poly
			(pts
				(xy -2.1336 -1.7653) (xy 2.1336 -1.7653) (xy 2.1336 1.778) (xy -2.1336 1.778)
			)
			(stroke
				(width 0)
				(type default)
			)
			(fill yes)
			(layer "F.SilkS")
		)
		(fp_rect
			(start -2.5019 3.2004)
			(end 2.5019 -3.2004)
			(stroke
				(width 0)
				(type default)
			)
			(fill no)
			(layer "F.CrtYd")
		)
		(fp_poly
			(pts
				(xy -3.048 4.0894) (xy -3.048 -2.5781) (xy -2.5019 -2.5781) (xy -2.5019 3.2004) (xy 2.5019 3.2004)
				(xy 2.5019 -3.2004) (xy -2.5019 -3.2004) (xy -2.5019 -2.5908) (xy -3.048 -2.5908) (xy -3.048 -4.0894)
				(xy 3.048 -4.0894) (xy 3.048 4.0894)
			)
			(stroke
				(width 0)
				(type default)
			)
			(fill no)
			(layer "F.CrtYd")
		)
		(fp_rect
			(start -3.048 4.0894)
			(end 3.048 -4.0894)
			(stroke
				(width 0)
				(type default)
			)
			(fill no)
			(layer "F.Fab")
		)
		(pad "1" smd rect
			(at -1.94945 2.8194)
			(size 0.3556 1.524)
			(layers "F.Cu" "F.Mask" "F.Paste")
			(net "PWM_BUFFER_IN_FAN5_FAN6")
		)
		(pad "2" smd rect
			(at -1.30048 2.8194)
			(size 0.3556 1.524)
			(layers "F.Cu" "F.Mask" "F.Paste")
			(net "PWM_OUT_FAN6")
		)
		(pad "3" smd rect
			(at -0.65024 2.8194)
			(size 0.3556 1.524)
			(layers "F.Cu" "F.Mask" "F.Paste")
			(net "PWM_BUFFER_IN_FAN5_FAN6")
		)
		(pad "4" smd rect
			(at 0 2.8194)
			(size 0.3556 1.524)
			(layers "F.Cu" "F.Mask" "F.Paste")
			(net "PWM_OUT_FAN5")
		)
		(pad "5" smd rect
			(at 0.65024 2.8194)
			(size 0.3556 1.524)
			(layers "F.Cu" "F.Mask" "F.Paste")
			(net "PWM_BUFFER_IN_FAN3_FAN4")
		)
		(pad "6" smd rect
			(at 1.30048 2.8194)
			(size 0.3556 1.524)
			(layers "F.Cu" "F.Mask" "F.Paste")
			(net "PWM_OUT_FAN4")
		)
		(pad "7" smd rect
			(at 1.94945 2.8194)
			(size 0.3556 1.524)
			(layers "F.Cu" "F.Mask" "F.Paste")
			(net "GND")
		)
		(pad "8" smd rect
			(at 1.94945 -2.8194)
			(size 0.3556 1.524)
			(layers "F.Cu" "F.Mask" "F.Paste")
			(net "PWM_OUT_FAN3")
		)
		(pad "9" smd rect
			(at 1.30048 -2.8194)
			(size 0.3556 1.524)
			(layers "F.Cu" "F.Mask" "F.Paste")
			(net "PWM_BUFFER_IN_FAN3_FAN4")
		)
		(pad "10" smd rect
			(at 0.65024 -2.8194)
			(size 0.3556 1.524)
			(layers "F.Cu" "F.Mask" "F.Paste")
			(net "PWM_OUT_FAN2")
		)
		(pad "11" smd rect
			(at 0 -2.8194)
			(size 0.3556 1.524)
			(layers "F.Cu" "F.Mask" "F.Paste")
			(net "PWM_BUFFER_IN_FAN1_FAN2")
		)
		(pad "12" smd rect
			(at -0.65024 -2.8194)
			(size 0.3556 1.524)
			(layers "F.Cu" "F.Mask" "F.Paste")
			(net "PWM_OUT_FAN1")
		)
		(pad "13" smd rect
			(at -1.30048 -2.8194)
			(size 0.3556 1.524)
			(layers "F.Cu" "F.Mask" "F.Paste")
			(net "PWM_BUFFER_IN_FAN1_FAN2")
		)
		(pad "14" smd rect
			(at -1.94945 -2.8194)
			(size 0.3556 1.524)
			(layers "F.Cu" "F.Mask" "F.Paste")
			(net "P3V3")
		)
	)
	(footprint ""
		(layer "F.Cu")
		(at 19.2278 -182.1942)
		(property "Reference" "C36"
			(at 0 0 0)
			(layer "F.SilkS")
			(hide yes)
			(effects
				(font
					(size 1.27 1.27)
				)
			)
		)
		(property "Value" "SCD1U16V2KX-3GP"
			(at 1.1811 -2.7051 0)
			(unlocked yes)
			(layer "F.Fab")
			(hide yes)
			(effects
				(font
					(size 1.016 1.016)
					(thickness 0.1524)
				)
			)
		)
		(property "Device Type" "C402H22"
			(at 1.1811 -4.2291 0)
			(unlocked yes)
			(layer "F.Fab")
			(hide yes)
			(effects
				(font
					(size 1.016 1.016)
					(thickness 0.1524)
				)
			)
		)
		(duplicate_pad_numbers_are_jumpers no)
		(fp_rect
			(start -0.4318 0.9525)
			(end 0.4318 -0.9525)
			(stroke
				(width 0)
				(type default)
			)
			(fill no)
			(layer "F.CrtYd")
		)
		(fp_rect
			(start -0.4318 0.9525)
			(end 0.4318 -0.9525)
			(stroke
				(width 0)
				(type default)
			)
			(fill no)
			(layer "F.Fab")
		)
		(pad "1" smd custom
			(at 0 -0.4445)
			(size 0.1524 0.1524)
			(layers "F.Cu" "F.Mask" "F.Paste")
			(net "FAN_TACH7")
			(options
				(clearance outline)
				(anchor circle)
			)
			(primitives
				(gr_poly
					(pts
						(arc
							(start 0.3048 -0.2032)
							(mid 0.275042 -0.275042)
							(end 0.2032 -0.3048)
						)
						(arc
							(start -0.2032 -0.3048)
							(mid -0.275042 -0.275042)
							(end -0.3048 -0.2032)
						)
						(arc
							(start -0.3048 0.2032)
							(mid -0.275042 0.275042)
							(end -0.2032 0.3048)
						)
						(arc
							(start 0.2032 0.3048)
							(mid 0.275042 0.275042)
							(end 0.3048 0.2032)
						)
					)
					(width 0)
					(fill yes)
				)
			)
		)
		(pad "2" smd custom
			(at 0 0.4445)
			(size 0.1524 0.1524)
			(layers "F.Cu" "F.Mask" "F.Paste")
			(net "GND")
			(options
				(clearance outline)
				(anchor circle)
			)
			(primitives
				(gr_poly
					(pts
						(arc
							(start 0.3048 -0.2032)
							(mid 0.275042 -0.275042)
							(end 0.2032 -0.3048)
						)
						(arc
							(start -0.2032 -0.3048)
							(mid -0.275042 -0.275042)
							(end -0.3048 -0.2032)
						)
						(arc
							(start -0.3048 0.2032)
							(mid -0.275042 0.275042)
							(end -0.2032 0.3048)
						)
						(arc
							(start 0.2032 0.3048)
							(mid 0.275042 0.275042)
							(end 0.3048 0.2032)
						)
					)
					(width 0)
					(fill yes)
				)
			)
		)
	)
	(footprint ""
		(layer "F.Cu")
		(at 31.9024 -91.8972 90)
		(property "Reference" "D16"
			(at 0 0 90)
			(layer "F.SilkS")
			(hide yes)
			(effects
				(font
					(size 1.27 1.27)
				)
			)
		)
		(property "Value" "MBRS340T3G-GP"
			(at 0 -10.6172 90)
			(unlocked yes)
			(layer "F.Fab")
			(hide yes)
			(effects
				(font
					(size 1.016 1.016)
					(thickness 0.1524)
				)
			)
		)
		(property "Device Type" "D8059AKH101"
			(at 0 -12.1412 90)
			(unlocked yes)
			(layer "F.Fab")
			(hide yes)
			(effects
				(font
					(size 1.016 1.016)
					(thickness 0.1524)
				)
			)
		)
		(duplicate_pad_numbers_are_jumpers no)
		(fp_line
			(start 3.175 -5.1054)
			(end 3.175 5.1054)
			(stroke
				(width 0.1524)
				(type default)
			)
			(layer "F.SilkS")
		)
		(fp_line
			(start -3.175 -5.1054)
			(end 3.175 -5.1054)
			(stroke
				(width 0.1524)
				(type default)
			)
			(layer "F.SilkS")
		)
		(fp_line
			(start 3.175 5.1054)
			(end -3.175 5.1054)
			(stroke
				(width 0.1524)
				(type default)
			)
			(layer "F.SilkS")
		)
		(fp_line
			(start -3.175 5.1054)
			(end -3.175 -5.1054)
			(stroke
				(width 0.1524)
				(type default)
			)
			(layer "F.SilkS")
		)
		(fp_line
			(start 3.175 5.2832)
			(end -3.175 5.2832)
			(stroke
				(width 0.508)
				(type default)
			)
			(layer "F.SilkS")
		)
		(fp_rect
			(start -3.429 5.1816)
			(end 3.429 -5.1816)
			(stroke
				(width 0)
				(type default)
			)
			(fill no)
			(layer "F.CrtYd")
		)
		(fp_poly
			(pts
				(xy -3.429 -5.1816) (xy 3.429 -5.1816) (xy 3.429 5.1816) (xy -3.429 5.1816)
			)
			(stroke
				(width 0)
				(type default)
			)
			(fill no)
			(layer "F.Fab")
		)
		(pad "A" smd rect
			(at 0 -3.77571 90)
			(size 3.2512 2.159)
			(layers "F.Cu" "F.Mask" "F.Paste")
			(net "GND")
		)
		(pad "K" smd rect
			(at 0 3.77571 90)
			(size 3.2512 2.159)
			(layers "F.Cu" "F.Mask" "F.Paste")
			(net "P12VL")
		)
	)
	(footprint ""
		(layer "F.Cu")
		(at 36.83 -240.665 180)
		(property "Reference" "R148"
			(at 0 0 180)
			(layer "F.SilkS")
			(hide yes)
			(effects
				(font
					(size 1.27 1.27)
				)
			)
		)
		(property "Value" "330R2J-3-GP"
			(at 0.064008 -3.993896 180)
			(unlocked yes)
			(layer "F.Fab")
			(hide yes)
			(effects
				(font
					(size 1.016 1.016)
					(thickness 0.1524)
				)
			)
		)
		(property "Device Type" "R402H16"
			(at 0.064008 -5.517896 180)
			(unlocked yes)
			(layer "F.Fab")
			(hide yes)
			(effects
				(font
					(size 1.016 1.016)
					(thickness 0.1524)
				)
			)
		)
		(duplicate_pad_numbers_are_jumpers no)
		(fp_line
			(start 0.508 -0.9398)
			(end -0.508 -0.9398)
			(stroke
				(width 0.1524)
				(type default)
			)
			(layer "F.SilkS")
		)
		(fp_line
			(start -0.508 -0.9398)
			(end -0.508 0.9398)
			(stroke
				(width 0.1524)
				(type default)
			)
			(layer "F.SilkS")
		)
		(fp_rect
			(start -0.508 0.9398)
			(end 0.508 -0.9398)
			(stroke
				(width 0)
				(type default)
			)
			(fill no)
			(layer "F.CrtYd")
		)
		(fp_rect
			(start -0.508 0.9398)
			(end 0.508 -0.9398)
			(stroke
				(width 0)
				(type default)
			)
			(fill no)
			(layer "F.Fab")
		)
		(pad "1" smd custom
			(at 0 -0.4445 180)
			(size 0.1397 0.1397)
			(layers "F.Cu" "F.Mask" "F.Paste")
			(net "P3V3")
			(options
				(clearance outline)
				(anchor circle)
			)
			(primitives
				(gr_poly
					(pts
						(arc
							(start -0.1778 -0.2794)
							(mid -0.249642 -0.249642)
							(end -0.2794 -0.1778)
						)
						(arc
							(start -0.2794 0.1778)
							(mid -0.249642 0.249642)
							(end -0.1778 0.2794)
						)
						(arc
							(start 0.1778 0.2794)
							(mid 0.249642 0.249642)
							(end 0.2794 0.1778)
						)
						(arc
							(start 0.2794 -0.1778)
							(mid 0.249642 -0.249642)
							(end 0.1778 -0.2794)
						)
					)
					(width 0)
					(fill yes)
				)
			)
		)
		(pad "2" smd custom
			(at 0 0.4445 180)
			(size 0.1397 0.1397)
			(layers "F.Cu" "F.Mask" "F.Paste")
			(net "LED_DR_LED0")
			(options
				(clearance outline)
				(anchor circle)
			)
			(primitives
				(gr_poly
					(pts
						(arc
							(start -0.1778 -0.2794)
							(mid -0.249642 -0.249642)
							(end -0.2794 -0.1778)
						)
						(arc
							(start -0.2794 0.1778)
							(mid -0.249642 0.249642)
							(end -0.1778 0.2794)
						)
						(arc
							(start 0.1778 0.2794)
							(mid 0.249642 0.249642)
							(end 0.2794 0.1778)
						)
						(arc
							(start 0.2794 -0.1778)
							(mid 0.249642 -0.249642)
							(end 0.1778 -0.2794)
						)
					)
					(width 0)
					(fill yes)
				)
			)
		)
	)
	(footprint ""
		(layer "F.Cu")
		(at 20.3454 -481.5586)
		(property "Reference" "R177"
			(at 0 0 0)
			(layer "F.SilkS")
			(hide yes)
			(effects
				(font
					(size 1.27 1.27)
				)
			)
		)
		(property "Value" "0R1206-PAD-1-GP"
			(at 0 -5.0292 0)
			(unlocked yes)
			(layer "F.Fab")
			(hide yes)
			(effects
				(font
					(size 1.016 1.016)
					(thickness 0.1524)
				)
			)
		)
		(property "Device Type" "0R1206-PAD-1"
			(at 0 -6.5532 0)
			(unlocked yes)
			(layer "F.Fab")
			(hide yes)
			(effects
				(font
					(size 1.016 1.016)
					(thickness 0.1524)
				)
			)
		)
		(duplicate_pad_numbers_are_jumpers no)
		(fp_line
			(start -1.016 -2.2352)
			(end -1.016 2.2352)
			(stroke
				(width 0.1524)
				(type default)
			)
			(layer "F.SilkS")
		)
		(fp_line
			(start -1.016 2.2352)
			(end 1.016 2.2352)
			(stroke
				(width 0.1524)
				(type default)
			)
			(layer "F.SilkS")
		)
		(fp_line
			(start 1.016 -2.2352)
			(end -1.016 -2.2352)
			(stroke
				(width 0.1524)
				(type default)
			)
			(layer "F.SilkS")
		)
		(fp_line
			(start 1.016 2.2352)
			(end 1.016 -2.2352)
			(stroke
				(width 0.1524)
				(type default)
			)
			(layer "F.SilkS")
		)
		(fp_rect
			(start -1.0922 2.3114)
			(end 1.0922 -2.3114)
			(stroke
				(width 0)
				(type default)
			)
			(fill no)
			(layer "F.CrtYd")
		)
		(fp_poly
			(pts
				(xy -1.0922 -2.3114) (xy 1.0922 -2.3114) (xy 1.0922 2.3114) (xy -1.0922 2.3114)
			)
			(stroke
				(width 0)
				(type default)
			)
			(fill no)
			(layer "F.Fab")
		)
		(pad "1" smd rect
			(at 0 -1.397)
			(size 1.651 2.0574)
			(drill
				(offset 0 0.3937)
			)
			(layers "F.Cu" "F.Mask" "F.Paste")
			(net "P12V_FAN1")
		)
		(pad "2" smd rect
			(at 0 1.397)
			(size 1.651 2.0574)
			(drill
				(offset 0 -0.3937)
			)
			(layers "F.Cu" "F.Mask" "F.Paste")
			(net "P12V")
		)
	)
	(footprint ""
		(layer "F.Cu")
		(at 38.43909 -161.068766 180)
		(property "Reference" "R5"
			(at 0 0 180)
			(layer "F.SilkS")
			(hide yes)
			(effects
				(font
					(size 1.27 1.27)
				)
			)
		)
		(property "Value" "0R2J-2-GP"
			(at 0.064008 -3.993896 180)
			(unlocked yes)
			(layer "F.Fab")
			(hide yes)
			(effects
				(font
					(size 1.016 1.016)
					(thickness 0.1524)
				)
			)
		)
		(property "Device Type" "R402H16"
			(at 0.064008 -5.517896 180)
			(unlocked yes)
			(layer "F.Fab")
			(hide yes)
			(effects
				(font
					(size 1.016 1.016)
					(thickness 0.1524)
				)
			)
		)
		(duplicate_pad_numbers_are_jumpers no)
		(fp_line
			(start 0.508 -0.9398)
			(end -0.508 -0.9398)
			(stroke
				(width 0.1524)
				(type default)
			)
			(layer "F.SilkS")
		)
		(fp_line
			(start -0.508 -0.9398)
			(end -0.508 0.9398)
			(stroke
				(width 0.1524)
				(type default)
			)
			(layer "F.SilkS")
		)
		(fp_rect
			(start -0.508 0.9398)
			(end 0.508 -0.9398)
			(stroke
				(width 0)
				(type default)
			)
			(fill no)
			(layer "F.CrtYd")
		)
		(fp_rect
			(start -0.508 0.9398)
			(end 0.508 -0.9398)
			(stroke
				(width 0)
				(type default)
			)
			(fill no)
			(layer "F.Fab")
		)
		(pad "1" smd custom
			(at 0 -0.4445 180)
			(size 0.1397 0.1397)
			(layers "F.Cu" "F.Mask" "F.Paste")
			(net "NCT7904_CLKIN")
			(options
				(clearance outline)
				(anchor circle)
			)
			(primitives
				(gr_poly
					(pts
						(arc
							(start -0.1778 -0.2794)
							(mid -0.249642 -0.249642)
							(end -0.2794 -0.1778)
						)
						(arc
							(start -0.2794 0.1778)
							(mid -0.249642 0.249642)
							(end -0.1778 0.2794)
						)
						(arc
							(start 0.1778 0.2794)
							(mid 0.249642 0.249642)
							(end 0.2794 0.1778)
						)
						(arc
							(start 0.2794 -0.1778)
							(mid 0.249642 -0.249642)
							(end 0.1778 -0.2794)
						)
					)
					(width 0)
					(fill yes)
				)
			)
		)
		(pad "2" smd custom
			(at 0 0.4445 180)
			(size 0.1397 0.1397)
			(layers "F.Cu" "F.Mask" "F.Paste")
			(net "NCT7904_CLK")
			(options
				(clearance outline)
				(anchor circle)
			)
			(primitives
				(gr_poly
					(pts
						(arc
							(start -0.1778 -0.2794)
							(mid -0.249642 -0.249642)
							(end -0.2794 -0.1778)
						)
						(arc
							(start -0.2794 0.1778)
							(mid -0.249642 0.249642)
							(end -0.1778 0.2794)
						)
						(arc
							(start 0.1778 0.2794)
							(mid 0.249642 0.249642)
							(end 0.2794 0.1778)
						)
						(arc
							(start 0.2794 -0.1778)
							(mid 0.249642 -0.249642)
							(end 0.1778 -0.2794)
						)
					)
					(width 0)
					(fill yes)
				)
			)
		)
	)
	(footprint ""
		(layer "F.Cu")
		(at 37.846508 -282.993338)
		(property "Reference" "C47"
			(at 0 0 0)
			(layer "F.SilkS")
			(hide yes)
			(effects
				(font
					(size 1.27 1.27)
				)
			)
		)
		(property "Value" "SCD1U50V3KX-GP"
			(at 0 -2.8194 0)
			(unlocked yes)
			(layer "F.Fab")
			(hide yes)
			(effects
				(font
					(size 1.016 1.016)
					(thickness 0.1524)
				)
			)
		)
		(property "Device Type" "C603H36"
			(at 0 -4.3434 0)
			(unlocked yes)
			(layer "F.Fab")
			(hide yes)
			(effects
				(font
					(size 1.016 1.016)
					(thickness 0.1524)
				)
			)
		)
		(duplicate_pad_numbers_are_jumpers no)
		(fp_line
			(start 0.508 0)
			(end -0.508 0)
			(stroke
				(width 0.2032)
				(type default)
			)
			(layer "F.SilkS")
		)
		(fp_rect
			(start -0.5842 1.3335)
			(end 0.5842 -1.3335)
			(stroke
				(width 0)
				(type default)
			)
			(fill no)
			(layer "F.CrtYd")
		)
		(fp_rect
			(start -0.5842 1.3335)
			(end 0.5842 -1.3335)
			(stroke
				(width 0)
				(type default)
			)
			(fill no)
			(layer "F.Fab")
		)
		(pad "1" smd custom
			(at 0 -0.762)
			(size 0.2159 0.2159)
			(layers "F.Cu" "F.Mask" "F.Paste")
			(net "P12V")
			(options
				(clearance outline)
				(anchor circle)
			)
			(primitives
				(gr_poly
					(pts
						(arc
							(start -0.3302 -0.4318)
							(mid -0.402042 -0.402042)
							(end -0.4318 -0.3302)
						)
						(arc
							(start -0.4318 0.3302)
							(mid -0.402042 0.402042)
							(end -0.3302 0.4318)
						)
						(arc
							(start 0.3302 0.4318)
							(mid 0.402042 0.402042)
							(end 0.4318 0.3302)
						)
						(arc
							(start 0.4318 -0.3302)
							(mid 0.402042 -0.402042)
							(end 0.3302 -0.4318)
						)
					)
					(width 0)
					(fill yes)
				)
			)
		)
		(pad "2" smd custom
			(at 0 0.762)
			(size 0.2159 0.2159)
			(layers "F.Cu" "F.Mask" "F.Paste")
			(net "GND")
			(options
				(clearance outline)
				(anchor circle)
			)
			(primitives
				(gr_poly
					(pts
						(arc
							(start -0.3302 -0.4318)
							(mid -0.402042 -0.402042)
							(end -0.4318 -0.3302)
						)
						(arc
							(start -0.4318 0.3302)
							(mid -0.402042 0.402042)
							(end -0.3302 0.4318)
						)
						(arc
							(start 0.3302 0.4318)
							(mid 0.402042 0.402042)
							(end 0.4318 0.3302)
						)
						(arc
							(start 0.4318 -0.3302)
							(mid 0.402042 -0.402042)
							(end 0.3302 -0.4318)
						)
					)
					(width 0)
					(fill yes)
				)
			)
		)
	)
	(footprint ""
		(layer "F.Cu")
		(at 17.526 -16.129 -90)
		(property "Reference" "R65"
			(at 0 0 270)
			(layer "F.SilkS")
			(hide yes)
			(effects
				(font
					(size 1.27 1.27)
				)
			)
		)
		(property "Value" "4K7R2F-GP"
			(at 0.064008 -3.993896 270)
			(unlocked yes)
			(layer "F.Fab")
			(hide yes)
			(effects
				(font
					(size 1.016 1.016)
					(thickness 0.1524)
				)
			)
		)
		(property "Device Type" "R402H16"
			(at 0.064008 -5.517896 270)
			(unlocked yes)
			(layer "F.Fab")
			(hide yes)
			(effects
				(font
					(size 1.016 1.016)
					(thickness 0.1524)
				)
			)
		)
		(duplicate_pad_numbers_are_jumpers no)
		(fp_line
			(start -0.508 -0.9398)
			(end -0.508 0.9398)
			(stroke
				(width 0.1524)
				(type default)
			)
			(layer "F.SilkS")
		)
		(fp_line
			(start 0.508 -0.9398)
			(end -0.508 -0.9398)
			(stroke
				(width 0.1524)
				(type default)
			)
			(layer "F.SilkS")
		)
		(fp_rect
			(start -0.508 0.9398)
			(end 0.508 -0.9398)
			(stroke
				(width 0)
				(type default)
			)
			(fill no)
			(layer "F.CrtYd")
		)
		(fp_rect
			(start -0.508 0.9398)
			(end 0.508 -0.9398)
			(stroke
				(width 0)
				(type default)
			)
			(fill no)
			(layer "F.Fab")
		)
		(pad "1" smd custom
			(at 0 -0.4445 270)
			(size 0.1397 0.1397)
			(layers "F.Cu" "F.Mask" "F.Paste")
			(net "P12V")
			(options
				(clearance outline)
				(anchor circle)
			)
			(primitives
				(gr_poly
					(pts
						(arc
							(start -0.1778 -0.2794)
							(mid -0.249642 -0.249642)
							(end -0.2794 -0.1778)
						)
						(arc
							(start -0.2794 0.1778)
							(mid -0.249642 0.249642)
							(end -0.1778 0.2794)
						)
						(arc
							(start 0.1778 0.2794)
							(mid 0.249642 0.249642)
							(end 0.2794 0.1778)
						)
						(arc
							(start 0.2794 -0.1778)
							(mid 0.249642 -0.249642)
							(end 0.1778 -0.2794)
						)
					)
					(width 0)
					(fill yes)
				)
			)
		)
		(pad "2" smd custom
			(at 0 0.4445 270)
			(size 0.1397 0.1397)
			(layers "F.Cu" "F.Mask" "F.Paste")
			(net "PWM_OUT_FAN6_NET")
			(options
				(clearance outline)
				(anchor circle)
			)
			(primitives
				(gr_poly
					(pts
						(arc
							(start -0.1778 -0.2794)
							(mid -0.249642 -0.249642)
							(end -0.2794 -0.1778)
						)
						(arc
							(start -0.2794 0.1778)
							(mid -0.249642 0.249642)
							(end -0.1778 0.2794)
						)
						(arc
							(start 0.1778 0.2794)
							(mid 0.249642 0.249642)
							(end 0.2794 0.1778)
						)
						(arc
							(start 0.2794 -0.1778)
							(mid 0.249642 -0.249642)
							(end 0.1778 -0.2794)
						)
					)
					(width 0)
					(fill yes)
				)
			)
		)
	)
	(footprint ""
		(layer "F.Cu")
		(at 7.949946 -443.900052 -90)
		(property "Reference" "LED1"
			(at 0 0 270)
			(layer "F.SilkS")
			(hide yes)
			(effects
				(font
					(size 1.27 1.27)
				)
			)
		)
		(property "Value" "LED-RB-6-GP"
			(at -4.6736 3.8354 270)
			(unlocked yes)
			(layer "F.Fab")
			(hide yes)
			(effects
				(font
					(size 1.016 1.016)
					(thickness 0.1524)
				)
			)
		)
		(property "Device Type" "LED-100-3P-067106H325"
			(at -4.6736 2.3114 270)
			(unlocked yes)
			(layer "F.Fab")
			(hide yes)
			(effects
				(font
					(size 1.016 1.016)
					(thickness 0.1524)
				)
			)
		)
		(duplicate_pad_numbers_are_jumpers no)
		(fp_line
			(start -1.7526 10.414)
			(end -1.7526 6.6548)
			(stroke
				(width 0.1524)
				(type default)
			)
			(layer "F.SilkS")
		)
		(fp_line
			(start 1.7526 10.414)
			(end -1.7526 10.414)
			(stroke
				(width 0.1524)
				(type default)
			)
			(layer "F.SilkS")
		)
		(fp_line
			(start -3.6068 6.6548)
			(end -3.6068 -0.889)
			(stroke
				(width 0.1524)
				(type default)
			)
			(layer "F.SilkS")
		)
		(fp_line
			(start -1.7526 6.6548)
			(end -3.6068 6.6548)
			(stroke
				(width 0.1524)
				(type default)
			)
			(layer "F.SilkS")
		)
		(fp_line
			(start 1.7526 6.6548)
			(end 1.7526 10.414)
			(stroke
				(width 0.1524)
				(type default)
			)
			(layer "F.SilkS")
		)
		(fp_line
			(start 3.6068 6.6548)
			(end 1.7526 6.6548)
			(stroke
				(width 0.1524)
				(type default)
			)
			(layer "F.SilkS")
		)
		(fp_line
			(start -3.6068 -0.889)
			(end 3.6068 -0.889)
			(stroke
				(width 0.1524)
				(type default)
			)
			(layer "F.SilkS")
		)
		(fp_line
			(start 3.6068 -0.889)
			(end 3.6068 6.6548)
			(stroke
				(width 0.1524)
				(type default)
			)
			(layer "F.SilkS")
		)
		(fp_circle
			(center -2.54 0)
			(end -2.54 -0.9906)
			(stroke
				(width 0.3048)
				(type default)
			)
			(fill no)
			(layer "F.SilkS")
		)
		(fp_circle
			(center 0 0)
			(end 0 -0.9906)
			(stroke
				(width 0.3048)
				(type default)
			)
			(fill no)
			(layer "F.SilkS")
		)
		(fp_circle
			(center 2.54 0)
			(end 2.54 -0.9906)
			(stroke
				(width 0.3048)
				(type default)
			)
			(fill no)
			(layer "F.SilkS")
		)
		(fp_poly
			(pts
				(xy -1.4986 10.1473) (xy -1.4986 6.4008) (xy -3.3528 6.4008) (xy -3.3528 -0.3937) (xy 3.3528 -0.3937)
				(xy 3.3528 6.4008) (xy 1.4986 6.4008) (xy 1.4986 10.1473)
			)
			(stroke
				(width 0)
				(type default)
			)
			(fill no)
			(layer "F.CrtYd")
		)
		(fp_poly
			(pts
				(xy -2.0066 10.668) (xy 2.0066 10.668) (xy 2.0066 6.9088) (xy 3.8608 6.9088) (xy 3.8608 2.2098)
				(xy 3.3528 2.2098) (xy 3.3528 6.4008) (xy 1.4986 6.4008) (xy 1.4986 10.1473) (xy -1.4986 10.1473)
				(xy -1.4986 6.4008) (xy -3.3528 6.4008) (xy -3.3528 -0.3937) (xy 3.3528 -0.3937) (xy 3.3528 2.1971)
				(xy 3.8608 2.1971) (xy 3.8608 -1.143) (xy -3.8608 -1.143) (xy -3.8608 6.9088) (xy -2.0066 6.9088)
			)
			(stroke
				(width 0)
				(type default)
			)
			(fill no)
			(layer "F.CrtYd")
		)
		(fp_poly
			(pts
				(xy -2.0066 10.668) (xy -2.0066 6.9088) (xy -3.8608 6.9088) (xy -3.8608 -1.143) (xy 3.8608 -1.143)
				(xy 3.8608 6.9088) (xy 2.0066 6.9088) (xy 2.0066 10.668)
			)
			(stroke
				(width 0)
				(type default)
			)
			(fill no)
			(layer "F.Fab")
		)
		(pad "1" thru_hole circle
			(at 2.54 0 270)
			(size 1.27 1.27)
			(drill 0.889)
			(layers "*.Cu" "*.Mask")
			(remove_unused_layers no)
			(net "LED_DR_LED0_BLUE")
			(clearance 0.1651)
			(thermal_gap 0.1651)
		)
		(pad "2" thru_hole circle
			(at 0 0 270)
			(size 1.27 1.27)
			(drill 0.889)
			(layers "*.Cu" "*.Mask")
			(remove_unused_layers no)
			(net "LED_DR_LED0_K")
			(clearance 0.1651)
			(thermal_gap 0.1651)
		)
		(pad "3" thru_hole circle
			(at -2.54 0 270)
			(size 1.27 1.27)
			(drill 0.889)
			(layers "*.Cu" "*.Mask")
			(remove_unused_layers no)
			(net "LED_DR_LED0")
			(clearance 0.1651)
			(thermal_gap 0.1651)
		)
	)
	(footprint ""
		(layer "F.Cu")
		(at 36.212526 -362.208826)
		(property "Reference" "PQ5"
			(at 0 0 0)
			(layer "F.SilkS")
			(hide yes)
			(effects
				(font
					(size 1.27 1.27)
				)
			)
		)
		(property "Value" "PMBS3904-1-GP"
			(at 0 -9.0932 0)
			(unlocked yes)
			(layer "F.Fab")
			(hide yes)
			(effects
				(font
					(size 1.016 1.016)
					(thickness 0.1524)
				)
			)
		)
		(property "Device Type" "SOT-23-10H44"
			(at 0 -10.6172 0)
			(unlocked yes)
			(layer "F.Fab")
			(hide yes)
			(effects
				(font
					(size 1.016 1.016)
					(thickness 0.1524)
				)
			)
		)
		(duplicate_pad_numbers_are_jumpers no)
		(fp_line
			(start -1.7526 1.8796)
			(end -1.7526 0.9906)
			(stroke
				(width 0.3302)
				(type default)
			)
			(layer "F.SilkS")
		)
		(fp_line
			(start -1.651 -1.778)
			(end -1.651 1.778)
			(stroke
				(width 0.1524)
				(type default)
			)
			(layer "F.SilkS")
		)
		(fp_line
			(start -1.651 1.778)
			(end 1.651 1.778)
			(stroke
				(width 0.1524)
				(type default)
			)
			(layer "F.SilkS")
		)
		(fp_line
			(start -1.279398 2.152142)
			(end -0.9906 1.86309)
			(stroke
				(width 0.0127)
				(type default)
			)
			(layer "F.SilkS")
		)
		(fp_line
			(start -1.279144 2.15265)
			(end -0.701294 2.15265)
			(stroke
				(width 0.0127)
				(type default)
			)
			(layer "F.SilkS")
		)
		(fp_line
			(start -1.260856 2.1336)
			(end -0.720344 2.1336)
			(stroke
				(width 0.0127)
				(type default)
			)
			(layer "F.SilkS")
		)
		(fp_line
			(start -1.251458 2.124202)
			(end -0.729996 2.124202)
			(stroke
				(width 0.0127)
				(type default)
			)
			(layer "F.SilkS")
		)
		(fp_line
			(start -1.241806 2.11455)
			(end -0.739394 2.11455)
			(stroke
				(width 0.0127)
				(type default)
			)
			(layer "F.SilkS")
		)
		(fp_line
			(start -1.232408 2.105152)
			(end -0.749046 2.105152)
			(stroke
				(width 0.0127)
				(type default)
			)
			(layer "F.SilkS")
		)
		(fp_line
			(start -1.222756 2.0955)
			(end -0.758444 2.0955)
			(stroke
				(width 0.0127)
				(type default)
			)
			(layer "F.SilkS")
		)
		(fp_line
			(start -1.213358 2.086102)
			(end -0.768096 2.086102)
			(stroke
				(width 0.0127)
				(type default)
			)
			(layer "F.SilkS")
		)
		(fp_line
			(start -1.203706 2.07645)
			(end -0.777494 2.07645)
			(stroke
				(width 0.0127)
				(type default)
			)
			(layer "F.SilkS")
		)
		(fp_line
			(start -1.194308 2.067052)
			(end -0.787146 2.067052)
			(stroke
				(width 0.0127)
				(type default)
			)
			(layer "F.SilkS")
		)
		(fp_line
			(start -1.184656 2.0574)
			(end -0.796544 2.0574)
			(stroke
				(width 0.0127)
				(type default)
			)
			(layer "F.SilkS")
		)
		(fp_line
			(start -1.175258 2.048002)
			(end -0.806196 2.048002)
			(stroke
				(width 0.0127)
				(type default)
			)
			(layer "F.SilkS")
		)
		(fp_line
			(start -1.165606 2.03835)
			(end -0.815594 2.03835)
			(stroke
				(width 0.0127)
				(type default)
			)
			(layer "F.SilkS")
		)
		(fp_line
			(start -1.156208 2.028952)
			(end -0.825246 2.028952)
			(stroke
				(width 0.0127)
				(type default)
			)
			(layer "F.SilkS")
		)
		(fp_line
			(start -1.146556 2.0193)
			(end -0.834644 2.0193)
			(stroke
				(width 0.0127)
				(type default)
			)
			(layer "F.SilkS")
		)
		(fp_line
			(start -1.137158 2.009902)
			(end -0.844296 2.009902)
			(stroke
				(width 0.0127)
				(type default)
			)
			(layer "F.SilkS")
		)
		(fp_line
			(start -1.127506 2.00025)
			(end -0.853694 2.00025)
			(stroke
				(width 0.0127)
				(type default)
			)
			(layer "F.SilkS")
		)
		(fp_line
			(start -1.118108 1.990852)
			(end -0.863346 1.990852)
			(stroke
				(width 0.0127)
				(type default)
			)
			(layer "F.SilkS")
		)
		(fp_line
			(start -1.108456 1.9812)
			(end -0.872744 1.9812)
			(stroke
				(width 0.0127)
				(type default)
			)
			(layer "F.SilkS")
		)
		(fp_line
			(start -1.099058 1.971802)
			(end -0.882396 1.971802)
			(stroke
				(width 0.0127)
				(type default)
			)
			(layer "F.SilkS")
		)
		(fp_line
			(start -1.089406 1.96215)
			(end -0.891794 1.96215)
			(stroke
				(width 0.0127)
				(type default)
			)
			(layer "F.SilkS")
		)
		(fp_line
			(start -1.080008 1.952752)
			(end -0.901446 1.952752)
			(stroke
				(width 0.0127)
				(type default)
			)
			(layer "F.SilkS")
		)
		(fp_line
			(start -1.070356 1.9431)
			(end -0.910844 1.9431)
			(stroke
				(width 0.0127)
				(type default)
			)
			(layer "F.SilkS")
		)
		(fp_line
			(start -1.060958 1.933702)
			(end -0.920496 1.933702)
			(stroke
				(width 0.0127)
				(type default)
			)
			(layer "F.SilkS")
		)
		(fp_line
			(start -1.051306 1.92405)
			(end -0.929894 1.92405)
			(stroke
				(width 0.0127)
				(type default)
			)
			(layer "F.SilkS")
		)
		(fp_line
			(start -1.041908 1.914652)
			(end -0.939546 1.914652)
			(stroke
				(width 0.0127)
				(type default)
			)
			(layer "F.SilkS")
		)
		(fp_line
			(start -1.032256 1.905)
			(end -0.948944 1.905)
			(stroke
				(width 0.0127)
				(type default)
			)
			(layer "F.SilkS")
		)
		(fp_line
			(start -1.022858 1.895602)
			(end -0.958596 1.895602)
			(stroke
				(width 0.0127)
				(type default)
			)
			(layer "F.SilkS")
		)
		(fp_line
			(start -1.013206 1.88595)
			(end -0.967994 1.88595)
			(stroke
				(width 0.0127)
				(type default)
			)
			(layer "F.SilkS")
		)
		(fp_line
			(start -1.003808 1.876552)
			(end -0.977646 1.876552)
			(stroke
				(width 0.0127)
				(type default)
			)
			(layer "F.SilkS")
		)
		(fp_line
			(start -0.994156 1.8669)
			(end -0.987044 1.8669)
			(stroke
				(width 0.0127)
				(type default)
			)
			(layer "F.SilkS")
		)
		(fp_line
			(start -0.9906 1.86309)
			(end -0.701294 2.15265)
			(stroke
				(width 0.0127)
				(type default)
			)
			(layer "F.SilkS")
		)
		(fp_line
			(start -0.719074 2.145538)
			(end -1.265936 2.14122)
			(stroke
				(width 0.0127)
				(type default)
			)
			(layer "F.SilkS")
		)
		(fp_line
			(start -0.71628 2.15265)
			(end -1.26492 2.15265)
			(stroke
				(width 0.0127)
				(type default)
			)
			(layer "F.SilkS")
		)
		(fp_line
			(start -0.635 1.8796)
			(end -1.7526 1.8796)
			(stroke
				(width 0.3302)
				(type default)
			)
			(layer "F.SilkS")
		)
		(fp_line
			(start 1.651 -1.778)
			(end -1.651 -1.778)
			(stroke
				(width 0.1524)
				(type default)
			)
			(layer "F.SilkS")
		)
		(fp_line
			(start 1.651 1.778)
			(end 1.651 -1.778)
			(stroke
				(width 0.1524)
				(type default)
			)
			(layer "F.SilkS")
		)
		(fp_poly
			(pts
				(xy -1.285748 2.159) (xy -1.285748 1.8796) (xy -1.778 1.8796) (xy -1.778 -1.8796) (xy 1.778 -1.8796)
				(xy 1.778 1.8796) (xy -0.694944 1.8796) (xy -0.694944 2.159)
			)
			(stroke
				(width 0)
				(type default)
			)
			(fill no)
			(layer "F.CrtYd")
		)
		(fp_poly
			(pts
				(xy -1.285748 2.159) (xy -1.285748 1.8796) (xy -1.778 1.8796) (xy -1.778 -1.8796) (xy 1.778 -1.8796)
				(xy 1.778 1.8796) (xy -0.694944 1.8796) (xy -0.694944 2.159)
			)
			(stroke
				(width 0)
				(type default)
			)
			(fill no)
			(layer "F.Fab")
		)
		(pad "1" smd rect
			(at -0.98425 0.9525)
			(size 0.762 1.143)
			(layers "F.Cu" "F.Mask" "F.Paste")
			(net "TEMP_ALM#_REVERSE_R")
		)
		(pad "2" smd rect
			(at 0.98425 0.9525)
			(size 0.762 1.143)
			(layers "F.Cu" "F.Mask" "F.Paste")
			(net "GND")
		)
		(pad "3" smd rect
			(at 0 -0.9525)
			(size 0.762 1.143)
			(layers "F.Cu" "F.Mask" "F.Paste")
			(net "ADM1276_LATCH_B")
		)
	)
	(footprint ""
		(layer "F.Cu")
		(at 21.7424 -21.8948)
		(property "Reference" "F1"
			(at 0 0 0)
			(layer "F.SilkS")
			(hide yes)
			(effects
				(font
					(size 1.27 1.27)
				)
			)
		)
		(property "Value" "FUSE-3A15V-GP"
			(at 0.2286 -10.5918 0)
			(unlocked yes)
			(layer "F.Fab")
			(hide yes)
			(effects
				(font
					(size 1.016 1.016)
					(thickness 0.1524)
				)
			)
		)
		(property "Device Type" "FUSE-7452-UH50"
			(at 0.2286 -12.4968 0)
			(unlocked yes)
			(layer "F.Fab")
			(hide yes)
			(effects
				(font
					(size 1.016 1.016)
					(thickness 0.1524)
				)
			)
		)
		(duplicate_pad_numbers_are_jumpers no)
		(fp_line
			(start -4.9276 -2.921)
			(end 4.9276 -2.921)
			(stroke
				(width 0.1524)
				(type default)
			)
			(layer "F.SilkS")
		)
		(fp_line
			(start -4.9276 2.921)
			(end -4.9276 -2.921)
			(stroke
				(width 0.1524)
				(type default)
			)
			(layer "F.SilkS")
		)
		(fp_line
			(start 4.9276 -2.921)
			(end 4.9276 2.921)
			(stroke
				(width 0.1524)
				(type default)
			)
			(layer "F.SilkS")
		)
		(fp_line
			(start 4.9276 2.921)
			(end -4.9276 2.921)
			(stroke
				(width 0.1524)
				(type default)
			)
			(layer "F.SilkS")
		)
		(fp_poly
			(pts
				(xy -5.08 3.0988) (xy 5.08 3.0988) (xy 5.08 -3.0988) (xy -5.08 -3.0988)
			)
			(stroke
				(width 0)
				(type default)
			)
			(fill no)
			(layer "F.CrtYd")
		)
		(fp_poly
			(pts
				(xy -5.08 -3.0988) (xy 5.08 -3.0988) (xy 5.08 3.0988) (xy -5.08 3.0988)
			)
			(stroke
				(width 0)
				(type default)
			)
			(fill no)
			(layer "F.Fab")
		)
		(pad "1" smd rect
			(at -3.4036 0)
			(size 2.2098 5.2832)
			(layers "F.Cu" "F.Mask" "F.Paste")
			(net "P12V_FAN6")
		)
		(pad "2" smd rect
			(at 3.4036 0)
			(size 2.2098 5.2832)
			(layers "F.Cu" "F.Mask" "F.Paste")
			(net "P12V")
		)
	)
	(footprint ""
		(layer "F.Cu")
		(at 24.4602 -142.367)
		(property "Reference" "PC96"
			(at 0 0 0)
			(layer "F.SilkS")
			(hide yes)
			(effects
				(font
					(size 1.27 1.27)
				)
			)
		)
		(property "Value" "SCD1U50V3KX-GP"
			(at 0 -2.8194 0)
			(unlocked yes)
			(layer "F.Fab")
			(hide yes)
			(effects
				(font
					(size 1.016 1.016)
					(thickness 0.1524)
				)
			)
		)
		(property "Device Type" "C603H36"
			(at 0 -4.3434 0)
			(unlocked yes)
			(layer "F.Fab")
			(hide yes)
			(effects
				(font
					(size 1.016 1.016)
					(thickness 0.1524)
				)
			)
		)
		(duplicate_pad_numbers_are_jumpers no)
		(fp_line
			(start 0.508 0)
			(end -0.508 0)
			(stroke
				(width 0.2032)
				(type default)
			)
			(layer "F.SilkS")
		)
		(fp_rect
			(start -0.5842 1.3335)
			(end 0.5842 -1.3335)
			(stroke
				(width 0)
				(type default)
			)
			(fill no)
			(layer "F.CrtYd")
		)
		(fp_rect
			(start -0.5842 1.3335)
			(end 0.5842 -1.3335)
			(stroke
				(width 0)
				(type default)
			)
			(fill no)
			(layer "F.Fab")
		)
		(pad "1" smd custom
			(at 0 -0.762)
			(size 0.2159 0.2159)
			(layers "F.Cu" "F.Mask" "F.Paste")
			(net "P12VU_2490_EN_2")
			(options
				(clearance outline)
				(anchor circle)
			)
			(primitives
				(gr_poly
					(pts
						(arc
							(start -0.3302 -0.4318)
							(mid -0.402042 -0.402042)
							(end -0.4318 -0.3302)
						)
						(arc
							(start -0.4318 0.3302)
							(mid -0.402042 0.402042)
							(end -0.3302 0.4318)
						)
						(arc
							(start 0.3302 0.4318)
							(mid 0.402042 0.402042)
							(end 0.4318 0.3302)
						)
						(arc
							(start 0.4318 -0.3302)
							(mid 0.402042 -0.402042)
							(end 0.3302 -0.4318)
						)
					)
					(width 0)
					(fill yes)
				)
			)
		)
		(pad "2" smd custom
			(at 0 0.762)
			(size 0.2159 0.2159)
			(layers "F.Cu" "F.Mask" "F.Paste")
			(net "GND")
			(options
				(clearance outline)
				(anchor circle)
			)
			(primitives
				(gr_poly
					(pts
						(arc
							(start -0.3302 -0.4318)
							(mid -0.402042 -0.402042)
							(end -0.4318 -0.3302)
						)
						(arc
							(start -0.4318 0.3302)
							(mid -0.402042 0.402042)
							(end -0.3302 0.4318)
						)
						(arc
							(start 0.3302 0.4318)
							(mid 0.402042 0.402042)
							(end 0.4318 0.3302)
						)
						(arc
							(start 0.4318 -0.3302)
							(mid 0.402042 -0.402042)
							(end 0.3302 -0.4318)
						)
					)
					(width 0)
					(fill yes)
				)
			)
		)
	)
	(footprint ""
		(layer "F.Cu")
		(at 22.5044 -136.6012 90)
		(property "Reference" "PC87"
			(at 0 0 90)
			(layer "F.SilkS")
			(hide yes)
			(effects
				(font
					(size 1.27 1.27)
				)
			)
		)
		(property "Value" "SC220P50V2KX-3GP"
			(at 1.1811 -2.7051 90)
			(unlocked yes)
			(layer "F.Fab")
			(hide yes)
			(effects
				(font
					(size 1.016 1.016)
					(thickness 0.1524)
				)
			)
		)
		(property "Device Type" "C402H22"
			(at 1.1811 -4.2291 90)
			(unlocked yes)
			(layer "F.Fab")
			(hide yes)
			(effects
				(font
					(size 1.016 1.016)
					(thickness 0.1524)
				)
			)
		)
		(duplicate_pad_numbers_are_jumpers no)
		(fp_rect
			(start -0.4318 0.9525)
			(end 0.4318 -0.9525)
			(stroke
				(width 0)
				(type default)
			)
			(fill no)
			(layer "F.CrtYd")
		)
		(fp_rect
			(start -0.4318 0.9525)
			(end 0.4318 -0.9525)
			(stroke
				(width 0)
				(type default)
			)
			(fill no)
			(layer "F.Fab")
		)
		(pad "1" smd custom
			(at 0 -0.4445 90)
			(size 0.1524 0.1524)
			(layers "F.Cu" "F.Mask" "F.Paste")
			(net "P12VU_2490_SENSE")
			(options
				(clearance outline)
				(anchor circle)
			)
			(primitives
				(gr_poly
					(pts
						(arc
							(start 0.3048 -0.2032)
							(mid 0.275042 -0.275042)
							(end 0.2032 -0.3048)
						)
						(arc
							(start -0.2032 -0.3048)
							(mid -0.275042 -0.275042)
							(end -0.3048 -0.2032)
						)
						(arc
							(start -0.3048 0.2032)
							(mid -0.275042 0.275042)
							(end -0.2032 0.3048)
						)
						(arc
							(start 0.2032 0.3048)
							(mid 0.275042 0.275042)
							(end 0.3048 0.2032)
						)
					)
					(width 0)
					(fill yes)
				)
			)
		)
		(pad "2" smd custom
			(at 0 0.4445 90)
			(size 0.1524 0.1524)
			(layers "F.Cu" "F.Mask" "F.Paste")
			(net "P12VU_2490_VCC")
			(options
				(clearance outline)
				(anchor circle)
			)
			(primitives
				(gr_poly
					(pts
						(arc
							(start 0.3048 -0.2032)
							(mid 0.275042 -0.275042)
							(end 0.2032 -0.3048)
						)
						(arc
							(start -0.2032 -0.3048)
							(mid -0.275042 -0.275042)
							(end -0.3048 -0.2032)
						)
						(arc
							(start -0.3048 0.2032)
							(mid -0.275042 0.275042)
							(end -0.2032 0.3048)
						)
						(arc
							(start 0.2032 0.3048)
							(mid 0.275042 0.275042)
							(end 0.3048 0.2032)
						)
					)
					(width 0)
					(fill yes)
				)
			)
		)
	)
	(footprint ""
		(layer "F.Cu")
		(at 16.128492 -285.014162 180)
		(property "Reference" "R93"
			(at 0 0 180)
			(layer "F.SilkS")
			(hide yes)
			(effects
				(font
					(size 1.27 1.27)
				)
			)
		)
		(property "Value" "4K7R2F-GP"
			(at 0.064008 -3.993896 180)
			(unlocked yes)
			(layer "F.Fab")
			(hide yes)
			(effects
				(font
					(size 1.016 1.016)
					(thickness 0.1524)
				)
			)
		)
		(property "Device Type" "R402H16"
			(at 0.064008 -5.517896 180)
			(unlocked yes)
			(layer "F.Fab")
			(hide yes)
			(effects
				(font
					(size 1.016 1.016)
					(thickness 0.1524)
				)
			)
		)
		(duplicate_pad_numbers_are_jumpers no)
		(fp_line
			(start 0.508 -0.9398)
			(end -0.508 -0.9398)
			(stroke
				(width 0.1524)
				(type default)
			)
			(layer "F.SilkS")
		)
		(fp_line
			(start -0.508 -0.9398)
			(end -0.508 0.9398)
			(stroke
				(width 0.1524)
				(type default)
			)
			(layer "F.SilkS")
		)
		(fp_rect
			(start -0.508 0.9398)
			(end 0.508 -0.9398)
			(stroke
				(width 0)
				(type default)
			)
			(fill no)
			(layer "F.CrtYd")
		)
		(fp_rect
			(start -0.508 0.9398)
			(end 0.508 -0.9398)
			(stroke
				(width 0)
				(type default)
			)
			(fill no)
			(layer "F.Fab")
		)
		(pad "1" smd custom
			(at 0 -0.4445 180)
			(size 0.1397 0.1397)
			(layers "F.Cu" "F.Mask" "F.Paste")
			(net "P12V")
			(options
				(clearance outline)
				(anchor circle)
			)
			(primitives
				(gr_poly
					(pts
						(arc
							(start -0.1778 -0.2794)
							(mid -0.249642 -0.249642)
							(end -0.2794 -0.1778)
						)
						(arc
							(start -0.2794 0.1778)
							(mid -0.249642 0.249642)
							(end -0.1778 0.2794)
						)
						(arc
							(start 0.1778 0.2794)
							(mid 0.249642 0.249642)
							(end 0.2794 0.1778)
						)
						(arc
							(start 0.2794 -0.1778)
							(mid 0.249642 -0.249642)
							(end 0.1778 -0.2794)
						)
					)
					(width 0)
					(fill yes)
				)
			)
		)
		(pad "2" smd custom
			(at 0 0.4445 180)
			(size 0.1397 0.1397)
			(layers "F.Cu" "F.Mask" "F.Paste")
			(net "FAN_TACH3")
			(options
				(clearance outline)
				(anchor circle)
			)
			(primitives
				(gr_poly
					(pts
						(arc
							(start -0.1778 -0.2794)
							(mid -0.249642 -0.249642)
							(end -0.2794 -0.1778)
						)
						(arc
							(start -0.2794 0.1778)
							(mid -0.249642 0.249642)
							(end -0.1778 0.2794)
						)
						(arc
							(start 0.1778 0.2794)
							(mid 0.249642 0.249642)
							(end 0.2794 0.1778)
						)
						(arc
							(start 0.2794 -0.1778)
							(mid 0.249642 -0.249642)
							(end 0.1778 -0.2794)
						)
					)
					(width 0)
					(fill yes)
				)
			)
		)
	)
	(footprint ""
		(layer "F.Cu")
		(at 17.2466 -400.2024)
		(property "Reference" "PQ13"
			(at 0 0 0)
			(layer "F.SilkS")
			(hide yes)
			(effects
				(font
					(size 1.27 1.27)
				)
			)
		)
		(property "Value" "PH0925CL-GP"
			(at -4.2799 -0.4572 0)
			(unlocked yes)
			(layer "F.Fab")
			(hide yes)
			(effects
				(font
					(size 1.016 1.016)
					(thickness 0.1524)
				)
			)
		)
		(property "Device Type" "LFPAK-5PH48-U"
			(at -4.2799 -1.9812 0)
			(unlocked yes)
			(layer "F.Fab")
			(hide yes)
			(effects
				(font
					(size 1.016 1.016)
					(thickness 0.1524)
				)
			)
		)
		(duplicate_pad_numbers_are_jumpers no)
		(fp_line
			(start -2.7559 -6.5532)
			(end -2.7559 1.0668)
			(stroke
				(width 0.1524)
				(type default)
			)
			(layer "F.SilkS")
		)
		(fp_line
			(start -2.7559 1.0668)
			(end 2.7559 1.0668)
			(stroke
				(width 0.1524)
				(type default)
			)
			(layer "F.SilkS")
		)
		(fp_line
			(start -1.7272 1.1684)
			(end -2.1082 1.1684)
			(stroke
				(width 0.3302)
				(type default)
			)
			(layer "F.SilkS")
		)
		(fp_line
			(start 2.7559 -6.5532)
			(end -2.7559 -6.5532)
			(stroke
				(width 0.1524)
				(type default)
			)
			(layer "F.SilkS")
		)
		(fp_line
			(start 2.7559 1.0668)
			(end 2.7559 -6.5532)
			(stroke
				(width 0.1524)
				(type default)
			)
			(layer "F.SilkS")
		)
		(fp_poly
			(pts
				(xy -2.3368 1.5748) (xy -1.905 1.143) (xy -1.4732 1.5748)
			)
			(stroke
				(width 0)
				(type default)
			)
			(fill yes)
			(layer "F.SilkS")
		)
		(fp_poly
			(pts
				(xy -2.5019 -4.02971) (xy -0.3302 -4.02971) (xy -0.3302 -6.30301) (xy -2.5019 -6.30301)
			)
			(stroke
				(width 0)
				(type default)
			)
			(fill yes)
			(layer "F.Paste")
		)
		(fp_poly
			(pts
				(xy -2.5019 -1.09601) (xy -0.3302 -1.09601) (xy -0.3302 -3.36931) (xy -2.5019 -3.36931)
			)
			(stroke
				(width 0)
				(type default)
			)
			(fill yes)
			(layer "F.Paste")
		)
		(fp_poly
			(pts
				(xy 0.3302 -4.02971) (xy 2.5019 -4.02971) (xy 2.5019 -6.30301) (xy 0.3302 -6.30301)
			)
			(stroke
				(width 0)
				(type default)
			)
			(fill yes)
			(layer "F.Paste")
		)
		(fp_poly
			(pts
				(xy 0.3302 -1.09601) (xy 2.5019 -1.09601) (xy 2.5019 -3.36931) (xy 0.3302 -3.36931)
			)
			(stroke
				(width 0)
				(type default)
			)
			(fill yes)
			(layer "F.Paste")
		)
		(fp_rect
			(start -2.4511 0.3048)
			(end 2.4511 -5.6896)
			(stroke
				(width 0)
				(type default)
			)
			(fill no)
			(layer "F.CrtYd")
		)
		(fp_poly
			(pts
				(xy -3.0099 1.3208) (xy -3.0099 -6.8072) (xy 3.0099 -6.8072) (xy 3.0099 -1.016) (xy 2.4511 -1.016)
				(xy 2.4511 -5.6896) (xy -2.4511 -5.6896) (xy -2.4511 0.3048) (xy 2.4511 0.3048) (xy 2.4511 -1.0033)
				(xy 3.0099 -1.0033) (xy 3.0099 1.3208)
			)
			(stroke
				(width 0)
				(type default)
			)
			(fill no)
			(layer "F.CrtYd")
		)
		(fp_rect
			(start -3.0099 1.3208)
			(end 3.0099 -6.8072)
			(stroke
				(width 0)
				(type default)
			)
			(fill no)
			(layer "F.Fab")
		)
		(pad "1" smd rect
			(at -1.905 0)
			(size 0.762 1.6256)
			(layers "F.Cu" "F.Mask" "F.Paste")
			(net "P12V")
		)
		(pad "2" smd rect
			(at -0.635 0)
			(size 0.762 1.6256)
			(layers "F.Cu" "F.Mask" "F.Paste")
			(net "P12V")
		)
		(pad "3" smd rect
			(at 0.635 0)
			(size 0.762 1.6256)
			(layers "F.Cu" "F.Mask" "F.Paste")
			(net "P12V")
		)
		(pad "4" smd rect
			(at 1.905 0)
			(size 0.762 1.6256)
			(layers "F.Cu" "F.Mask" "F.Paste")
			(net "ADM1276_GATE_DRV0")
		)
		(pad "5" smd rect
			(at 0 -3.69951)
			(size 5.0038 5.207)
			(layers "F.Cu" "F.Mask" "F.Paste")
			(net "P12V_SENSE_TRACE")
		)
	)
	(footprint ""
		(layer "F.Cu")
		(at 7.8232 -81.6102 90)
		(property "Reference" "R29"
			(at 0 0 90)
			(layer "F.SilkS")
			(hide yes)
			(effects
				(font
					(size 1.27 1.27)
				)
			)
		)
		(property "Value" "33R2F-3-GP"
			(at 0.064008 -3.993896 90)
			(unlocked yes)
			(layer "F.Fab")
			(hide yes)
			(effects
				(font
					(size 1.016 1.016)
					(thickness 0.1524)
				)
			)
		)
		(property "Device Type" "R402H16"
			(at 0.064008 -5.517896 90)
			(unlocked yes)
			(layer "F.Fab")
			(hide yes)
			(effects
				(font
					(size 1.016 1.016)
					(thickness 0.1524)
				)
			)
		)
		(duplicate_pad_numbers_are_jumpers no)
		(fp_line
			(start 0.508 -0.9398)
			(end -0.508 -0.9398)
			(stroke
				(width 0.1524)
				(type default)
			)
			(layer "F.SilkS")
		)
		(fp_line
			(start -0.508 -0.9398)
			(end -0.508 0.9398)
			(stroke
				(width 0.1524)
				(type default)
			)
			(layer "F.SilkS")
		)
		(fp_rect
			(start -0.508 0.9398)
			(end 0.508 -0.9398)
			(stroke
				(width 0)
				(type default)
			)
			(fill no)
			(layer "F.CrtYd")
		)
		(fp_rect
			(start -0.508 0.9398)
			(end 0.508 -0.9398)
			(stroke
				(width 0)
				(type default)
			)
			(fill no)
			(layer "F.Fab")
		)
		(pad "1" smd custom
			(at 0 -0.4445 90)
			(size 0.1397 0.1397)
			(layers "F.Cu" "F.Mask" "F.Paste")
			(net "P3V3")
			(options
				(clearance outline)
				(anchor circle)
			)
			(primitives
				(gr_poly
					(pts
						(arc
							(start -0.1778 -0.2794)
							(mid -0.249642 -0.249642)
							(end -0.2794 -0.1778)
						)
						(arc
							(start -0.2794 0.1778)
							(mid -0.249642 0.249642)
							(end -0.1778 0.2794)
						)
						(arc
							(start 0.1778 0.2794)
							(mid 0.249642 0.249642)
							(end 0.2794 0.1778)
						)
						(arc
							(start 0.2794 -0.1778)
							(mid 0.249642 -0.249642)
							(end 0.1778 -0.2794)
						)
					)
					(width 0)
					(fill yes)
				)
			)
		)
		(pad "2" smd custom
			(at 0 0.4445 90)
			(size 0.1397 0.1397)
			(layers "F.Cu" "F.Mask" "F.Paste")
			(net "LED_DR_LED4_BLUE")
			(options
				(clearance outline)
				(anchor circle)
			)
			(primitives
				(gr_poly
					(pts
						(arc
							(start -0.1778 -0.2794)
							(mid -0.249642 -0.249642)
							(end -0.2794 -0.1778)
						)
						(arc
							(start -0.2794 0.1778)
							(mid -0.249642 0.249642)
							(end -0.1778 0.2794)
						)
						(arc
							(start 0.1778 0.2794)
							(mid 0.249642 0.249642)
							(end 0.2794 0.1778)
						)
						(arc
							(start 0.2794 -0.1778)
							(mid 0.249642 -0.249642)
							(end 0.1778 -0.2794)
						)
					)
					(width 0)
					(fill yes)
				)
			)
		)
	)
	(footprint ""
		(layer "F.Cu")
		(at 33.401 -362.7882 -90)
		(property "Reference" "PR39"
			(at 0 0 270)
			(layer "F.SilkS")
			(hide yes)
			(effects
				(font
					(size 1.27 1.27)
				)
			)
		)
		(property "Value" "5K1R2F-2-GP"
			(at 0.064008 -3.993896 270)
			(unlocked yes)
			(layer "F.Fab")
			(hide yes)
			(effects
				(font
					(size 1.016 1.016)
					(thickness 0.1524)
				)
			)
		)
		(property "Device Type" "R402H16"
			(at 0.064008 -5.517896 270)
			(unlocked yes)
			(layer "F.Fab")
			(hide yes)
			(effects
				(font
					(size 1.016 1.016)
					(thickness 0.1524)
				)
			)
		)
		(duplicate_pad_numbers_are_jumpers no)
		(fp_line
			(start -0.508 -0.9398)
			(end -0.508 0.9398)
			(stroke
				(width 0.1524)
				(type default)
			)
			(layer "F.SilkS")
		)
		(fp_line
			(start 0.508 -0.9398)
			(end -0.508 -0.9398)
			(stroke
				(width 0.1524)
				(type default)
			)
			(layer "F.SilkS")
		)
		(fp_rect
			(start -0.508 0.9398)
			(end 0.508 -0.9398)
			(stroke
				(width 0)
				(type default)
			)
			(fill no)
			(layer "F.CrtYd")
		)
		(fp_rect
			(start -0.508 0.9398)
			(end 0.508 -0.9398)
			(stroke
				(width 0)
				(type default)
			)
			(fill no)
			(layer "F.Fab")
		)
		(pad "1" smd custom
			(at 0 -0.4445 270)
			(size 0.1397 0.1397)
			(layers "F.Cu" "F.Mask" "F.Paste")
			(net "TEMP_ALM#_REVERSE_R")
			(options
				(clearance outline)
				(anchor circle)
			)
			(primitives
				(gr_poly
					(pts
						(arc
							(start -0.1778 -0.2794)
							(mid -0.249642 -0.249642)
							(end -0.2794 -0.1778)
						)
						(arc
							(start -0.2794 0.1778)
							(mid -0.249642 0.249642)
							(end -0.1778 0.2794)
						)
						(arc
							(start 0.1778 0.2794)
							(mid 0.249642 0.249642)
							(end 0.2794 0.1778)
						)
						(arc
							(start 0.2794 -0.1778)
							(mid 0.249642 -0.249642)
							(end 0.1778 -0.2794)
						)
					)
					(width 0)
					(fill yes)
				)
			)
		)
		(pad "2" smd custom
			(at 0 0.4445 270)
			(size 0.1397 0.1397)
			(layers "F.Cu" "F.Mask" "F.Paste")
			(net "GND")
			(options
				(clearance outline)
				(anchor circle)
			)
			(primitives
				(gr_poly
					(pts
						(arc
							(start -0.1778 -0.2794)
							(mid -0.249642 -0.249642)
							(end -0.2794 -0.1778)
						)
						(arc
							(start -0.2794 0.1778)
							(mid -0.249642 0.249642)
							(end -0.1778 0.2794)
						)
						(arc
							(start 0.1778 0.2794)
							(mid 0.249642 0.249642)
							(end 0.2794 0.1778)
						)
						(arc
							(start 0.2794 -0.1778)
							(mid 0.249642 -0.249642)
							(end 0.1778 -0.2794)
						)
					)
					(width 0)
					(fill yes)
				)
			)
		)
	)
	(footprint ""
		(layer "F.Cu")
		(at 38.692074 -363.062774 180)
		(property "Reference" "PR40"
			(at 0 0 180)
			(layer "F.SilkS")
			(hide yes)
			(effects
				(font
					(size 1.27 1.27)
				)
			)
		)
		(property "Value" "54K9R2F-L-GP"
			(at 0.064008 -3.993896 180)
			(unlocked yes)
			(layer "F.Fab")
			(hide yes)
			(effects
				(font
					(size 1.016 1.016)
					(thickness 0.1524)
				)
			)
		)
		(property "Device Type" "R402H16"
			(at 0.064008 -5.517896 180)
			(unlocked yes)
			(layer "F.Fab")
			(hide yes)
			(effects
				(font
					(size 1.016 1.016)
					(thickness 0.1524)
				)
			)
		)
		(duplicate_pad_numbers_are_jumpers no)
		(fp_line
			(start 0.508 -0.9398)
			(end -0.508 -0.9398)
			(stroke
				(width 0.1524)
				(type default)
			)
			(layer "F.SilkS")
		)
		(fp_line
			(start -0.508 -0.9398)
			(end -0.508 0.9398)
			(stroke
				(width 0.1524)
				(type default)
			)
			(layer "F.SilkS")
		)
		(fp_rect
			(start -0.508 0.9398)
			(end 0.508 -0.9398)
			(stroke
				(width 0)
				(type default)
			)
			(fill no)
			(layer "F.CrtYd")
		)
		(fp_rect
			(start -0.508 0.9398)
			(end 0.508 -0.9398)
			(stroke
				(width 0)
				(type default)
			)
			(fill no)
			(layer "F.Fab")
		)
		(pad "1" smd custom
			(at 0 -0.4445 180)
			(size 0.1397 0.1397)
			(layers "F.Cu" "F.Mask" "F.Paste")
			(net "P12V_AUX")
			(options
				(clearance outline)
				(anchor circle)
			)
			(primitives
				(gr_poly
					(pts
						(arc
							(start -0.1778 -0.2794)
							(mid -0.249642 -0.249642)
							(end -0.2794 -0.1778)
						)
						(arc
							(start -0.2794 0.1778)
							(mid -0.249642 0.249642)
							(end -0.1778 0.2794)
						)
						(arc
							(start 0.1778 0.2794)
							(mid 0.249642 0.249642)
							(end 0.2794 0.1778)
						)
						(arc
							(start 0.2794 -0.1778)
							(mid 0.249642 -0.249642)
							(end 0.1778 -0.2794)
						)
					)
					(width 0)
					(fill yes)
				)
			)
		)
		(pad "2" smd custom
			(at 0 0.4445 180)
			(size 0.1397 0.1397)
			(layers "F.Cu" "F.Mask" "F.Paste")
			(net "TEMP_ALM#_REVERSE")
			(options
				(clearance outline)
				(anchor circle)
			)
			(primitives
				(gr_poly
					(pts
						(arc
							(start -0.1778 -0.2794)
							(mid -0.249642 -0.249642)
							(end -0.2794 -0.1778)
						)
						(arc
							(start -0.2794 0.1778)
							(mid -0.249642 0.249642)
							(end -0.1778 0.2794)
						)
						(arc
							(start 0.1778 0.2794)
							(mid 0.249642 0.249642)
							(end 0.2794 0.1778)
						)
						(arc
							(start 0.2794 -0.1778)
							(mid 0.249642 -0.249642)
							(end 0.1778 -0.2794)
						)
					)
					(width 0)
					(fill yes)
				)
			)
		)
	)
	(footprint ""
		(layer "F.Cu")
		(at 10.0838 -278.384 -90)
		(property "Reference" "R117"
			(at 0 0 270)
			(layer "F.SilkS")
			(hide yes)
			(effects
				(font
					(size 1.27 1.27)
				)
			)
		)
		(property "Value" "2KR2F-3-GP"
			(at 0.064008 -3.993896 270)
			(unlocked yes)
			(layer "F.Fab")
			(hide yes)
			(effects
				(font
					(size 1.016 1.016)
					(thickness 0.1524)
				)
			)
		)
		(property "Device Type" "R402H16"
			(at 0.064008 -5.517896 270)
			(unlocked yes)
			(layer "F.Fab")
			(hide yes)
			(effects
				(font
					(size 1.016 1.016)
					(thickness 0.1524)
				)
			)
		)
		(duplicate_pad_numbers_are_jumpers no)
		(fp_line
			(start -0.508 -0.9398)
			(end -0.508 0.9398)
			(stroke
				(width 0.1524)
				(type default)
			)
			(layer "F.SilkS")
		)
		(fp_line
			(start 0.508 -0.9398)
			(end -0.508 -0.9398)
			(stroke
				(width 0.1524)
				(type default)
			)
			(layer "F.SilkS")
		)
		(fp_rect
			(start -0.508 0.9398)
			(end 0.508 -0.9398)
			(stroke
				(width 0)
				(type default)
			)
			(fill no)
			(layer "F.CrtYd")
		)
		(fp_rect
			(start -0.508 0.9398)
			(end 0.508 -0.9398)
			(stroke
				(width 0)
				(type default)
			)
			(fill no)
			(layer "F.Fab")
		)
		(pad "1" smd custom
			(at 0 -0.4445 270)
			(size 0.1397 0.1397)
			(layers "F.Cu" "F.Mask" "F.Paste")
			(net "LED_DR_LED2")
			(options
				(clearance outline)
				(anchor circle)
			)
			(primitives
				(gr_poly
					(pts
						(arc
							(start -0.1778 -0.2794)
							(mid -0.249642 -0.249642)
							(end -0.2794 -0.1778)
						)
						(arc
							(start -0.2794 0.1778)
							(mid -0.249642 0.249642)
							(end -0.1778 0.2794)
						)
						(arc
							(start 0.1778 0.2794)
							(mid 0.249642 0.249642)
							(end 0.2794 0.1778)
						)
						(arc
							(start 0.2794 -0.1778)
							(mid 0.249642 -0.249642)
							(end 0.1778 -0.2794)
						)
					)
					(width 0)
					(fill yes)
				)
			)
		)
		(pad "2" smd custom
			(at 0 0.4445 270)
			(size 0.1397 0.1397)
			(layers "F.Cu" "F.Mask" "F.Paste")
			(net "LED_DR_LED2_B")
			(options
				(clearance outline)
				(anchor circle)
			)
			(primitives
				(gr_poly
					(pts
						(arc
							(start -0.1778 -0.2794)
							(mid -0.249642 -0.249642)
							(end -0.2794 -0.1778)
						)
						(arc
							(start -0.2794 0.1778)
							(mid -0.249642 0.249642)
							(end -0.1778 0.2794)
						)
						(arc
							(start 0.1778 0.2794)
							(mid 0.249642 0.249642)
							(end 0.2794 0.1778)
						)
						(arc
							(start 0.2794 -0.1778)
							(mid 0.249642 -0.249642)
							(end 0.1778 -0.2794)
						)
					)
					(width 0)
					(fill yes)
				)
			)
		)
	)
	(footprint ""
		(layer "F.Cu")
		(at 39.116 -252.603 -90)
		(property "Reference" "TP19"
			(at 0 0 270)
			(layer "F.SilkS")
			(hide yes)
			(effects
				(font
					(size 1.27 1.27)
				)
			)
		)
		(property "Value" "TPAD32-GP"
			(at 0 -3.166364 270)
			(unlocked yes)
			(layer "F.Fab")
			(hide yes)
			(effects
				(font
					(size 1.016 1.016)
					(thickness 0.1524)
				)
			)
		)
		(property "Device Type" "TPAD32"
			(at 0 -4.690618 270)
			(unlocked yes)
			(layer "F.Fab")
			(hide yes)
			(effects
				(font
					(size 1.016 1.016)
					(thickness 0.1524)
				)
			)
		)
		(duplicate_pad_numbers_are_jumpers no)
		(fp_poly
			(pts
				(arc
					(start 0.7112 0)
					(mid -0.7112 0)
					(end 0.7112 0)
				)
			)
			(stroke
				(width 0)
				(type default)
			)
			(fill no)
			(layer "F.CrtYd")
		)
		(fp_poly
			(pts
				(arc
					(start 0.7112 0)
					(mid -0.7112 0)
					(end 0.7112 0)
				)
			)
			(stroke
				(width 0)
				(type default)
			)
			(fill no)
			(layer "F.Fab")
		)
		(pad "1" smd circle
			(at 0 0 270)
			(size 0.8128 0.8128)
			(layers "F.Cu" "F.Mask" "F.Paste")
			(net "LED_DR_LED6_RESERVE")
		)
	)
	(footprint ""
		(layer "F.Cu")
		(at 5.5626 -429.9712 90)
		(property "Reference" "R31"
			(at 0 0 90)
			(layer "F.SilkS")
			(hide yes)
			(effects
				(font
					(size 1.27 1.27)
				)
			)
		)
		(property "Value" "33R2F-3-GP"
			(at 0.064008 -3.993896 90)
			(unlocked yes)
			(layer "F.Fab")
			(hide yes)
			(effects
				(font
					(size 1.016 1.016)
					(thickness 0.1524)
				)
			)
		)
		(property "Device Type" "R402H16"
			(at 0.064008 -5.517896 90)
			(unlocked yes)
			(layer "F.Fab")
			(hide yes)
			(effects
				(font
					(size 1.016 1.016)
					(thickness 0.1524)
				)
			)
		)
		(duplicate_pad_numbers_are_jumpers no)
		(fp_line
			(start 0.508 -0.9398)
			(end -0.508 -0.9398)
			(stroke
				(width 0.1524)
				(type default)
			)
			(layer "F.SilkS")
		)
		(fp_line
			(start -0.508 -0.9398)
			(end -0.508 0.9398)
			(stroke
				(width 0.1524)
				(type default)
			)
			(layer "F.SilkS")
		)
		(fp_rect
			(start -0.508 0.9398)
			(end 0.508 -0.9398)
			(stroke
				(width 0)
				(type default)
			)
			(fill no)
			(layer "F.CrtYd")
		)
		(fp_rect
			(start -0.508 0.9398)
			(end 0.508 -0.9398)
			(stroke
				(width 0)
				(type default)
			)
			(fill no)
			(layer "F.Fab")
		)
		(pad "1" smd custom
			(at 0 -0.4445 90)
			(size 0.1397 0.1397)
			(layers "F.Cu" "F.Mask" "F.Paste")
			(net "P3V3")
			(options
				(clearance outline)
				(anchor circle)
			)
			(primitives
				(gr_poly
					(pts
						(arc
							(start -0.1778 -0.2794)
							(mid -0.249642 -0.249642)
							(end -0.2794 -0.1778)
						)
						(arc
							(start -0.2794 0.1778)
							(mid -0.249642 0.249642)
							(end -0.1778 0.2794)
						)
						(arc
							(start 0.1778 0.2794)
							(mid 0.249642 0.249642)
							(end 0.2794 0.1778)
						)
						(arc
							(start 0.2794 -0.1778)
							(mid 0.249642 -0.249642)
							(end 0.1778 -0.2794)
						)
					)
					(width 0)
					(fill yes)
				)
			)
		)
		(pad "2" smd custom
			(at 0 0.4445 90)
			(size 0.1397 0.1397)
			(layers "F.Cu" "F.Mask" "F.Paste")
			(net "LED_DR_LED0_BLUE")
			(options
				(clearance outline)
				(anchor circle)
			)
			(primitives
				(gr_poly
					(pts
						(arc
							(start -0.1778 -0.2794)
							(mid -0.249642 -0.249642)
							(end -0.2794 -0.1778)
						)
						(arc
							(start -0.2794 0.1778)
							(mid -0.249642 0.249642)
							(end -0.1778 0.2794)
						)
						(arc
							(start 0.1778 0.2794)
							(mid 0.249642 0.249642)
							(end 0.2794 0.1778)
						)
						(arc
							(start 0.2794 -0.1778)
							(mid 0.249642 -0.249642)
							(end 0.1778 -0.2794)
						)
					)
					(width 0)
					(fill yes)
				)
			)
		)
	)
	(footprint ""
		(layer "F.Cu")
		(at 17.8816 -253.9492 90)
		(property "Reference" "R90"
			(at 0 0 90)
			(layer "F.SilkS")
			(hide yes)
			(effects
				(font
					(size 1.27 1.27)
				)
			)
		)
		(property "Value" "10KR2F-2-GP"
			(at 0.064008 -3.993896 90)
			(unlocked yes)
			(layer "F.Fab")
			(hide yes)
			(effects
				(font
					(size 1.016 1.016)
					(thickness 0.1524)
				)
			)
		)
		(property "Device Type" "R402H16"
			(at 0.064008 -5.517896 90)
			(unlocked yes)
			(layer "F.Fab")
			(hide yes)
			(effects
				(font
					(size 1.016 1.016)
					(thickness 0.1524)
				)
			)
		)
		(duplicate_pad_numbers_are_jumpers no)
		(fp_line
			(start 0.508 -0.9398)
			(end -0.508 -0.9398)
			(stroke
				(width 0.1524)
				(type default)
			)
			(layer "F.SilkS")
		)
		(fp_line
			(start -0.508 -0.9398)
			(end -0.508 0.9398)
			(stroke
				(width 0.1524)
				(type default)
			)
			(layer "F.SilkS")
		)
		(fp_rect
			(start -0.508 0.9398)
			(end 0.508 -0.9398)
			(stroke
				(width 0)
				(type default)
			)
			(fill no)
			(layer "F.CrtYd")
		)
		(fp_rect
			(start -0.508 0.9398)
			(end 0.508 -0.9398)
			(stroke
				(width 0)
				(type default)
			)
			(fill no)
			(layer "F.Fab")
		)
		(pad "1" smd custom
			(at 0 -0.4445 90)
			(size 0.1397 0.1397)
			(layers "F.Cu" "F.Mask" "F.Paste")
			(net "FANIN_5")
			(options
				(clearance outline)
				(anchor circle)
			)
			(primitives
				(gr_poly
					(pts
						(arc
							(start -0.1778 -0.2794)
							(mid -0.249642 -0.249642)
							(end -0.2794 -0.1778)
						)
						(arc
							(start -0.2794 0.1778)
							(mid -0.249642 0.249642)
							(end -0.1778 0.2794)
						)
						(arc
							(start 0.1778 0.2794)
							(mid 0.249642 0.249642)
							(end 0.2794 0.1778)
						)
						(arc
							(start 0.2794 -0.1778)
							(mid 0.249642 -0.249642)
							(end 0.1778 -0.2794)
						)
					)
					(width 0)
					(fill yes)
				)
			)
		)
		(pad "2" smd custom
			(at 0 0.4445 90)
			(size 0.1397 0.1397)
			(layers "F.Cu" "F.Mask" "F.Paste")
			(net "GND")
			(options
				(clearance outline)
				(anchor circle)
			)
			(primitives
				(gr_poly
					(pts
						(arc
							(start -0.1778 -0.2794)
							(mid -0.249642 -0.249642)
							(end -0.2794 -0.1778)
						)
						(arc
							(start -0.2794 0.1778)
							(mid -0.249642 0.249642)
							(end -0.1778 0.2794)
						)
						(arc
							(start 0.1778 0.2794)
							(mid 0.249642 0.249642)
							(end 0.2794 0.1778)
						)
						(arc
							(start 0.2794 -0.1778)
							(mid 0.249642 -0.249642)
							(end 0.1778 -0.2794)
						)
					)
					(width 0)
					(fill yes)
				)
			)
		)
	)
	(footprint ""
		(layer "F.Cu")
		(at 43.2054 -155.2956 180)
		(property "Reference" "C3"
			(at 0 0 180)
			(layer "F.SilkS")
			(hide yes)
			(effects
				(font
					(size 1.27 1.27)
				)
			)
		)
		(property "Value" "SC10U25V5KX-GP"
			(at -0.0762 -6.1214 180)
			(unlocked yes)
			(layer "F.Fab")
			(hide yes)
			(effects
				(font
					(size 1.016 1.016)
					(thickness 0.1524)
				)
			)
		)
		(property "Device Type" "C805H56"
			(at -0.0762 -8.1534 180)
			(unlocked yes)
			(layer "F.Fab")
			(hide yes)
			(effects
				(font
					(size 1.016 1.016)
					(thickness 0.1524)
				)
			)
		)
		(duplicate_pad_numbers_are_jumpers no)
		(fp_line
			(start 0.635 0)
			(end -0.635 0)
			(stroke
				(width 0.508)
				(type default)
			)
			(layer "F.SilkS")
		)
		(fp_rect
			(start -0.9652 1.778)
			(end 0.9652 -1.778)
			(stroke
				(width 0)
				(type default)
			)
			(fill no)
			(layer "F.CrtYd")
		)
		(fp_poly
			(pts
				(xy -0.9652 -1.778) (xy 0.9652 -1.778) (xy 0.9652 1.778) (xy -0.9652 1.778)
			)
			(stroke
				(width 0)
				(type default)
			)
			(fill no)
			(layer "F.Fab")
		)
		(pad "1" smd rect
			(at 0 -0.9652 180)
			(size 1.397 1.143)
			(layers "F.Cu" "F.Mask" "F.Paste")
			(net "NCT7904_3VSB")
		)
		(pad "2" smd rect
			(at 0 0.9652 180)
			(size 1.397 1.143)
			(layers "F.Cu" "F.Mask" "F.Paste")
			(net "GND")
		)
	)
	(footprint ""
		(layer "F.Cu")
		(at 22.733 -372.237 180)
		(property "Reference" "PC9"
			(at 0 0 180)
			(layer "F.SilkS")
			(hide yes)
			(effects
				(font
					(size 1.27 1.27)
				)
			)
		)
		(property "Value" "SC1U25V5KX-1GP"
			(at -0.0762 -6.1214 180)
			(unlocked yes)
			(layer "F.Fab")
			(hide yes)
			(effects
				(font
					(size 1.016 1.016)
					(thickness 0.1524)
				)
			)
		)
		(property "Device Type" "C805H58"
			(at -0.0762 -8.1534 180)
			(unlocked yes)
			(layer "F.Fab")
			(hide yes)
			(effects
				(font
					(size 1.016 1.016)
					(thickness 0.1524)
				)
			)
		)
		(duplicate_pad_numbers_are_jumpers no)
		(fp_line
			(start 0.635 0)
			(end -0.635 0)
			(stroke
				(width 0.508)
				(type default)
			)
			(layer "F.SilkS")
		)
		(fp_rect
			(start -0.9652 1.778)
			(end 0.9652 -1.778)
			(stroke
				(width 0)
				(type default)
			)
			(fill no)
			(layer "F.CrtYd")
		)
		(fp_poly
			(pts
				(xy -0.9652 -1.778) (xy 0.9652 -1.778) (xy 0.9652 1.778) (xy -0.9652 1.778)
			)
			(stroke
				(width 0)
				(type default)
			)
			(fill no)
			(layer "F.Fab")
		)
		(pad "1" smd rect
			(at 0 -0.9652 180)
			(size 1.397 1.143)
			(layers "F.Cu" "F.Mask" "F.Paste")
			(net "ADM1276_OV")
		)
		(pad "2" smd rect
			(at 0 0.9652 180)
			(size 1.397 1.143)
			(layers "F.Cu" "F.Mask" "F.Paste")
			(net "GND")
		)
	)
	(footprint ""
		(layer "F.Cu")
		(at 21.463 -91.9226 -90)
		(property "Reference" "D15"
			(at 0 0 270)
			(layer "F.SilkS")
			(hide yes)
			(effects
				(font
					(size 1.27 1.27)
				)
			)
		)
		(property "Value" "MBRS340T3G-GP"
			(at 0 -10.6172 270)
			(unlocked yes)
			(layer "F.Fab")
			(hide yes)
			(effects
				(font
					(size 1.016 1.016)
					(thickness 0.1524)
				)
			)
		)
		(property "Device Type" "D8059AKH101"
			(at 0 -12.1412 270)
			(unlocked yes)
			(layer "F.Fab")
			(hide yes)
			(effects
				(font
					(size 1.016 1.016)
					(thickness 0.1524)
				)
			)
		)
		(duplicate_pad_numbers_are_jumpers no)
		(fp_line
			(start 3.175 5.2832)
			(end -3.175 5.2832)
			(stroke
				(width 0.508)
				(type default)
			)
			(layer "F.SilkS")
		)
		(fp_line
			(start -3.175 5.1054)
			(end -3.175 -5.1054)
			(stroke
				(width 0.1524)
				(type default)
			)
			(layer "F.SilkS")
		)
		(fp_line
			(start 3.175 5.1054)
			(end -3.175 5.1054)
			(stroke
				(width 0.1524)
				(type default)
			)
			(layer "F.SilkS")
		)
		(fp_line
			(start -3.175 -5.1054)
			(end 3.175 -5.1054)
			(stroke
				(width 0.1524)
				(type default)
			)
			(layer "F.SilkS")
		)
		(fp_line
			(start 3.175 -5.1054)
			(end 3.175 5.1054)
			(stroke
				(width 0.1524)
				(type default)
			)
			(layer "F.SilkS")
		)
		(fp_rect
			(start -3.429 5.1816)
			(end 3.429 -5.1816)
			(stroke
				(width 0)
				(type default)
			)
			(fill no)
			(layer "F.CrtYd")
		)
		(fp_poly
			(pts
				(xy -3.429 -5.1816) (xy 3.429 -5.1816) (xy 3.429 5.1816) (xy -3.429 5.1816)
			)
			(stroke
				(width 0)
				(type default)
			)
			(fill no)
			(layer "F.Fab")
		)
		(pad "A" smd rect
			(at 0 -3.77571 270)
			(size 3.2512 2.159)
			(layers "F.Cu" "F.Mask" "F.Paste")
			(net "GND")
		)
		(pad "K" smd rect
			(at 0 3.77571 270)
			(size 3.2512 2.159)
			(layers "F.Cu" "F.Mask" "F.Paste")
			(net "P12VU")
		)
	)
	(footprint ""
		(layer "F.Cu")
		(at 35.8394 -357.097584 180)
		(property "Reference" "D19"
			(at 0 0 180)
			(layer "F.SilkS")
			(hide yes)
			(effects
				(font
					(size 1.27 1.27)
				)
			)
		)
		(property "Value" "CH751H-40PT-1GP"
			(at -0.1016 -4.4958 180)
			(unlocked yes)
			(layer "F.Fab")
			(hide yes)
			(effects
				(font
					(size 1.016 1.016)
					(thickness 0.1524)
				)
			)
		)
		(property "Device Type" "SOD80CAKH36"
			(at -0.1016 -6.0198 180)
			(unlocked yes)
			(layer "F.Fab")
			(hide yes)
			(effects
				(font
					(size 1.016 1.016)
					(thickness 0.1524)
				)
			)
		)
		(duplicate_pad_numbers_are_jumpers no)
		(fp_line
			(start 0.8128 1.8796)
			(end 0.8128 -1.8796)
			(stroke
				(width 0.1524)
				(type default)
			)
			(layer "F.SilkS")
		)
		(fp_line
			(start 0.8128 -1.8796)
			(end -0.8128 -1.8796)
			(stroke
				(width 0.1524)
				(type default)
			)
			(layer "F.SilkS")
		)
		(fp_line
			(start -0.6858 2.0066)
			(end 0.6858 2.0066)
			(stroke
				(width 0.4064)
				(type default)
			)
			(layer "F.SilkS")
		)
		(fp_line
			(start -0.8128 1.8796)
			(end 0.8128 1.8796)
			(stroke
				(width 0.1524)
				(type default)
			)
			(layer "F.SilkS")
		)
		(fp_line
			(start -0.8128 -1.8796)
			(end -0.8128 1.8796)
			(stroke
				(width 0.1524)
				(type default)
			)
			(layer "F.SilkS")
		)
		(fp_rect
			(start -0.889 2.2098)
			(end 0.889 -1.9558)
			(stroke
				(width 0)
				(type default)
			)
			(fill no)
			(layer "F.CrtYd")
		)
		(fp_rect
			(start -0.889 2.2098)
			(end 0.889 -1.9558)
			(stroke
				(width 0)
				(type default)
			)
			(fill no)
			(layer "F.Fab")
		)
		(pad "A" smd rect
			(at 0 -1.0668 180)
			(size 0.762 1.1684)
			(layers "F.Cu" "F.Mask" "F.Paste")
			(net "OTP_RETRY_C")
		)
		(pad "K" smd rect
			(at 0 1.0668 180)
			(size 0.762 1.1684)
			(layers "F.Cu" "F.Mask" "F.Paste")
			(net "OTP_RETRY_DIODE")
		)
	)
	(footprint ""
		(layer "F.Cu")
		(at 41.3766 -140.5382 -90)
		(property "Reference" "PC98"
			(at 0 0 270)
			(layer "F.SilkS")
			(hide yes)
			(effects
				(font
					(size 1.27 1.27)
				)
			)
		)
		(property "Value" "SCD1U50V3KX-GP"
			(at 0 -2.8194 270)
			(unlocked yes)
			(layer "F.Fab")
			(hide yes)
			(effects
				(font
					(size 1.016 1.016)
					(thickness 0.1524)
				)
			)
		)
		(property "Device Type" "C603H36"
			(at 0 -4.3434 270)
			(unlocked yes)
			(layer "F.Fab")
			(hide yes)
			(effects
				(font
					(size 1.016 1.016)
					(thickness 0.1524)
				)
			)
		)
		(duplicate_pad_numbers_are_jumpers no)
		(fp_line
			(start 0.508 0)
			(end -0.508 0)
			(stroke
				(width 0.2032)
				(type default)
			)
			(layer "F.SilkS")
		)
		(fp_rect
			(start -0.5842 1.3335)
			(end 0.5842 -1.3335)
			(stroke
				(width 0)
				(type default)
			)
			(fill no)
			(layer "F.CrtYd")
		)
		(fp_rect
			(start -0.5842 1.3335)
			(end 0.5842 -1.3335)
			(stroke
				(width 0)
				(type default)
			)
			(fill no)
			(layer "F.Fab")
		)
		(pad "1" smd custom
			(at 0 -0.762 270)
			(size 0.2159 0.2159)
			(layers "F.Cu" "F.Mask" "F.Paste")
			(net "P12VL_2490_EN_2")
			(options
				(clearance outline)
				(anchor circle)
			)
			(primitives
				(gr_poly
					(pts
						(arc
							(start -0.3302 -0.4318)
							(mid -0.402042 -0.402042)
							(end -0.4318 -0.3302)
						)
						(arc
							(start -0.4318 0.3302)
							(mid -0.402042 0.402042)
							(end -0.3302 0.4318)
						)
						(arc
							(start 0.3302 0.4318)
							(mid 0.402042 0.402042)
							(end 0.4318 0.3302)
						)
						(arc
							(start 0.4318 -0.3302)
							(mid 0.402042 -0.402042)
							(end 0.3302 -0.4318)
						)
					)
					(width 0)
					(fill yes)
				)
			)
		)
		(pad "2" smd custom
			(at 0 0.762 270)
			(size 0.2159 0.2159)
			(layers "F.Cu" "F.Mask" "F.Paste")
			(net "GND")
			(options
				(clearance outline)
				(anchor circle)
			)
			(primitives
				(gr_poly
					(pts
						(arc
							(start -0.3302 -0.4318)
							(mid -0.402042 -0.402042)
							(end -0.4318 -0.3302)
						)
						(arc
							(start -0.4318 0.3302)
							(mid -0.402042 0.402042)
							(end -0.3302 0.4318)
						)
						(arc
							(start 0.3302 0.4318)
							(mid 0.402042 0.402042)
							(end 0.4318 0.3302)
						)
						(arc
							(start 0.4318 -0.3302)
							(mid 0.402042 -0.402042)
							(end 0.3302 -0.4318)
						)
					)
					(width 0)
					(fill yes)
				)
			)
		)
	)
	(footprint ""
		(layer "F.Cu")
		(at 29.5402 -169.9006 180)
		(property "Reference" "R161"
			(at 0 0 180)
			(layer "F.SilkS")
			(hide yes)
			(effects
				(font
					(size 1.27 1.27)
				)
			)
		)
		(property "Value" "0R2J-2-GP"
			(at 0.064008 -3.993896 180)
			(unlocked yes)
			(layer "F.Fab")
			(hide yes)
			(effects
				(font
					(size 1.016 1.016)
					(thickness 0.1524)
				)
			)
		)
		(property "Device Type" "R402H16"
			(at 0.064008 -5.517896 180)
			(unlocked yes)
			(layer "F.Fab")
			(hide yes)
			(effects
				(font
					(size 1.016 1.016)
					(thickness 0.1524)
				)
			)
		)
		(duplicate_pad_numbers_are_jumpers no)
		(fp_line
			(start 0.508 -0.9398)
			(end -0.508 -0.9398)
			(stroke
				(width 0.1524)
				(type default)
			)
			(layer "F.SilkS")
		)
		(fp_line
			(start -0.508 -0.9398)
			(end -0.508 0.9398)
			(stroke
				(width 0.1524)
				(type default)
			)
			(layer "F.SilkS")
		)
		(fp_rect
			(start -0.508 0.9398)
			(end 0.508 -0.9398)
			(stroke
				(width 0)
				(type default)
			)
			(fill no)
			(layer "F.CrtYd")
		)
		(fp_rect
			(start -0.508 0.9398)
			(end 0.508 -0.9398)
			(stroke
				(width 0)
				(type default)
			)
			(fill no)
			(layer "F.Fab")
		)
		(pad "1" smd custom
			(at 0 -0.4445 180)
			(size 0.1397 0.1397)
			(layers "F.Cu" "F.Mask" "F.Paste")
			(net "NCT7904D_PWM1")
			(options
				(clearance outline)
				(anchor circle)
			)
			(primitives
				(gr_poly
					(pts
						(arc
							(start -0.1778 -0.2794)
							(mid -0.249642 -0.249642)
							(end -0.2794 -0.1778)
						)
						(arc
							(start -0.2794 0.1778)
							(mid -0.249642 0.249642)
							(end -0.1778 0.2794)
						)
						(arc
							(start 0.1778 0.2794)
							(mid 0.249642 0.249642)
							(end 0.2794 0.1778)
						)
						(arc
							(start 0.2794 -0.1778)
							(mid 0.249642 -0.249642)
							(end 0.1778 -0.2794)
						)
					)
					(width 0)
					(fill yes)
				)
			)
		)
		(pad "2" smd custom
			(at 0 0.4445 180)
			(size 0.1397 0.1397)
			(layers "F.Cu" "F.Mask" "F.Paste")
			(net "PWM_BUFFER_IN_FAN1_FAN2")
			(options
				(clearance outline)
				(anchor circle)
			)
			(primitives
				(gr_poly
					(pts
						(arc
							(start -0.1778 -0.2794)
							(mid -0.249642 -0.249642)
							(end -0.2794 -0.1778)
						)
						(arc
							(start -0.2794 0.1778)
							(mid -0.249642 0.249642)
							(end -0.1778 0.2794)
						)
						(arc
							(start 0.1778 0.2794)
							(mid 0.249642 0.249642)
							(end 0.2794 0.1778)
						)
						(arc
							(start 0.2794 -0.1778)
							(mid 0.249642 -0.249642)
							(end 0.1778 -0.2794)
						)
					)
					(width 0)
					(fill yes)
				)
			)
		)
	)
	(footprint ""
		(layer "F.Cu")
		(at 8.3566 -422.275)
		(property "Reference" "R119"
			(at 0 0 0)
			(layer "F.SilkS")
			(hide yes)
			(effects
				(font
					(size 1.27 1.27)
				)
			)
		)
		(property "Value" "2KR2F-3-GP"
			(at 0.064008 -3.993896 0)
			(unlocked yes)
			(layer "F.Fab")
			(hide yes)
			(effects
				(font
					(size 1.016 1.016)
					(thickness 0.1524)
				)
			)
		)
		(property "Device Type" "R402H16"
			(at 0.064008 -5.517896 0)
			(unlocked yes)
			(layer "F.Fab")
			(hide yes)
			(effects
				(font
					(size 1.016 1.016)
					(thickness 0.1524)
				)
			)
		)
		(duplicate_pad_numbers_are_jumpers no)
		(fp_line
			(start -0.508 -0.9398)
			(end -0.508 0.9398)
			(stroke
				(width 0.1524)
				(type default)
			)
			(layer "F.SilkS")
		)
		(fp_line
			(start 0.508 -0.9398)
			(end -0.508 -0.9398)
			(stroke
				(width 0.1524)
				(type default)
			)
			(layer "F.SilkS")
		)
		(fp_rect
			(start -0.508 0.9398)
			(end 0.508 -0.9398)
			(stroke
				(width 0)
				(type default)
			)
			(fill no)
			(layer "F.CrtYd")
		)
		(fp_rect
			(start -0.508 0.9398)
			(end 0.508 -0.9398)
			(stroke
				(width 0)
				(type default)
			)
			(fill no)
			(layer "F.Fab")
		)
		(pad "1" smd custom
			(at 0 -0.4445)
			(size 0.1397 0.1397)
			(layers "F.Cu" "F.Mask" "F.Paste")
			(net "LED_DR_LED1")
			(options
				(clearance outline)
				(anchor circle)
			)
			(primitives
				(gr_poly
					(pts
						(arc
							(start -0.1778 -0.2794)
							(mid -0.249642 -0.249642)
							(end -0.2794 -0.1778)
						)
						(arc
							(start -0.2794 0.1778)
							(mid -0.249642 0.249642)
							(end -0.1778 0.2794)
						)
						(arc
							(start 0.1778 0.2794)
							(mid 0.249642 0.249642)
							(end 0.2794 0.1778)
						)
						(arc
							(start 0.2794 -0.1778)
							(mid 0.249642 -0.249642)
							(end 0.1778 -0.2794)
						)
					)
					(width 0)
					(fill yes)
				)
			)
		)
		(pad "2" smd custom
			(at 0 0.4445)
			(size 0.1397 0.1397)
			(layers "F.Cu" "F.Mask" "F.Paste")
			(net "LED_DR_LED1_B")
			(options
				(clearance outline)
				(anchor circle)
			)
			(primitives
				(gr_poly
					(pts
						(arc
							(start -0.1778 -0.2794)
							(mid -0.249642 -0.249642)
							(end -0.2794 -0.1778)
						)
						(arc
							(start -0.2794 0.1778)
							(mid -0.249642 0.249642)
							(end -0.1778 0.2794)
						)
						(arc
							(start 0.1778 0.2794)
							(mid 0.249642 0.249642)
							(end 0.2794 0.1778)
						)
						(arc
							(start 0.2794 -0.1778)
							(mid 0.249642 -0.249642)
							(end 0.1778 -0.2794)
						)
					)
					(width 0)
					(fill yes)
				)
			)
		)
	)
	(footprint ""
		(layer "F.Cu")
		(at 34.29 -358.166416)
		(property "Reference" "R364"
			(at 0 0 0)
			(layer "F.SilkS")
			(hide yes)
			(effects
				(font
					(size 1.27 1.27)
				)
			)
		)
		(property "Value" "0R2J-2-GP"
			(at 0.064008 -3.993896 0)
			(unlocked yes)
			(layer "F.Fab")
			(hide yes)
			(effects
				(font
					(size 1.016 1.016)
					(thickness 0.1524)
				)
			)
		)
		(property "Device Type" "R402H16"
			(at 0.064008 -5.517896 0)
			(unlocked yes)
			(layer "F.Fab")
			(hide yes)
			(effects
				(font
					(size 1.016 1.016)
					(thickness 0.1524)
				)
			)
		)
		(duplicate_pad_numbers_are_jumpers no)
		(fp_line
			(start -0.508 -0.9398)
			(end -0.508 0.9398)
			(stroke
				(width 0.1524)
				(type default)
			)
			(layer "F.SilkS")
		)
		(fp_line
			(start 0.508 -0.9398)
			(end -0.508 -0.9398)
			(stroke
				(width 0.1524)
				(type default)
			)
			(layer "F.SilkS")
		)
		(fp_rect
			(start -0.508 0.9398)
			(end 0.508 -0.9398)
			(stroke
				(width 0)
				(type default)
			)
			(fill no)
			(layer "F.CrtYd")
		)
		(fp_rect
			(start -0.508 0.9398)
			(end 0.508 -0.9398)
			(stroke
				(width 0)
				(type default)
			)
			(fill no)
			(layer "F.Fab")
		)
		(pad "1" smd custom
			(at 0 -0.4445)
			(size 0.1397 0.1397)
			(layers "F.Cu" "F.Mask" "F.Paste")
			(net "OTP_RETRY_DIODE")
			(options
				(clearance outline)
				(anchor circle)
			)
			(primitives
				(gr_poly
					(pts
						(arc
							(start -0.1778 -0.2794)
							(mid -0.249642 -0.249642)
							(end -0.2794 -0.1778)
						)
						(arc
							(start -0.2794 0.1778)
							(mid -0.249642 0.249642)
							(end -0.1778 0.2794)
						)
						(arc
							(start 0.1778 0.2794)
							(mid 0.249642 0.249642)
							(end 0.2794 0.1778)
						)
						(arc
							(start 0.2794 -0.1778)
							(mid 0.249642 -0.249642)
							(end 0.1778 -0.2794)
						)
					)
					(width 0)
					(fill yes)
				)
			)
		)
		(pad "2" smd custom
			(at 0 0.4445)
			(size 0.1397 0.1397)
			(layers "F.Cu" "F.Mask" "F.Paste")
			(net "OTP_RETRY_G")
			(options
				(clearance outline)
				(anchor circle)
			)
			(primitives
				(gr_poly
					(pts
						(arc
							(start -0.1778 -0.2794)
							(mid -0.249642 -0.249642)
							(end -0.2794 -0.1778)
						)
						(arc
							(start -0.2794 0.1778)
							(mid -0.249642 0.249642)
							(end -0.1778 0.2794)
						)
						(arc
							(start 0.1778 0.2794)
							(mid 0.249642 0.249642)
							(end 0.2794 0.1778)
						)
						(arc
							(start 0.2794 -0.1778)
							(mid 0.249642 -0.249642)
							(end 0.1778 -0.2794)
						)
					)
					(width 0)
					(fill yes)
				)
			)
		)
	)
	(footprint ""
		(layer "F.Cu")
		(at 16.002 -67.564)
		(property "Reference" "R60"
			(at 0 0 0)
			(layer "F.SilkS")
			(hide yes)
			(effects
				(font
					(size 1.27 1.27)
				)
			)
		)
		(property "Value" "4K7R2F-GP"
			(at 0.064008 -3.993896 0)
			(unlocked yes)
			(layer "F.Fab")
			(hide yes)
			(effects
				(font
					(size 1.016 1.016)
					(thickness 0.1524)
				)
			)
		)
		(property "Device Type" "R402H16"
			(at 0.064008 -5.517896 0)
			(unlocked yes)
			(layer "F.Fab")
			(hide yes)
			(effects
				(font
					(size 1.016 1.016)
					(thickness 0.1524)
				)
			)
		)
		(duplicate_pad_numbers_are_jumpers no)
		(fp_line
			(start -0.508 -0.9398)
			(end -0.508 0.9398)
			(stroke
				(width 0.1524)
				(type default)
			)
			(layer "F.SilkS")
		)
		(fp_line
			(start 0.508 -0.9398)
			(end -0.508 -0.9398)
			(stroke
				(width 0.1524)
				(type default)
			)
			(layer "F.SilkS")
		)
		(fp_rect
			(start -0.508 0.9398)
			(end 0.508 -0.9398)
			(stroke
				(width 0)
				(type default)
			)
			(fill no)
			(layer "F.CrtYd")
		)
		(fp_rect
			(start -0.508 0.9398)
			(end 0.508 -0.9398)
			(stroke
				(width 0)
				(type default)
			)
			(fill no)
			(layer "F.Fab")
		)
		(pad "1" smd custom
			(at 0 -0.4445)
			(size 0.1397 0.1397)
			(layers "F.Cu" "F.Mask" "F.Paste")
			(net "P3V3")
			(options
				(clearance outline)
				(anchor circle)
			)
			(primitives
				(gr_poly
					(pts
						(arc
							(start -0.1778 -0.2794)
							(mid -0.249642 -0.249642)
							(end -0.2794 -0.1778)
						)
						(arc
							(start -0.2794 0.1778)
							(mid -0.249642 0.249642)
							(end -0.1778 0.2794)
						)
						(arc
							(start 0.1778 0.2794)
							(mid 0.249642 0.249642)
							(end 0.2794 0.1778)
						)
						(arc
							(start 0.2794 -0.1778)
							(mid 0.249642 -0.249642)
							(end 0.1778 -0.2794)
						)
					)
					(width 0)
					(fill yes)
				)
			)
		)
		(pad "2" smd custom
			(at 0 0.4445)
			(size 0.1397 0.1397)
			(layers "F.Cu" "F.Mask" "F.Paste")
			(net "I2C_C_SDA_CONN_R")
			(options
				(clearance outline)
				(anchor circle)
			)
			(primitives
				(gr_poly
					(pts
						(arc
							(start -0.1778 -0.2794)
							(mid -0.249642 -0.249642)
							(end -0.2794 -0.1778)
						)
						(arc
							(start -0.2794 0.1778)
							(mid -0.249642 0.249642)
							(end -0.1778 0.2794)
						)
						(arc
							(start 0.1778 0.2794)
							(mid 0.249642 0.249642)
							(end 0.2794 0.1778)
						)
						(arc
							(start 0.2794 -0.1778)
							(mid 0.249642 -0.249642)
							(end 0.1778 -0.2794)
						)
					)
					(width 0)
					(fill yes)
				)
			)
		)
	)
	(footprint ""
		(layer "F.Cu")
		(at 14.5796 -53.2384)
		(property "Reference" "R360"
			(at 0 0 0)
			(layer "F.SilkS")
			(hide yes)
			(effects
				(font
					(size 1.27 1.27)
				)
			)
		)
		(property "Value" "100R2J-2-GP"
			(at 0.064008 -3.993896 0)
			(unlocked yes)
			(layer "F.Fab")
			(hide yes)
			(effects
				(font
					(size 1.016 1.016)
					(thickness 0.1524)
				)
			)
		)
		(property "Device Type" "R402H14"
			(at 0.064008 -5.517896 0)
			(unlocked yes)
			(layer "F.Fab")
			(hide yes)
			(effects
				(font
					(size 1.016 1.016)
					(thickness 0.1524)
				)
			)
		)
		(duplicate_pad_numbers_are_jumpers no)
		(fp_line
			(start -0.508 -0.9398)
			(end -0.508 0.9398)
			(stroke
				(width 0.1524)
				(type default)
			)
			(layer "F.SilkS")
		)
		(fp_line
			(start 0.508 -0.9398)
			(end -0.508 -0.9398)
			(stroke
				(width 0.1524)
				(type default)
			)
			(layer "F.SilkS")
		)
		(fp_rect
			(start -0.508 0.9398)
			(end 0.508 -0.9398)
			(stroke
				(width 0)
				(type default)
			)
			(fill no)
			(layer "F.CrtYd")
		)
		(fp_rect
			(start -0.508 0.9398)
			(end 0.508 -0.9398)
			(stroke
				(width 0)
				(type default)
			)
			(fill no)
			(layer "F.Fab")
		)
		(pad "1" smd custom
			(at 0 -0.4445)
			(size 0.1397 0.1397)
			(layers "F.Cu" "F.Mask" "F.Paste")
			(net "FCB_HW_REVISION")
			(options
				(clearance outline)
				(anchor circle)
			)
			(primitives
				(gr_poly
					(pts
						(arc
							(start -0.1778 -0.2794)
							(mid -0.249642 -0.249642)
							(end -0.2794 -0.1778)
						)
						(arc
							(start -0.2794 0.1778)
							(mid -0.249642 0.249642)
							(end -0.1778 0.2794)
						)
						(arc
							(start 0.1778 0.2794)
							(mid 0.249642 0.249642)
							(end 0.2794 0.1778)
						)
						(arc
							(start 0.2794 -0.1778)
							(mid 0.249642 -0.249642)
							(end 0.1778 -0.2794)
						)
					)
					(width 0)
					(fill yes)
				)
			)
		)
		(pad "2" smd custom
			(at 0 0.4445)
			(size 0.1397 0.1397)
			(layers "F.Cu" "F.Mask" "F.Paste")
			(net "GND")
			(options
				(clearance outline)
				(anchor circle)
			)
			(primitives
				(gr_poly
					(pts
						(arc
							(start -0.1778 -0.2794)
							(mid -0.249642 -0.249642)
							(end -0.2794 -0.1778)
						)
						(arc
							(start -0.2794 0.1778)
							(mid -0.249642 0.249642)
							(end -0.1778 0.2794)
						)
						(arc
							(start 0.1778 0.2794)
							(mid 0.249642 0.249642)
							(end 0.2794 0.1778)
						)
						(arc
							(start 0.2794 -0.1778)
							(mid 0.249642 -0.249642)
							(end 0.1778 -0.2794)
						)
					)
					(width 0)
					(fill yes)
				)
			)
		)
	)
	(footprint ""
		(layer "F.Cu")
		(at 42.5958 -177.2666 180)
		(property "Reference" "PR47"
			(at 0 0 180)
			(layer "F.SilkS")
			(hide yes)
			(effects
				(font
					(size 1.27 1.27)
				)
			)
		)
		(property "Value" "4K7R2J-2-GP"
			(at 0.064008 -3.993896 180)
			(unlocked yes)
			(layer "F.Fab")
			(hide yes)
			(effects
				(font
					(size 1.016 1.016)
					(thickness 0.1524)
				)
			)
		)
		(property "Device Type" "R402H16"
			(at 0.064008 -5.517896 180)
			(unlocked yes)
			(layer "F.Fab")
			(hide yes)
			(effects
				(font
					(size 1.016 1.016)
					(thickness 0.1524)
				)
			)
		)
		(duplicate_pad_numbers_are_jumpers no)
		(fp_line
			(start 0.508 -0.9398)
			(end -0.508 -0.9398)
			(stroke
				(width 0.1524)
				(type default)
			)
			(layer "F.SilkS")
		)
		(fp_line
			(start -0.508 -0.9398)
			(end -0.508 0.9398)
			(stroke
				(width 0.1524)
				(type default)
			)
			(layer "F.SilkS")
		)
		(fp_rect
			(start -0.508 0.9398)
			(end 0.508 -0.9398)
			(stroke
				(width 0)
				(type default)
			)
			(fill no)
			(layer "F.CrtYd")
		)
		(fp_rect
			(start -0.508 0.9398)
			(end 0.508 -0.9398)
			(stroke
				(width 0)
				(type default)
			)
			(fill no)
			(layer "F.Fab")
		)
		(pad "1" smd custom
			(at 0 -0.4445 180)
			(size 0.1397 0.1397)
			(layers "F.Cu" "F.Mask" "F.Paste")
			(net "P3V3_AUX")
			(options
				(clearance outline)
				(anchor circle)
			)
			(primitives
				(gr_poly
					(pts
						(arc
							(start -0.1778 -0.2794)
							(mid -0.249642 -0.249642)
							(end -0.2794 -0.1778)
						)
						(arc
							(start -0.2794 0.1778)
							(mid -0.249642 0.249642)
							(end -0.1778 0.2794)
						)
						(arc
							(start 0.1778 0.2794)
							(mid 0.249642 0.249642)
							(end 0.2794 0.1778)
						)
						(arc
							(start 0.2794 -0.1778)
							(mid 0.249642 -0.249642)
							(end 0.1778 -0.2794)
						)
					)
					(width 0)
					(fill yes)
				)
			)
		)
		(pad "2" smd custom
			(at 0 0.4445 180)
			(size 0.1397 0.1397)
			(layers "F.Cu" "F.Mask" "F.Paste")
			(net "D_LATCH_Q")
			(options
				(clearance outline)
				(anchor circle)
			)
			(primitives
				(gr_poly
					(pts
						(arc
							(start -0.1778 -0.2794)
							(mid -0.249642 -0.249642)
							(end -0.2794 -0.1778)
						)
						(arc
							(start -0.2794 0.1778)
							(mid -0.249642 0.249642)
							(end -0.1778 0.2794)
						)
						(arc
							(start 0.1778 0.2794)
							(mid 0.249642 0.249642)
							(end 0.2794 0.1778)
						)
						(arc
							(start 0.2794 -0.1778)
							(mid 0.249642 -0.249642)
							(end 0.1778 -0.2794)
						)
					)
					(width 0)
					(fill yes)
				)
			)
		)
	)
	(footprint ""
		(layer "F.Cu")
		(at 29.1592 -253.8984 180)
		(property "Reference" "R45"
			(at 0 0 180)
			(layer "F.SilkS")
			(hide yes)
			(effects
				(font
					(size 1.27 1.27)
				)
			)
		)
		(property "Value" "0R2J-2-GP"
			(at 0.064008 -3.993896 180)
			(unlocked yes)
			(layer "F.Fab")
			(hide yes)
			(effects
				(font
					(size 1.016 1.016)
					(thickness 0.1524)
				)
			)
		)
		(property "Device Type" "R402H16"
			(at 0.064008 -5.517896 180)
			(unlocked yes)
			(layer "F.Fab")
			(hide yes)
			(effects
				(font
					(size 1.016 1.016)
					(thickness 0.1524)
				)
			)
		)
		(duplicate_pad_numbers_are_jumpers no)
		(fp_line
			(start 0.508 -0.9398)
			(end -0.508 -0.9398)
			(stroke
				(width 0.1524)
				(type default)
			)
			(layer "F.SilkS")
		)
		(fp_line
			(start -0.508 -0.9398)
			(end -0.508 0.9398)
			(stroke
				(width 0.1524)
				(type default)
			)
			(layer "F.SilkS")
		)
		(fp_rect
			(start -0.508 0.9398)
			(end 0.508 -0.9398)
			(stroke
				(width 0)
				(type default)
			)
			(fill no)
			(layer "F.CrtYd")
		)
		(fp_rect
			(start -0.508 0.9398)
			(end 0.508 -0.9398)
			(stroke
				(width 0)
				(type default)
			)
			(fill no)
			(layer "F.Fab")
		)
		(pad "1" smd custom
			(at 0 -0.4445 180)
			(size 0.1397 0.1397)
			(layers "F.Cu" "F.Mask" "F.Paste")
			(net "EEPROM_WP")
			(options
				(clearance outline)
				(anchor circle)
			)
			(primitives
				(gr_poly
					(pts
						(arc
							(start -0.1778 -0.2794)
							(mid -0.249642 -0.249642)
							(end -0.2794 -0.1778)
						)
						(arc
							(start -0.2794 0.1778)
							(mid -0.249642 0.249642)
							(end -0.1778 0.2794)
						)
						(arc
							(start 0.1778 0.2794)
							(mid 0.249642 0.249642)
							(end 0.2794 0.1778)
						)
						(arc
							(start 0.2794 -0.1778)
							(mid 0.249642 -0.249642)
							(end 0.1778 -0.2794)
						)
					)
					(width 0)
					(fill yes)
				)
			)
		)
		(pad "2" smd custom
			(at 0 0.4445 180)
			(size 0.1397 0.1397)
			(layers "F.Cu" "F.Mask" "F.Paste")
			(net "GND")
			(options
				(clearance outline)
				(anchor circle)
			)
			(primitives
				(gr_poly
					(pts
						(arc
							(start -0.1778 -0.2794)
							(mid -0.249642 -0.249642)
							(end -0.2794 -0.1778)
						)
						(arc
							(start -0.2794 0.1778)
							(mid -0.249642 0.249642)
							(end -0.1778 0.2794)
						)
						(arc
							(start 0.1778 0.2794)
							(mid 0.249642 0.249642)
							(end 0.2794 0.1778)
						)
						(arc
							(start 0.2794 -0.1778)
							(mid 0.249642 -0.249642)
							(end 0.1778 -0.2794)
						)
					)
					(width 0)
					(fill yes)
				)
			)
		)
	)
	(footprint ""
		(layer "F.Cu")
		(at 37.4904 -252.6284)
		(property "Reference" "TP26"
			(at 0 0 0)
			(layer "F.SilkS")
			(hide yes)
			(effects
				(font
					(size 1.27 1.27)
				)
			)
		)
		(property "Value" "TPAD32-GP"
			(at 0 -3.166364 0)
			(unlocked yes)
			(layer "F.Fab")
			(hide yes)
			(effects
				(font
					(size 1.016 1.016)
					(thickness 0.1524)
				)
			)
		)
		(property "Device Type" "TPAD32"
			(at 0 -4.690618 0)
			(unlocked yes)
			(layer "F.Fab")
			(hide yes)
			(effects
				(font
					(size 1.016 1.016)
					(thickness 0.1524)
				)
			)
		)
		(duplicate_pad_numbers_are_jumpers no)
		(fp_poly
			(pts
				(arc
					(start 0.7112 0)
					(mid -0.7112 0)
					(end 0.7112 0)
				)
			)
			(stroke
				(width 0)
				(type default)
			)
			(fill no)
			(layer "F.CrtYd")
		)
		(fp_poly
			(pts
				(arc
					(start 0.7112 0)
					(mid -0.7112 0)
					(end 0.7112 0)
				)
			)
			(stroke
				(width 0)
				(type default)
			)
			(fill no)
			(layer "F.Fab")
		)
		(pad "1" smd circle
			(at 0 0)
			(size 0.8128 0.8128)
			(layers "F.Cu" "F.Mask" "F.Paste")
			(net "LED_DR_LED7_RESERVE")
		)
	)
	(footprint ""
		(layer "F.Cu")
		(at 19.5834 -266.7254)
		(property "Reference" "F4"
			(at 0 0 0)
			(layer "F.SilkS")
			(hide yes)
			(effects
				(font
					(size 1.27 1.27)
				)
			)
		)
		(property "Value" "FUSE-3A15V-GP"
			(at 0.2286 -10.5918 0)
			(unlocked yes)
			(layer "F.Fab")
			(hide yes)
			(effects
				(font
					(size 1.016 1.016)
					(thickness 0.1524)
				)
			)
		)
		(property "Device Type" "FUSE-7452-UH50"
			(at 0.2286 -12.4968 0)
			(unlocked yes)
			(layer "F.Fab")
			(hide yes)
			(effects
				(font
					(size 1.016 1.016)
					(thickness 0.1524)
				)
			)
		)
		(duplicate_pad_numbers_are_jumpers no)
		(fp_line
			(start -4.9276 -2.921)
			(end 4.9276 -2.921)
			(stroke
				(width 0.1524)
				(type default)
			)
			(layer "F.SilkS")
		)
		(fp_line
			(start -4.9276 2.921)
			(end -4.9276 -2.921)
			(stroke
				(width 0.1524)
				(type default)
			)
			(layer "F.SilkS")
		)
		(fp_line
			(start 4.9276 -2.921)
			(end 4.9276 2.921)
			(stroke
				(width 0.1524)
				(type default)
			)
			(layer "F.SilkS")
		)
		(fp_line
			(start 4.9276 2.921)
			(end -4.9276 2.921)
			(stroke
				(width 0.1524)
				(type default)
			)
			(layer "F.SilkS")
		)
		(fp_poly
			(pts
				(xy -5.08 3.0988) (xy 5.08 3.0988) (xy 5.08 -3.0988) (xy -5.08 -3.0988)
			)
			(stroke
				(width 0)
				(type default)
			)
			(fill no)
			(layer "F.CrtYd")
		)
		(fp_poly
			(pts
				(xy -5.08 -3.0988) (xy 5.08 -3.0988) (xy 5.08 3.0988) (xy -5.08 3.0988)
			)
			(stroke
				(width 0)
				(type default)
			)
			(fill no)
			(layer "F.Fab")
		)
		(pad "1" smd rect
			(at -3.4036 0)
			(size 2.2098 5.2832)
			(layers "F.Cu" "F.Mask" "F.Paste")
			(net "P12V_FAN3")
		)
		(pad "2" smd rect
			(at 3.4036 0)
			(size 2.2098 5.2832)
			(layers "F.Cu" "F.Mask" "F.Paste")
			(net "P12V")
		)
	)
	(footprint ""
		(layer "F.Cu")
		(at 27.9654 -355.5238 90)
		(property "Reference" "Q10"
			(at 0 0 90)
			(layer "F.SilkS")
			(hide yes)
			(effects
				(font
					(size 1.27 1.27)
				)
			)
		)
		(property "Value" "2N7002DW-7F-GP"
			(at -2.3622 -8.2042 90)
			(unlocked yes)
			(layer "F.Fab")
			(hide yes)
			(effects
				(font
					(size 1.016 1.016)
					(thickness 0.1524)
				)
			)
		)
		(property "Device Type" "SOT-363H44"
			(at -2.3622 -10.1092 90)
			(unlocked yes)
			(layer "F.Fab")
			(hide yes)
			(effects
				(font
					(size 1.016 1.016)
					(thickness 0.1524)
				)
			)
		)
		(duplicate_pad_numbers_are_jumpers no)
		(fp_line
			(start 1.4478 -1.7018)
			(end -1.4478 -1.7018)
			(stroke
				(width 0.1524)
				(type default)
			)
			(layer "F.SilkS")
		)
		(fp_line
			(start -1.4478 -1.7018)
			(end -1.4478 1.7018)
			(stroke
				(width 0.1524)
				(type default)
			)
			(layer "F.SilkS")
		)
		(fp_line
			(start -1.27 1.524)
			(end -1.27 0.6604)
			(stroke
				(width 0.4826)
				(type default)
			)
			(layer "F.SilkS")
		)
		(fp_line
			(start 1.4478 1.7018)
			(end 1.4478 -1.7018)
			(stroke
				(width 0.1524)
				(type default)
			)
			(layer "F.SilkS")
		)
		(fp_line
			(start -1.4478 1.7018)
			(end 1.4478 1.7018)
			(stroke
				(width 0.1524)
				(type default)
			)
			(layer "F.SilkS")
		)
		(fp_poly
			(pts
				(xy -1.524 -1.778) (xy 1.524 -1.778) (xy 1.524 1.778) (xy -1.524 1.778)
			)
			(stroke
				(width 0)
				(type default)
			)
			(fill no)
			(layer "F.CrtYd")
		)
		(fp_poly
			(pts
				(xy -1.524 -1.778) (xy 1.524 -1.778) (xy 1.524 1.778) (xy -1.524 1.778)
			)
			(stroke
				(width 0)
				(type default)
			)
			(fill no)
			(layer "F.Fab")
		)
		(pad "1" smd rect
			(at -0.65024 0.9398 90)
			(size 0.4064 1.016)
			(layers "F.Cu" "F.Mask" "F.Paste")
			(net "GND")
		)
		(pad "2" smd rect
			(at 0 0.9398 90)
			(size 0.4064 1.016)
			(layers "F.Cu" "F.Mask" "F.Paste")
			(net "TEMP_ALM#")
		)
		(pad "3" smd rect
			(at 0.65024 0.9398 90)
			(size 0.4064 1.016)
			(layers "F.Cu" "F.Mask" "F.Paste")
			(net "TEMP_ALM#_JP_2")
		)
		(pad "4" smd rect
			(at 0.65024 -0.9398 90)
			(size 0.4064 1.016)
			(layers "F.Cu" "F.Mask" "F.Paste")
			(net "GND")
		)
		(pad "5" smd rect
			(at 0 -0.9398 90)
			(size 0.4064 1.016)
			(layers "F.Cu" "F.Mask" "F.Paste")
			(net "TEMP_ALM#_G")
		)
		(pad "6" smd rect
			(at -0.65024 -0.9398 90)
			(size 0.4064 1.016)
			(layers "F.Cu" "F.Mask" "F.Paste")
			(net "TEMP_ALM#_G")
		)
	)
	(footprint ""
		(layer "F.Cu")
		(at 28.1686 -224.3074)
		(property "Reference" "R140"
			(at 0 0 0)
			(layer "F.SilkS")
			(hide yes)
			(effects
				(font
					(size 1.27 1.27)
				)
			)
		)
		(property "Value" "0R2J-2-GP"
			(at 0.064008 -3.993896 0)
			(unlocked yes)
			(layer "F.Fab")
			(hide yes)
			(effects
				(font
					(size 1.016 1.016)
					(thickness 0.1524)
				)
			)
		)
		(property "Device Type" "R402H16"
			(at 0.064008 -5.517896 0)
			(unlocked yes)
			(layer "F.Fab")
			(hide yes)
			(effects
				(font
					(size 1.016 1.016)
					(thickness 0.1524)
				)
			)
		)
		(duplicate_pad_numbers_are_jumpers no)
		(fp_line
			(start -0.508 -0.9398)
			(end -0.508 0.9398)
			(stroke
				(width 0.1524)
				(type default)
			)
			(layer "F.SilkS")
		)
		(fp_line
			(start 0.508 -0.9398)
			(end -0.508 -0.9398)
			(stroke
				(width 0.1524)
				(type default)
			)
			(layer "F.SilkS")
		)
		(fp_rect
			(start -0.508 0.9398)
			(end 0.508 -0.9398)
			(stroke
				(width 0)
				(type default)
			)
			(fill no)
			(layer "F.CrtYd")
		)
		(fp_rect
			(start -0.508 0.9398)
			(end 0.508 -0.9398)
			(stroke
				(width 0)
				(type default)
			)
			(fill no)
			(layer "F.Fab")
		)
		(pad "1" smd custom
			(at 0 -0.4445)
			(size 0.1397 0.1397)
			(layers "F.Cu" "F.Mask" "F.Paste")
			(net "PWM_OUT_FAN2_NET")
			(options
				(clearance outline)
				(anchor circle)
			)
			(primitives
				(gr_poly
					(pts
						(arc
							(start -0.1778 -0.2794)
							(mid -0.249642 -0.249642)
							(end -0.2794 -0.1778)
						)
						(arc
							(start -0.2794 0.1778)
							(mid -0.249642 0.249642)
							(end -0.1778 0.2794)
						)
						(arc
							(start 0.1778 0.2794)
							(mid 0.249642 0.249642)
							(end 0.2794 0.1778)
						)
						(arc
							(start 0.2794 -0.1778)
							(mid 0.249642 -0.249642)
							(end 0.1778 -0.2794)
						)
					)
					(width 0)
					(fill yes)
				)
			)
		)
		(pad "2" smd custom
			(at 0 0.4445)
			(size 0.1397 0.1397)
			(layers "F.Cu" "F.Mask" "F.Paste")
			(net "PWM_OUT_FAN2")
			(options
				(clearance outline)
				(anchor circle)
			)
			(primitives
				(gr_poly
					(pts
						(arc
							(start -0.1778 -0.2794)
							(mid -0.249642 -0.249642)
							(end -0.2794 -0.1778)
						)
						(arc
							(start -0.2794 0.1778)
							(mid -0.249642 0.249642)
							(end -0.1778 0.2794)
						)
						(arc
							(start 0.1778 0.2794)
							(mid 0.249642 0.249642)
							(end 0.2794 0.1778)
						)
						(arc
							(start 0.2794 -0.1778)
							(mid 0.249642 -0.249642)
							(end 0.1778 -0.2794)
						)
					)
					(width 0)
					(fill yes)
				)
			)
		)
	)
	(footprint ""
		(layer "F.Cu")
		(at 37.211 -378.333 180)
		(property "Reference" "PR27"
			(at 0 0 180)
			(layer "F.SilkS")
			(hide yes)
			(effects
				(font
					(size 1.27 1.27)
				)
			)
		)
		(property "Value" "10R2F-L-GP"
			(at 0.064008 -3.993896 180)
			(unlocked yes)
			(layer "F.Fab")
			(hide yes)
			(effects
				(font
					(size 1.016 1.016)
					(thickness 0.1524)
				)
			)
		)
		(property "Device Type" "R402H14"
			(at 0.064008 -5.517896 180)
			(unlocked yes)
			(layer "F.Fab")
			(hide yes)
			(effects
				(font
					(size 1.016 1.016)
					(thickness 0.1524)
				)
			)
		)
		(duplicate_pad_numbers_are_jumpers no)
		(fp_line
			(start 0.508 -0.9398)
			(end -0.508 -0.9398)
			(stroke
				(width 0.1524)
				(type default)
			)
			(layer "F.SilkS")
		)
		(fp_line
			(start -0.508 -0.9398)
			(end -0.508 0.9398)
			(stroke
				(width 0.1524)
				(type default)
			)
			(layer "F.SilkS")
		)
		(fp_rect
			(start -0.508 0.9398)
			(end 0.508 -0.9398)
			(stroke
				(width 0)
				(type default)
			)
			(fill no)
			(layer "F.CrtYd")
		)
		(fp_rect
			(start -0.508 0.9398)
			(end 0.508 -0.9398)
			(stroke
				(width 0)
				(type default)
			)
			(fill no)
			(layer "F.Fab")
		)
		(pad "1" smd custom
			(at 0 -0.4445 180)
			(size 0.1397 0.1397)
			(layers "F.Cu" "F.Mask" "F.Paste")
			(net "ADM1276_GATE")
			(options
				(clearance outline)
				(anchor circle)
			)
			(primitives
				(gr_poly
					(pts
						(arc
							(start -0.1778 -0.2794)
							(mid -0.249642 -0.249642)
							(end -0.2794 -0.1778)
						)
						(arc
							(start -0.2794 0.1778)
							(mid -0.249642 0.249642)
							(end -0.1778 0.2794)
						)
						(arc
							(start 0.1778 0.2794)
							(mid 0.249642 0.249642)
							(end 0.2794 0.1778)
						)
						(arc
							(start 0.2794 -0.1778)
							(mid 0.249642 -0.249642)
							(end 0.1778 -0.2794)
						)
					)
					(width 0)
					(fill yes)
				)
			)
		)
		(pad "2" smd custom
			(at 0 0.4445 180)
			(size 0.1397 0.1397)
			(layers "F.Cu" "F.Mask" "F.Paste")
			(net "ADM1276_GATE_DRV2")
			(options
				(clearance outline)
				(anchor circle)
			)
			(primitives
				(gr_poly
					(pts
						(arc
							(start -0.1778 -0.2794)
							(mid -0.249642 -0.249642)
							(end -0.2794 -0.1778)
						)
						(arc
							(start -0.2794 0.1778)
							(mid -0.249642 0.249642)
							(end -0.1778 0.2794)
						)
						(arc
							(start 0.1778 0.2794)
							(mid 0.249642 0.249642)
							(end 0.2794 0.1778)
						)
						(arc
							(start 0.2794 -0.1778)
							(mid 0.249642 -0.249642)
							(end 0.1778 -0.2794)
						)
					)
					(width 0)
					(fill yes)
				)
			)
		)
	)
	(footprint ""
		(layer "F.Cu")
		(at 18.288 -122.555)
		(property "Reference" "PR60"
			(at 0 0 0)
			(layer "F.SilkS")
			(hide yes)
			(effects
				(font
					(size 1.27 1.27)
				)
			)
		)
		(property "Value" "D002R2512F-GP"
			(at -3.228594 -1.194054 0)
			(unlocked yes)
			(layer "F.Fab")
			(hide yes)
			(effects
				(font
					(size 1.016 1.016)
					(thickness 0.1524)
				)
			)
		)
		(property "Device Type" "R2512-2H32"
			(at -3.228594 -2.718054 0)
			(unlocked yes)
			(layer "F.Fab")
			(hide yes)
			(effects
				(font
					(size 1.016 1.016)
					(thickness 0.1524)
				)
			)
		)
		(duplicate_pad_numbers_are_jumpers no)
		(fp_line
			(start -1.9685 -3.81)
			(end 1.9685 -3.81)
			(stroke
				(width 0.1524)
				(type default)
			)
			(layer "F.SilkS")
		)
		(fp_line
			(start -1.9685 3.81)
			(end -1.9685 -3.81)
			(stroke
				(width 0.1524)
				(type default)
			)
			(layer "F.SilkS")
		)
		(fp_line
			(start 1.9685 -3.81)
			(end 1.9685 3.81)
			(stroke
				(width 0.1524)
				(type default)
			)
			(layer "F.SilkS")
		)
		(fp_line
			(start 1.9685 3.81)
			(end -1.9685 3.81)
			(stroke
				(width 0.1524)
				(type default)
			)
			(layer "F.SilkS")
		)
		(fp_rect
			(start -1.5875 3.175)
			(end 1.5875 -3.175)
			(stroke
				(width 0)
				(type default)
			)
			(fill no)
			(layer "F.CrtYd")
		)
		(fp_poly
			(pts
				(xy -2.2225 3.8862) (xy -2.2225 0.00254) (xy -1.5875 0.00254) (xy -1.5875 3.175) (xy 1.5875 3.175)
				(xy 1.5875 -3.175) (xy -1.5875 -3.175) (xy -1.5875 -0.00254) (xy -2.2225 -0.00254) (xy -2.2225 -3.8862)
				(xy 2.2225 -3.8862) (xy 2.2225 3.8862)
			)
			(stroke
				(width 0)
				(type default)
			)
			(fill no)
			(layer "F.CrtYd")
		)
		(fp_rect
			(start -2.2225 3.8862)
			(end 2.2225 -3.8862)
			(stroke
				(width 0)
				(type default)
			)
			(fill no)
			(layer "F.Fab")
		)
		(pad "1" smd rect
			(at 0 -2.273808)
			(size 3.429 2.5654)
			(layers "F.Cu" "F.Mask" "F.Paste")
			(net "P12V")
		)
		(pad "2" smd rect
			(at 0 2.273808)
			(size 3.429 2.5654)
			(layers "F.Cu" "F.Mask" "F.Paste")
			(net "P12VU_NET")
		)
	)
	(footprint ""
		(layer "F.Cu")
		(at 19.939 -18.161 90)
		(property "Reference" "R71"
			(at 0 0 90)
			(layer "F.SilkS")
			(hide yes)
			(effects
				(font
					(size 1.27 1.27)
				)
			)
		)
		(property "Value" "27KR3F-GP"
			(at -0.0254 -2.5146 90)
			(unlocked yes)
			(layer "F.Fab")
			(hide yes)
			(effects
				(font
					(size 1.016 1.016)
					(thickness 0.1524)
				)
			)
		)
		(property "Device Type" "R603H22"
			(at -0.0254 -4.0386 90)
			(unlocked yes)
			(layer "F.Fab")
			(hide yes)
			(effects
				(font
					(size 1.016 1.016)
					(thickness 0.1524)
				)
			)
		)
		(duplicate_pad_numbers_are_jumpers no)
		(fp_line
			(start 0.2032 0)
			(end 0.4826 0)
			(stroke
				(width 0.2032)
				(type default)
			)
			(layer "F.SilkS")
		)
		(fp_line
			(start -0.4826 0)
			(end -0.2032 0)
			(stroke
				(width 0.2032)
				(type default)
			)
			(layer "F.SilkS")
		)
		(fp_rect
			(start -0.5842 1.3335)
			(end 0.5842 -1.3335)
			(stroke
				(width 0)
				(type default)
			)
			(fill no)
			(layer "F.CrtYd")
		)
		(fp_rect
			(start -0.5842 1.3335)
			(end 0.5842 -1.3335)
			(stroke
				(width 0)
				(type default)
			)
			(fill no)
			(layer "F.Fab")
		)
		(pad "1" smd custom
			(at 0 -0.762 90)
			(size 0.2159 0.2159)
			(layers "F.Cu" "F.Mask" "F.Paste")
			(net "FAN_TACH12")
			(options
				(clearance outline)
				(anchor circle)
			)
			(primitives
				(gr_poly
					(pts
						(arc
							(start -0.3302 -0.4318)
							(mid -0.402042 -0.402042)
							(end -0.4318 -0.3302)
						)
						(arc
							(start -0.4318 0.3302)
							(mid -0.402042 0.402042)
							(end -0.3302 0.4318)
						)
						(arc
							(start 0.3302 0.4318)
							(mid 0.402042 0.402042)
							(end 0.4318 0.3302)
						)
						(arc
							(start 0.4318 -0.3302)
							(mid 0.402042 -0.402042)
							(end 0.3302 -0.4318)
						)
					)
					(width 0)
					(fill yes)
				)
			)
		)
		(pad "2" smd custom
			(at 0 0.762 90)
			(size 0.2159 0.2159)
			(layers "F.Cu" "F.Mask" "F.Paste")
			(net "FANIN_12")
			(options
				(clearance outline)
				(anchor circle)
			)
			(primitives
				(gr_poly
					(pts
						(arc
							(start -0.3302 -0.4318)
							(mid -0.402042 -0.402042)
							(end -0.4318 -0.3302)
						)
						(arc
							(start -0.4318 0.3302)
							(mid -0.402042 0.402042)
							(end -0.3302 0.4318)
						)
						(arc
							(start 0.3302 0.4318)
							(mid 0.402042 0.402042)
							(end 0.4318 0.3302)
						)
						(arc
							(start 0.4318 -0.3302)
							(mid 0.402042 -0.402042)
							(end 0.3302 -0.4318)
						)
					)
					(width 0)
					(fill yes)
				)
			)
		)
	)
	(footprint ""
		(layer "F.Cu")
		(at 22.860762 -15.621508 90)
		(property "Reference" "R77"
			(at 0 0 90)
			(layer "F.SilkS")
			(hide yes)
			(effects
				(font
					(size 1.27 1.27)
				)
			)
		)
		(property "Value" "10KR2F-2-GP"
			(at 0.064008 -3.993896 90)
			(unlocked yes)
			(layer "F.Fab")
			(hide yes)
			(effects
				(font
					(size 1.016 1.016)
					(thickness 0.1524)
				)
			)
		)
		(property "Device Type" "R402H16"
			(at 0.064008 -5.517896 90)
			(unlocked yes)
			(layer "F.Fab")
			(hide yes)
			(effects
				(font
					(size 1.016 1.016)
					(thickness 0.1524)
				)
			)
		)
		(duplicate_pad_numbers_are_jumpers no)
		(fp_line
			(start 0.508 -0.9398)
			(end -0.508 -0.9398)
			(stroke
				(width 0.1524)
				(type default)
			)
			(layer "F.SilkS")
		)
		(fp_line
			(start -0.508 -0.9398)
			(end -0.508 0.9398)
			(stroke
				(width 0.1524)
				(type default)
			)
			(layer "F.SilkS")
		)
		(fp_rect
			(start -0.508 0.9398)
			(end 0.508 -0.9398)
			(stroke
				(width 0)
				(type default)
			)
			(fill no)
			(layer "F.CrtYd")
		)
		(fp_rect
			(start -0.508 0.9398)
			(end 0.508 -0.9398)
			(stroke
				(width 0)
				(type default)
			)
			(fill no)
			(layer "F.Fab")
		)
		(pad "1" smd custom
			(at 0 -0.4445 90)
			(size 0.1397 0.1397)
			(layers "F.Cu" "F.Mask" "F.Paste")
			(net "FANIN_11")
			(options
				(clearance outline)
				(anchor circle)
			)
			(primitives
				(gr_poly
					(pts
						(arc
							(start -0.1778 -0.2794)
							(mid -0.249642 -0.249642)
							(end -0.2794 -0.1778)
						)
						(arc
							(start -0.2794 0.1778)
							(mid -0.249642 0.249642)
							(end -0.1778 0.2794)
						)
						(arc
							(start 0.1778 0.2794)
							(mid 0.249642 0.249642)
							(end 0.2794 0.1778)
						)
						(arc
							(start 0.2794 -0.1778)
							(mid 0.249642 -0.249642)
							(end 0.1778 -0.2794)
						)
					)
					(width 0)
					(fill yes)
				)
			)
		)
		(pad "2" smd custom
			(at 0 0.4445 90)
			(size 0.1397 0.1397)
			(layers "F.Cu" "F.Mask" "F.Paste")
			(net "GND")
			(options
				(clearance outline)
				(anchor circle)
			)
			(primitives
				(gr_poly
					(pts
						(arc
							(start -0.1778 -0.2794)
							(mid -0.249642 -0.249642)
							(end -0.2794 -0.1778)
						)
						(arc
							(start -0.2794 0.1778)
							(mid -0.249642 0.249642)
							(end -0.1778 0.2794)
						)
						(arc
							(start 0.1778 0.2794)
							(mid 0.249642 0.249642)
							(end 0.2794 0.1778)
						)
						(arc
							(start 0.2794 -0.1778)
							(mid 0.249642 -0.249642)
							(end 0.1778 -0.2794)
						)
					)
					(width 0)
					(fill yes)
				)
			)
		)
	)
	(footprint ""
		(layer "F.Cu")
		(at 5.5118 -420.9034 90)
		(property "Reference" "R126"
			(at 0 0 90)
			(layer "F.SilkS")
			(hide yes)
			(effects
				(font
					(size 1.27 1.27)
				)
			)
		)
		(property "Value" "1K8R6J-GP"
			(at -0.0508 -4.8514 90)
			(unlocked yes)
			(layer "F.Fab")
			(hide yes)
			(effects
				(font
					(size 1.016 1.016)
					(thickness 0.1524)
				)
			)
		)
		(property "Device Type" "R1206H28"
			(at 0 -6.3754 90)
			(unlocked yes)
			(layer "F.Fab")
			(hide yes)
			(effects
				(font
					(size 1.016 1.016)
					(thickness 0.1524)
				)
			)
		)
		(duplicate_pad_numbers_are_jumpers no)
		(fp_line
			(start 1.016 -2.2352)
			(end 1.016 2.2352)
			(stroke
				(width 0.1524)
				(type default)
			)
			(layer "F.SilkS")
		)
		(fp_line
			(start -1.016 -2.2352)
			(end 1.016 -2.2352)
			(stroke
				(width 0.1524)
				(type default)
			)
			(layer "F.SilkS")
		)
		(fp_line
			(start 1.016 2.2352)
			(end -1.016 2.2352)
			(stroke
				(width 0.1524)
				(type default)
			)
			(layer "F.SilkS")
		)
		(fp_line
			(start -1.016 2.2352)
			(end -1.016 -2.2352)
			(stroke
				(width 0.1524)
				(type default)
			)
			(layer "F.SilkS")
		)
		(fp_rect
			(start -1.0922 2.3114)
			(end 1.0922 -2.3114)
			(stroke
				(width 0)
				(type default)
			)
			(fill no)
			(layer "F.CrtYd")
		)
		(fp_poly
			(pts
				(xy -1.0922 -2.3114) (xy 1.0922 -2.3114) (xy 1.0922 2.3114) (xy -1.0922 2.3114)
			)
			(stroke
				(width 0)
				(type default)
			)
			(fill no)
			(layer "F.Fab")
		)
		(pad "1" smd rect
			(at 0 -1.397 90)
			(size 1.651 1.27)
			(layers "F.Cu" "F.Mask" "F.Paste")
			(net "P12V")
		)
		(pad "2" smd rect
			(at 0 1.397 90)
			(size 1.651 1.27)
			(layers "F.Cu" "F.Mask" "F.Paste")
			(net "LED_DR_LED1_BLUE")
		)
	)
	(footprint ""
		(layer "F.Cu")
		(at 45.499782 -144.999964)
		(property "Reference" "H8"
			(at 0 0 0)
			(layer "F.SilkS")
			(hide yes)
			(effects
				(font
					(size 1.27 1.27)
				)
			)
		)
		(property "Value" "HOLE315R138"
			(at 0 -7.0612 0)
			(unlocked yes)
			(layer "F.Fab")
			(hide yes)
			(effects
				(font
					(size 1.016 1.016)
					(thickness 0.1524)
				)
			)
		)
		(property "Device Type" "HOLE315R138"
			(at 0 -8.5852 0)
			(unlocked yes)
			(layer "F.Fab")
			(hide yes)
			(effects
				(font
					(size 1.016 1.016)
					(thickness 0.1524)
				)
			)
		)
		(duplicate_pad_numbers_are_jumpers no)
		(fp_poly
			(pts
				(xy 0 4.3053) (xy -0.13462 4.30276) (xy -0.27051 4.29641) (xy -0.40513 4.28625) (xy -0.53975 4.27101)
				(xy -0.6731 4.25196) (xy -0.80645 4.2291) (xy -0.9398 4.20116) (xy -1.07061 4.17068) (xy -1.20142 4.13385)
				(xy -1.33096 4.09448) (xy -1.45796 4.0513) (xy -1.58496 4.00304) (xy -1.70942 3.95097) (xy -1.83261 3.89509)
				(xy -1.95453 3.83667) (xy -2.07391 3.77317) (xy -2.19202 3.70586) (xy -2.30632 3.63474) (xy -2.41935 3.56108)
				(xy -2.53111 3.48361) (xy -2.63906 3.40233) (xy -2.74447 3.31724) (xy -2.84734 3.22961) (xy -2.94767 3.13817)
				(xy -3.04419 3.04419) (xy -3.13817 2.94767) (xy -3.22961 2.84734) (xy -3.31724 2.74447) (xy -3.40233 2.63906)
				(xy -3.48361 2.53111) (xy -3.56108 2.41935) (xy -3.63474 2.30632) (xy -3.70586 2.19202) (xy -3.77317 2.07391)
				(xy -3.83667 1.95453) (xy -3.89509 1.83261) (xy -3.95097 1.70942) (xy -4.00304 1.58496) (xy -4.0513 1.45796)
				(xy -4.09448 1.33096) (xy -4.13385 1.20142) (xy -4.17068 1.07061) (xy -4.20116 0.9398) (xy -4.2291 0.80645)
				(xy -4.25196 0.6731) (xy -4.27101 0.53975) (xy -4.28625 0.40513) (xy -4.29641 0.27051) (xy -4.30276 0.13462)
				(xy -4.3053 0) (xy -4.30276 -0.13462) (xy -4.29641 -0.27051) (xy -4.28625 -0.40513) (xy -4.27101 -0.53975)
				(xy -4.25196 -0.6731) (xy -4.2291 -0.80645) (xy -4.20116 -0.9398) (xy -4.17068 -1.07061) (xy -4.13385 -1.20142)
				(xy -4.09448 -1.33096) (xy -4.0513 -1.45796) (xy -4.00304 -1.58496) (xy -3.95097 -1.70942) (xy -3.89509 -1.83261)
				(xy -3.83667 -1.95453) (xy -3.77317 -2.07391) (xy -3.70586 -2.19202) (xy -3.63474 -2.30632) (xy -3.56108 -2.41935)
				(xy -3.48361 -2.53111) (xy -3.40233 -2.63906) (xy -3.31724 -2.74447) (xy -3.22961 -2.84734) (xy -3.13817 -2.94767)
				(xy -3.04419 -3.04419) (xy -2.94767 -3.13817) (xy -2.84734 -3.22961) (xy -2.74447 -3.31724) (xy -2.63906 -3.40233)
				(xy -2.53111 -3.48361) (xy -2.41935 -3.56108) (xy -2.30632 -3.63474) (xy -2.19202 -3.70586) (xy -2.07391 -3.77317)
				(xy -1.95453 -3.83667) (xy -1.83261 -3.89509) (xy -1.70942 -3.95097) (xy -1.58496 -4.00304) (xy -1.45796 -4.0513)
				(xy -1.33096 -4.09448) (xy -1.20142 -4.13385) (xy -1.07061 -4.17068) (xy -0.9398 -4.20116) (xy -0.80645 -4.2291)
				(xy -0.6731 -4.25196) (xy -0.53975 -4.27101) (xy -0.40513 -4.28625) (xy -0.27051 -4.29641) (xy -0.13462 -4.30276)
				(xy 0 -4.3053) (xy 0.13462 -4.30276) (xy 0.27051 -4.29641) (xy 0.40513 -4.28625) (xy 0.53975 -4.27101)
				(xy 0.6731 -4.25196) (xy 0.80645 -4.2291) (xy 0.9398 -4.20116) (xy 1.07061 -4.17068) (xy 1.20142 -4.13385)
				(xy 1.33096 -4.09448) (xy 1.45796 -4.0513) (xy 1.58496 -4.00304) (xy 1.70942 -3.95097) (xy 1.83261 -3.89509)
				(xy 1.95453 -3.83667) (xy 2.07391 -3.77317) (xy 2.19202 -3.70586) (xy 2.30632 -3.63474) (xy 2.41935 -3.56108)
				(xy 2.53111 -3.48361) (xy 2.63906 -3.40233) (xy 2.74447 -3.31724) (xy 2.84734 -3.22961) (xy 2.94767 -3.13817)
				(xy 3.04419 -3.04419) (xy 3.13817 -2.94767) (xy 3.22961 -2.84734) (xy 3.31724 -2.74447) (xy 3.40233 -2.63906)
				(xy 3.48361 -2.53111) (xy 3.56108 -2.41935) (xy 3.63474 -2.30632) (xy 3.70586 -2.19202) (xy 3.77317 -2.07391)
				(xy 3.83667 -1.95453) (xy 3.89509 -1.83261) (xy 3.95097 -1.70942) (xy 4.00304 -1.58496) (xy 4.0513 -1.45796)
				(xy 4.09448 -1.33096) (xy 4.13385 -1.20142) (xy 4.17068 -1.07061) (xy 4.20116 -0.9398) (xy 4.2291 -0.80645)
				(xy 4.25196 -0.6731) (xy 4.27101 -0.53975) (xy 4.28625 -0.40513) (xy 4.29641 -0.27051) (xy 4.30276 -0.13462)
				(xy 4.3053 0) (xy 4.30276 0.13462) (xy 4.29641 0.27051) (xy 4.28625 0.40513) (xy 4.27101 0.53975)
				(xy 4.25196 0.6731) (xy 4.2291 0.80645) (xy 4.20116 0.9398) (xy 4.17068 1.07061) (xy 4.13385 1.20142)
				(xy 4.09448 1.33096) (xy 4.0513 1.45796) (xy 4.00304 1.58496) (xy 3.95097 1.70942) (xy 3.89509 1.83261)
				(xy 3.83667 1.95453) (xy 3.77317 2.07391) (xy 3.70586 2.19202) (xy 3.63474 2.30632) (xy 3.56108 2.41935)
				(xy 3.48361 2.53111) (xy 3.40233 2.63906) (xy 3.31724 2.74447) (xy 3.22961 2.84734) (xy 3.13817 2.94767)
				(xy 3.04419 3.04419) (xy 2.94767 3.13817) (xy 2.84734 3.22961) (xy 2.74447 3.31724) (xy 2.63906 3.40233)
				(xy 2.53111 3.48361) (xy 2.41935 3.56108) (xy 2.30632 3.63474) (xy 2.19202 3.70586) (xy 2.07391 3.77317)
				(xy 1.95453 3.83667) (xy 1.83261 3.89509) (xy 1.70942 3.95097) (xy 1.58496 4.00304) (xy 1.45796 4.0513)
				(xy 1.33096 4.09448) (xy 1.20142 4.13385) (xy 1.07061 4.17068) (xy 0.9398 4.20116) (xy 0.80645 4.2291)
				(xy 0.6731 4.25196) (xy 0.53975 4.27101) (xy 0.40513 4.28625) (xy 0.27051 4.29641) (xy 0.13462 4.30276)
			)
			(stroke
				(width 0)
				(type default)
			)
			(fill no)
			(layer "F.CrtYd")
		)
		(fp_poly
			(pts
				(xy 0 4.3053) (xy -0.13462 4.30276) (xy -0.27051 4.29641) (xy -0.40513 4.28625) (xy -0.53975 4.27101)
				(xy -0.6731 4.25196) (xy -0.80645 4.2291) (xy -0.9398 4.20116) (xy -1.07061 4.17068) (xy -1.20142 4.13385)
				(xy -1.33096 4.09448) (xy -1.45796 4.0513) (xy -1.58496 4.00304) (xy -1.70942 3.95097) (xy -1.83261 3.89509)
				(xy -1.95453 3.83667) (xy -2.07391 3.77317) (xy -2.19202 3.70586) (xy -2.30632 3.63474) (xy -2.41935 3.56108)
				(xy -2.53111 3.48361) (xy -2.63906 3.40233) (xy -2.74447 3.31724) (xy -2.84734 3.22961) (xy -2.94767 3.13817)
				(xy -3.04419 3.04419) (xy -3.13817 2.94767) (xy -3.22961 2.84734) (xy -3.31724 2.74447) (xy -3.40233 2.63906)
				(xy -3.48361 2.53111) (xy -3.56108 2.41935) (xy -3.63474 2.30632) (xy -3.70586 2.19202) (xy -3.77317 2.07391)
				(xy -3.83667 1.95453) (xy -3.89509 1.83261) (xy -3.95097 1.70942) (xy -4.00304 1.58496) (xy -4.0513 1.45796)
				(xy -4.09448 1.33096) (xy -4.13385 1.20142) (xy -4.17068 1.07061) (xy -4.20116 0.9398) (xy -4.2291 0.80645)
				(xy -4.25196 0.6731) (xy -4.27101 0.53975) (xy -4.28625 0.40513) (xy -4.29641 0.27051) (xy -4.30276 0.13462)
				(xy -4.3053 0) (xy -4.30276 -0.13462) (xy -4.29641 -0.27051) (xy -4.28625 -0.40513) (xy -4.27101 -0.53975)
				(xy -4.25196 -0.6731) (xy -4.2291 -0.80645) (xy -4.20116 -0.9398) (xy -4.17068 -1.07061) (xy -4.13385 -1.20142)
				(xy -4.09448 -1.33096) (xy -4.0513 -1.45796) (xy -4.00304 -1.58496) (xy -3.95097 -1.70942) (xy -3.89509 -1.83261)
				(xy -3.83667 -1.95453) (xy -3.77317 -2.07391) (xy -3.70586 -2.19202) (xy -3.63474 -2.30632) (xy -3.56108 -2.41935)
				(xy -3.48361 -2.53111) (xy -3.40233 -2.63906) (xy -3.31724 -2.74447) (xy -3.22961 -2.84734) (xy -3.13817 -2.94767)
				(xy -3.04419 -3.04419) (xy -2.94767 -3.13817) (xy -2.84734 -3.22961) (xy -2.74447 -3.31724) (xy -2.63906 -3.40233)
				(xy -2.53111 -3.48361) (xy -2.41935 -3.56108) (xy -2.30632 -3.63474) (xy -2.19202 -3.70586) (xy -2.07391 -3.77317)
				(xy -1.95453 -3.83667) (xy -1.83261 -3.89509) (xy -1.70942 -3.95097) (xy -1.58496 -4.00304) (xy -1.45796 -4.0513)
				(xy -1.33096 -4.09448) (xy -1.20142 -4.13385) (xy -1.07061 -4.17068) (xy -0.9398 -4.20116) (xy -0.80645 -4.2291)
				(xy -0.6731 -4.25196) (xy -0.53975 -4.27101) (xy -0.40513 -4.28625) (xy -0.27051 -4.29641) (xy -0.13462 -4.30276)
				(xy 0 -4.3053) (xy 0.13462 -4.30276) (xy 0.27051 -4.29641) (xy 0.40513 -4.28625) (xy 0.53975 -4.27101)
				(xy 0.6731 -4.25196) (xy 0.80645 -4.2291) (xy 0.9398 -4.20116) (xy 1.07061 -4.17068) (xy 1.20142 -4.13385)
				(xy 1.33096 -4.09448) (xy 1.45796 -4.0513) (xy 1.58496 -4.00304) (xy 1.70942 -3.95097) (xy 1.83261 -3.89509)
				(xy 1.95453 -3.83667) (xy 2.07391 -3.77317) (xy 2.19202 -3.70586) (xy 2.30632 -3.63474) (xy 2.41935 -3.56108)
				(xy 2.53111 -3.48361) (xy 2.63906 -3.40233) (xy 2.74447 -3.31724) (xy 2.84734 -3.22961) (xy 2.94767 -3.13817)
				(xy 3.04419 -3.04419) (xy 3.13817 -2.94767) (xy 3.22961 -2.84734) (xy 3.31724 -2.74447) (xy 3.40233 -2.63906)
				(xy 3.48361 -2.53111) (xy 3.56108 -2.41935) (xy 3.63474 -2.30632) (xy 3.70586 -2.19202) (xy 3.77317 -2.07391)
				(xy 3.83667 -1.95453) (xy 3.89509 -1.83261) (xy 3.95097 -1.70942) (xy 4.00304 -1.58496) (xy 4.0513 -1.45796)
				(xy 4.09448 -1.33096) (xy 4.13385 -1.20142) (xy 4.17068 -1.07061) (xy 4.20116 -0.9398) (xy 4.2291 -0.80645)
				(xy 4.25196 -0.6731) (xy 4.27101 -0.53975) (xy 4.28625 -0.40513) (xy 4.29641 -0.27051) (xy 4.30276 -0.13462)
				(xy 4.3053 0) (xy 4.30276 0.13462) (xy 4.29641 0.27051) (xy 4.28625 0.40513) (xy 4.27101 0.53975)
				(xy 4.25196 0.6731) (xy 4.2291 0.80645) (xy 4.20116 0.9398) (xy 4.17068 1.07061) (xy 4.13385 1.20142)
				(xy 4.09448 1.33096) (xy 4.0513 1.45796) (xy 4.00304 1.58496) (xy 3.95097 1.70942) (xy 3.89509 1.83261)
				(xy 3.83667 1.95453) (xy 3.77317 2.07391) (xy 3.70586 2.19202) (xy 3.63474 2.30632) (xy 3.56108 2.41935)
				(xy 3.48361 2.53111) (xy 3.40233 2.63906) (xy 3.31724 2.74447) (xy 3.22961 2.84734) (xy 3.13817 2.94767)
				(xy 3.04419 3.04419) (xy 2.94767 3.13817) (xy 2.84734 3.22961) (xy 2.74447 3.31724) (xy 2.63906 3.40233)
				(xy 2.53111 3.48361) (xy 2.41935 3.56108) (xy 2.30632 3.63474) (xy 2.19202 3.70586) (xy 2.07391 3.77317)
				(xy 1.95453 3.83667) (xy 1.83261 3.89509) (xy 1.70942 3.95097) (xy 1.58496 4.00304) (xy 1.45796 4.0513)
				(xy 1.33096 4.09448) (xy 1.20142 4.13385) (xy 1.07061 4.17068) (xy 0.9398 4.20116) (xy 0.80645 4.2291)
				(xy 0.6731 4.25196) (xy 0.53975 4.27101) (xy 0.40513 4.28625) (xy 0.27051 4.29641) (xy 0.13462 4.30276)
			)
			(stroke
				(width 0)
				(type default)
			)
			(fill no)
			(layer "F.Fab")
		)
		(pad "1" thru_hole circle
			(at 0 0)
			(size 8.001 8.001)
			(drill 3.5052)
			(layers "*.Cu" "*.Mask")
			(remove_unused_layers no)
			(net "GND")
			(clearance -1.7399)
			(thermal_gap 0.3048)
			(padstack
				(mode front_inner_back)
				(layer "Inner"
					(shape circle)
					(size 3.9116 3.9116)
					(clearance 0.3048)
				)
				(layer "B.Cu"
					(shape circle)
					(size 8.001 8.001)
					(clearance -1.7399)
				)
			)
		)
	)
	(footprint ""
		(layer "F.Cu")
		(at 24.8666 -136.6012 90)
		(property "Reference" "PC89"
			(at 0 0 90)
			(layer "F.SilkS")
			(hide yes)
			(effects
				(font
					(size 1.27 1.27)
				)
			)
		)
		(property "Value" "SCD1U25V2KX-GP"
			(at 1.1811 -2.7051 90)
			(unlocked yes)
			(layer "F.Fab")
			(hide yes)
			(effects
				(font
					(size 1.016 1.016)
					(thickness 0.1524)
				)
			)
		)
		(property "Device Type" "C402H22"
			(at 1.1811 -4.2291 90)
			(unlocked yes)
			(layer "F.Fab")
			(hide yes)
			(effects
				(font
					(size 1.016 1.016)
					(thickness 0.1524)
				)
			)
		)
		(duplicate_pad_numbers_are_jumpers no)
		(fp_rect
			(start -0.4318 0.9525)
			(end 0.4318 -0.9525)
			(stroke
				(width 0)
				(type default)
			)
			(fill no)
			(layer "F.CrtYd")
		)
		(fp_rect
			(start -0.4318 0.9525)
			(end 0.4318 -0.9525)
			(stroke
				(width 0)
				(type default)
			)
			(fill no)
			(layer "F.Fab")
		)
		(pad "1" smd custom
			(at 0 -0.4445 90)
			(size 0.1524 0.1524)
			(layers "F.Cu" "F.Mask" "F.Paste")
			(net "P12VU_2490_VCC")
			(options
				(clearance outline)
				(anchor circle)
			)
			(primitives
				(gr_poly
					(pts
						(arc
							(start 0.3048 -0.2032)
							(mid 0.275042 -0.275042)
							(end 0.2032 -0.3048)
						)
						(arc
							(start -0.2032 -0.3048)
							(mid -0.275042 -0.275042)
							(end -0.3048 -0.2032)
						)
						(arc
							(start -0.3048 0.2032)
							(mid -0.275042 0.275042)
							(end -0.2032 0.3048)
						)
						(arc
							(start 0.2032 0.3048)
							(mid 0.275042 0.275042)
							(end 0.3048 0.2032)
						)
					)
					(width 0)
					(fill yes)
				)
			)
		)
		(pad "2" smd custom
			(at 0 0.4445 90)
			(size 0.1524 0.1524)
			(layers "F.Cu" "F.Mask" "F.Paste")
			(net "GND")
			(options
				(clearance outline)
				(anchor circle)
			)
			(primitives
				(gr_poly
					(pts
						(arc
							(start 0.3048 -0.2032)
							(mid 0.275042 -0.275042)
							(end 0.2032 -0.3048)
						)
						(arc
							(start -0.2032 -0.3048)
							(mid -0.275042 -0.275042)
							(end -0.3048 -0.2032)
						)
						(arc
							(start -0.3048 0.2032)
							(mid -0.275042 0.275042)
							(end -0.2032 0.3048)
						)
						(arc
							(start 0.2032 0.3048)
							(mid 0.275042 0.275042)
							(end 0.3048 0.2032)
						)
					)
					(width 0)
					(fill yes)
				)
			)
		)
	)
	(footprint ""
		(layer "F.Cu")
		(at 45.83811 -160.825434)
		(property "Reference" "C6"
			(at 0 0 0)
			(layer "F.SilkS")
			(hide yes)
			(effects
				(font
					(size 1.27 1.27)
				)
			)
		)
		(property "Value" "SC4D7U6D3V2MX-GP-U"
			(at -1.524 -1.905 0)
			(unlocked yes)
			(layer "F.Fab")
			(hide yes)
			(effects
				(font
					(size 1.016 1.016)
					(thickness 0.1524)
				)
			)
		)
		(property "Device Type" "C402-TO0D2H26"
			(at -1.524 -3.429 0)
			(unlocked yes)
			(layer "F.Fab")
			(hide yes)
			(effects
				(font
					(size 1.016 1.016)
					(thickness 0.1524)
				)
			)
		)
		(duplicate_pad_numbers_are_jumpers no)
		(fp_rect
			(start -0.4826 0.889)
			(end 0.4826 -0.889)
			(stroke
				(width 0)
				(type default)
			)
			(fill no)
			(layer "F.CrtYd")
		)
		(fp_rect
			(start -0.4826 0.889)
			(end 0.4826 -0.889)
			(stroke
				(width 0)
				(type default)
			)
			(fill no)
			(layer "F.Fab")
		)
		(pad "1" smd custom
			(at 0 -0.4572)
			(size 0.1524 0.1524)
			(layers "F.Cu" "F.Mask" "F.Paste")
			(net "P3V3")
			(options
				(clearance outline)
				(anchor circle)
			)
			(primitives
				(gr_poly
					(pts
						(arc
							(start -0.254 0.3048)
							(mid -0.325842 0.275042)
							(end -0.3556 0.2032)
						)
						(arc
							(start -0.3556 -0.2032)
							(mid -0.325842 -0.275042)
							(end -0.254 -0.3048)
						)
						(arc
							(start 0.254 -0.3048)
							(mid 0.325842 -0.275042)
							(end 0.3556 -0.2032)
						)
						(arc
							(start 0.3556 0.2032)
							(mid 0.325842 0.275042)
							(end 0.254 0.3048)
						)
					)
					(width 0)
					(fill yes)
				)
			)
		)
		(pad "2" smd custom
			(at 0 0.4572)
			(size 0.1524 0.1524)
			(layers "F.Cu" "F.Mask" "F.Paste")
			(net "GND")
			(options
				(clearance outline)
				(anchor circle)
			)
			(primitives
				(gr_poly
					(pts
						(arc
							(start -0.254 0.3048)
							(mid -0.325842 0.275042)
							(end -0.3556 0.2032)
						)
						(arc
							(start -0.3556 -0.2032)
							(mid -0.325842 -0.275042)
							(end -0.254 -0.3048)
						)
						(arc
							(start 0.254 -0.3048)
							(mid 0.325842 -0.275042)
							(end 0.3556 -0.2032)
						)
						(arc
							(start 0.3556 0.2032)
							(mid 0.325842 0.275042)
							(end 0.254 0.3048)
						)
					)
					(width 0)
					(fill yes)
				)
			)
		)
	)
	(footprint ""
		(layer "F.Cu")
		(at 20.6756 -135.1788)
		(property "Reference" "PR95"
			(at 0 0 0)
			(layer "F.SilkS")
			(hide yes)
			(effects
				(font
					(size 1.27 1.27)
				)
			)
		)
		(property "Value" "0R2J-2-GP"
			(at 0.064008 -3.993896 0)
			(unlocked yes)
			(layer "F.Fab")
			(hide yes)
			(effects
				(font
					(size 1.016 1.016)
					(thickness 0.1524)
				)
			)
		)
		(property "Device Type" "R402H16"
			(at 0.064008 -5.517896 0)
			(unlocked yes)
			(layer "F.Fab")
			(hide yes)
			(effects
				(font
					(size 1.016 1.016)
					(thickness 0.1524)
				)
			)
		)
		(duplicate_pad_numbers_are_jumpers no)
		(fp_line
			(start -0.508 -0.9398)
			(end -0.508 0.9398)
			(stroke
				(width 0.1524)
				(type default)
			)
			(layer "F.SilkS")
		)
		(fp_line
			(start 0.508 -0.9398)
			(end -0.508 -0.9398)
			(stroke
				(width 0.1524)
				(type default)
			)
			(layer "F.SilkS")
		)
		(fp_rect
			(start -0.508 0.9398)
			(end 0.508 -0.9398)
			(stroke
				(width 0)
				(type default)
			)
			(fill no)
			(layer "F.CrtYd")
		)
		(fp_rect
			(start -0.508 0.9398)
			(end 0.508 -0.9398)
			(stroke
				(width 0)
				(type default)
			)
			(fill no)
			(layer "F.Fab")
		)
		(pad "1" smd custom
			(at 0 -0.4445)
			(size 0.1397 0.1397)
			(layers "F.Cu" "F.Mask" "F.Paste")
			(net "P12VU_2490_SENSE")
			(options
				(clearance outline)
				(anchor circle)
			)
			(primitives
				(gr_poly
					(pts
						(arc
							(start -0.1778 -0.2794)
							(mid -0.249642 -0.249642)
							(end -0.2794 -0.1778)
						)
						(arc
							(start -0.2794 0.1778)
							(mid -0.249642 0.249642)
							(end -0.1778 0.2794)
						)
						(arc
							(start 0.1778 0.2794)
							(mid 0.249642 0.249642)
							(end 0.2794 0.1778)
						)
						(arc
							(start 0.2794 -0.1778)
							(mid 0.249642 -0.249642)
							(end 0.1778 -0.2794)
						)
					)
					(width 0)
					(fill yes)
				)
			)
		)
		(pad "2" smd custom
			(at 0 0.4445)
			(size 0.1397 0.1397)
			(layers "F.Cu" "F.Mask" "F.Paste")
			(net "P12VU_NET")
			(options
				(clearance outline)
				(anchor circle)
			)
			(primitives
				(gr_poly
					(pts
						(arc
							(start -0.1778 -0.2794)
							(mid -0.249642 -0.249642)
							(end -0.2794 -0.1778)
						)
						(arc
							(start -0.2794 0.1778)
							(mid -0.249642 0.249642)
							(end -0.1778 0.2794)
						)
						(arc
							(start 0.1778 0.2794)
							(mid 0.249642 0.249642)
							(end 0.2794 0.1778)
						)
						(arc
							(start 0.2794 -0.1778)
							(mid 0.249642 -0.249642)
							(end 0.1778 -0.2794)
						)
					)
					(width 0)
					(fill yes)
				)
			)
		)
	)
	(footprint ""
		(layer "B.Cu")
		(at 45.449998 -337.49996 90)
		(property "Reference" "H13"
			(at 0 0 90)
			(layer "B.SilkS")
			(hide yes)
			(effects
				(font
					(size 1.27 1.27)
				)
				(justify mirror)
			)
		)
		(property "Value" "STF375R199H50-GP"
			(at 6.124702 -0.033274 90)
			(unlocked yes)
			(layer "B.Fab")
			(hide yes)
			(effects
				(font
					(size 1.016 1.016)
					(thickness 0.1524)
				)
				(justify mirror)
			)
		)
		(property "Device Type" "STF375R199H50"
			(at 6.124702 -1.557274 90)
			(unlocked yes)
			(layer "B.Fab")
			(hide yes)
			(effects
				(font
					(size 1.016 1.016)
					(thickness 0.1524)
				)
				(justify mirror)
			)
		)
		(duplicate_pad_numbers_are_jumpers no)
		(fp_circle
			(center 0 0)
			(end 0 5.1181)
			(stroke
				(width 0.3048)
				(type default)
			)
			(fill no)
			(layer "B.SilkS")
		)
		(fp_poly
			(pts
				(arc
					(start -4.0005 0)
					(mid 4.0005 0)
					(end -4.0005 0)
				)
			)
			(stroke
				(width 0)
				(type default)
			)
			(fill no)
			(layer "B.CrtYd")
		)
		(fp_poly
			(pts
				(arc
					(start -5.2705 0.00254)
					(mid 5.270501 0)
					(end -5.2705 -0.00254)
				)
				(arc
					(start -4.0005 -0.00254)
					(mid 4.000501 0)
					(end -4.0005 0.00254)
				)
			)
			(stroke
				(width 0)
				(type default)
			)
			(fill no)
			(layer "B.CrtYd")
		)
		(fp_poly
			(pts
				(arc
					(start -5.2705 0)
					(mid 5.2705 0)
					(end -5.2705 0)
				)
			)
			(stroke
				(width 0)
				(type default)
			)
			(fill no)
			(layer "F.CrtYd")
		)
		(fp_poly
			(pts
				(arc
					(start -5.2705 0)
					(mid 5.2705 0)
					(end -5.2705 0)
				)
			)
			(stroke
				(width 0)
				(type default)
			)
			(fill no)
			(layer "B.Fab")
		)
		(fp_poly
			(pts
				(arc
					(start -5.2705 0)
					(mid 5.2705 0)
					(end -5.2705 0)
				)
			)
			(stroke
				(width 0)
				(type default)
			)
			(fill no)
			(layer "F.Fab")
		)
		(pad "1" thru_hole circle
			(at 0 0 270)
			(size 9.525 9.525)
			(drill 5.0546)
			(layers "*.Cu" "*.Mask")
			(remove_unused_layers no)
			(net "GND")
			(clearance -1.7272)
			(padstack
				(mode front_inner_back)
				(layer "Inner"
					(shape circle)
					(size 5.461 5.461)
					(clearance 0.3048)
				)
				(layer "B.Cu"
					(shape circle)
					(size 9.525 9.525)
					(thermal_gap 0.3048)
					(clearance -1.7272)
				)
			)
		)
	)
	(footprint ""
		(layer "B.Cu")
		(at 40.999918 -463.049874 90)
		(property "Reference" "H11"
			(at 0 0 90)
			(layer "B.SilkS")
			(hide yes)
			(effects
				(font
					(size 1.27 1.27)
				)
				(justify mirror)
			)
		)
		(property "Value" "STF375R199H50-GP"
			(at 6.124702 -0.033274 90)
			(unlocked yes)
			(layer "B.Fab")
			(hide yes)
			(effects
				(font
					(size 1.016 1.016)
					(thickness 0.1524)
				)
				(justify mirror)
			)
		)
		(property "Device Type" "STF375R199H50"
			(at 6.124702 -1.557274 90)
			(unlocked yes)
			(layer "B.Fab")
			(hide yes)
			(effects
				(font
					(size 1.016 1.016)
					(thickness 0.1524)
				)
				(justify mirror)
			)
		)
		(duplicate_pad_numbers_are_jumpers no)
		(fp_circle
			(center 0 0)
			(end 0 5.1181)
			(stroke
				(width 0.3048)
				(type default)
			)
			(fill no)
			(layer "B.SilkS")
		)
		(fp_poly
			(pts
				(arc
					(start 0 4.0005)
					(mid 0 -4.0005)
					(end 0 4.0005)
				)
			)
			(stroke
				(width 0)
				(type default)
			)
			(fill no)
			(layer "B.CrtYd")
		)
		(fp_poly
			(pts
				(arc
					(start -5.2705 0.00254)
					(mid 5.270501 0)
					(end -5.2705 -0.00254)
				)
				(arc
					(start -4.0005 -0.00254)
					(mid 4.000501 0)
					(end -4.0005 0.00254)
				)
			)
			(stroke
				(width 0)
				(type default)
			)
			(fill no)
			(layer "B.CrtYd")
		)
		(fp_poly
			(pts
				(arc
					(start 0 5.2705)
					(mid 0 -5.2705)
					(end 0 5.2705)
				)
			)
			(stroke
				(width 0)
				(type default)
			)
			(fill no)
			(layer "F.CrtYd")
		)
		(fp_poly
			(pts
				(arc
					(start 0 5.2705)
					(mid 0 -5.2705)
					(end 0 5.2705)
				)
			)
			(stroke
				(width 0)
				(type default)
			)
			(fill no)
			(layer "B.Fab")
		)
		(fp_poly
			(pts
				(arc
					(start 0 5.2705)
					(mid 0 -5.2705)
					(end 0 5.2705)
				)
			)
			(stroke
				(width 0)
				(type default)
			)
			(fill no)
			(layer "F.Fab")
		)
		(pad "1" thru_hole circle
			(at 0 0 270)
			(size 9.525 9.525)
			(drill 5.0546)
			(layers "*.Cu" "*.Mask")
			(remove_unused_layers no)
			(net "GND")
			(clearance -1.7272)
			(padstack
				(mode front_inner_back)
				(layer "Inner"
					(shape circle)
					(size 5.461 5.461)
					(clearance 0.3048)
				)
				(layer "B.Cu"
					(shape circle)
					(size 9.525 9.525)
					(thermal_gap 0.3048)
					(clearance -1.7272)
				)
			)
		)
	)
	(footprint ""
		(layer "B.Cu")
		(at 24.500078 -443.95009 90)
		(property "Reference" "H10"
			(at 0 0 90)
			(layer "B.SilkS")
			(hide yes)
			(effects
				(font
					(size 1.27 1.27)
				)
				(justify mirror)
			)
		)
		(property "Value" "STF375R199H50-GP"
			(at 6.124702 -0.033274 90)
			(unlocked yes)
			(layer "B.Fab")
			(hide yes)
			(effects
				(font
					(size 1.016 1.016)
					(thickness 0.1524)
				)
				(justify mirror)
			)
		)
		(property "Device Type" "STF375R199H50"
			(at 6.124702 -1.557274 90)
			(unlocked yes)
			(layer "B.Fab")
			(hide yes)
			(effects
				(font
					(size 1.016 1.016)
					(thickness 0.1524)
				)
				(justify mirror)
			)
		)
		(duplicate_pad_numbers_are_jumpers no)
		(fp_circle
			(center 0 0)
			(end 0 5.1181)
			(stroke
				(width 0.3048)
				(type default)
			)
			(fill no)
			(layer "B.SilkS")
		)
		(fp_poly
			(pts
				(arc
					(start 0 4.0005)
					(mid 0 -4.0005)
					(end 0 4.0005)
				)
			)
			(stroke
				(width 0)
				(type default)
			)
			(fill no)
			(layer "B.CrtYd")
		)
		(fp_poly
			(pts
				(arc
					(start -5.2705 0.00254)
					(mid 5.270501 0)
					(end -5.2705 -0.00254)
				)
				(arc
					(start -4.0005 -0.00254)
					(mid 4.000501 0)
					(end -4.0005 0.00254)
				)
			)
			(stroke
				(width 0)
				(type default)
			)
			(fill no)
			(layer "B.CrtYd")
		)
		(fp_poly
			(pts
				(arc
					(start 0 5.2705)
					(mid 0 -5.2705)
					(end 0 5.2705)
				)
			)
			(stroke
				(width 0)
				(type default)
			)
			(fill no)
			(layer "F.CrtYd")
		)
		(fp_poly
			(pts
				(arc
					(start 0 5.2705)
					(mid 0 -5.2705)
					(end 0 5.2705)
				)
			)
			(stroke
				(width 0)
				(type default)
			)
			(fill no)
			(layer "B.Fab")
		)
		(fp_poly
			(pts
				(arc
					(start 0 5.2705)
					(mid 0 -5.2705)
					(end 0 5.2705)
				)
			)
			(stroke
				(width 0)
				(type default)
			)
			(fill no)
			(layer "F.Fab")
		)
		(pad "1" thru_hole circle
			(at 0 0 270)
			(size 9.525 9.525)
			(drill 5.0546)
			(layers "*.Cu" "*.Mask")
			(remove_unused_layers no)
			(net "P12V_AUX")
			(clearance -1.7272)
			(padstack
				(mode front_inner_back)
				(layer "Inner"
					(shape circle)
					(size 5.461 5.461)
					(clearance 0.3048)
				)
				(layer "B.Cu"
					(shape circle)
					(size 9.525 9.525)
					(thermal_gap 0.3048)
					(clearance -1.7272)
				)
			)
		)
	)
	(footprint ""
		(layer "B.Cu")
		(at 40.999918 -443.95009 90)
		(property "Reference" "H12"
			(at 0 0 90)
			(layer "B.SilkS")
			(hide yes)
			(effects
				(font
					(size 1.27 1.27)
				)
				(justify mirror)
			)
		)
		(property "Value" "STF375R199H50-GP"
			(at 6.124702 -0.033274 90)
			(unlocked yes)
			(layer "B.Fab")
			(hide yes)
			(effects
				(font
					(size 1.016 1.016)
					(thickness 0.1524)
				)
				(justify mirror)
			)
		)
		(property "Device Type" "STF375R199H50"
			(at 6.124702 -1.557274 90)
			(unlocked yes)
			(layer "B.Fab")
			(hide yes)
			(effects
				(font
					(size 1.016 1.016)
					(thickness 0.1524)
				)
				(justify mirror)
			)
		)
		(duplicate_pad_numbers_are_jumpers no)
		(fp_circle
			(center 0 0)
			(end 0 5.1181)
			(stroke
				(width 0.3048)
				(type default)
			)
			(fill no)
			(layer "B.SilkS")
		)
		(fp_poly
			(pts
				(arc
					(start 0 4.0005)
					(mid 0 -4.0005)
					(end 0 4.0005)
				)
			)
			(stroke
				(width 0)
				(type default)
			)
			(fill no)
			(layer "B.CrtYd")
		)
		(fp_poly
			(pts
				(arc
					(start -5.2705 0.00254)
					(mid 5.270501 0)
					(end -5.2705 -0.00254)
				)
				(arc
					(start -4.0005 -0.00254)
					(mid 4.000501 0)
					(end -4.0005 0.00254)
				)
			)
			(stroke
				(width 0)
				(type default)
			)
			(fill no)
			(layer "B.CrtYd")
		)
		(fp_poly
			(pts
				(arc
					(start 0 5.2705)
					(mid 0 -5.2705)
					(end 0 5.2705)
				)
			)
			(stroke
				(width 0)
				(type default)
			)
			(fill no)
			(layer "F.CrtYd")
		)
		(fp_poly
			(pts
				(arc
					(start 0 5.2705)
					(mid 0 -5.2705)
					(end 0 5.2705)
				)
			)
			(stroke
				(width 0)
				(type default)
			)
			(fill no)
			(layer "B.Fab")
		)
		(fp_poly
			(pts
				(arc
					(start 0 5.2705)
					(mid 0 -5.2705)
					(end 0 5.2705)
				)
			)
			(stroke
				(width 0)
				(type default)
			)
			(fill no)
			(layer "F.Fab")
		)
		(pad "1" thru_hole circle
			(at 0 0 270)
			(size 9.525 9.525)
			(drill 5.0546)
			(layers "*.Cu" "*.Mask")
			(remove_unused_layers no)
			(net "GND")
			(clearance -1.7272)
			(padstack
				(mode front_inner_back)
				(layer "Inner"
					(shape circle)
					(size 5.461 5.461)
					(clearance 0.3048)
				)
				(layer "B.Cu"
					(shape circle)
					(size 9.525 9.525)
					(thermal_gap 0.3048)
					(clearance -1.7272)
				)
			)
		)
	)
	(footprint ""
		(layer "B.Cu")
		(at 24.500078 -463.049874 90)
		(property "Reference" "H9"
			(at 0 0 90)
			(layer "B.SilkS")
			(hide yes)
			(effects
				(font
					(size 1.27 1.27)
				)
				(justify mirror)
			)
		)
		(property "Value" "STF375R199H50-GP"
			(at 6.124702 -0.033274 90)
			(unlocked yes)
			(layer "B.Fab")
			(hide yes)
			(effects
				(font
					(size 1.016 1.016)
					(thickness 0.1524)
				)
				(justify mirror)
			)
		)
		(property "Device Type" "STF375R199H50"
			(at 6.124702 -1.557274 90)
			(unlocked yes)
			(layer "B.Fab")
			(hide yes)
			(effects
				(font
					(size 1.016 1.016)
					(thickness 0.1524)
				)
				(justify mirror)
			)
		)
		(duplicate_pad_numbers_are_jumpers no)
		(fp_circle
			(center 0 0)
			(end 0 5.1181)
			(stroke
				(width 0.3048)
				(type default)
			)
			(fill no)
			(layer "B.SilkS")
		)
		(fp_poly
			(pts
				(arc
					(start 0 4.0005)
					(mid 0 -4.0005)
					(end 0 4.0005)
				)
			)
			(stroke
				(width 0)
				(type default)
			)
			(fill no)
			(layer "B.CrtYd")
		)
		(fp_poly
			(pts
				(arc
					(start -5.2705 0.00254)
					(mid 5.270501 0)
					(end -5.2705 -0.00254)
				)
				(arc
					(start -4.0005 -0.00254)
					(mid 4.000501 0)
					(end -4.0005 0.00254)
				)
			)
			(stroke
				(width 0)
				(type default)
			)
			(fill no)
			(layer "B.CrtYd")
		)
		(fp_poly
			(pts
				(arc
					(start 0 5.2705)
					(mid 0 -5.2705)
					(end 0 5.2705)
				)
			)
			(stroke
				(width 0)
				(type default)
			)
			(fill no)
			(layer "F.CrtYd")
		)
		(fp_poly
			(pts
				(arc
					(start 0 5.2705)
					(mid 0 -5.2705)
					(end 0 5.2705)
				)
			)
			(stroke
				(width 0)
				(type default)
			)
			(fill no)
			(layer "B.Fab")
		)
		(fp_poly
			(pts
				(arc
					(start 0 5.2705)
					(mid 0 -5.2705)
					(end 0 5.2705)
				)
			)
			(stroke
				(width 0)
				(type default)
			)
			(fill no)
			(layer "F.Fab")
		)
		(pad "1" thru_hole circle
			(at 0 0 270)
			(size 9.525 9.525)
			(drill 5.0546)
			(layers "*.Cu" "*.Mask")
			(remove_unused_layers no)
			(net "P12V_AUX")
			(clearance -1.7272)
			(padstack
				(mode front_inner_back)
				(layer "Inner"
					(shape circle)
					(size 5.461 5.461)
					(clearance 0.3048)
				)
				(layer "B.Cu"
					(shape circle)
					(size 9.525 9.525)
					(thermal_gap 0.3048)
					(clearance -1.7272)
				)
			)
		)
	)
	(gr_line
		(start 0 -499.000018)
		(end 0 -0.999998)
		(stroke
			(width 1.524)
			(type default)
		)
		(layer "In1.Cu")
	)
	(gr_arc
		(start 0 -499.000018)
		(mid 0.292892 -499.707125)
		(end 0.999998 -500.000016)
		(stroke
			(width 1.524)
			(type default)
		)
		(layer "In1.Cu")
	)
	(gr_arc
		(start 0.999998 0)
		(mid 0.292893 -0.292893)
		(end 0 -0.999998)
		(stroke
			(width 1.524)
			(type default)
		)
		(layer "In1.Cu")
	)
	(gr_line
		(start 0.999998 0)
		(end 16.500094 0)
		(stroke
			(width 1.524)
			(type default)
		)
		(layer "In1.Cu")
	)
	(gr_line
		(start 16.500094 -500.000016)
		(end 0.999998 -500.000016)
		(stroke
			(width 1.524)
			(type default)
		)
		(layer "In1.Cu")
	)
	(gr_arc
		(start 16.500094 -500.000016)
		(mid 17.20721 -499.707127)
		(end 17.500092 -499.000018)
		(stroke
			(width 1.524)
			(type default)
		)
		(layer "In1.Cu")
	)
	(gr_line
		(start 17.500092 -491.000034)
		(end 17.500092 -499.000018)
		(stroke
			(width 1.524)
			(type default)
		)
		(layer "In1.Cu")
	)
	(gr_arc
		(start 17.500092 -8.999982)
		(mid 17.792985 -9.707087)
		(end 18.50009 -9.99998)
		(stroke
			(width 1.524)
			(type default)
		)
		(layer "In1.Cu")
	)
	(gr_arc
		(start 17.500092 -0.999998)
		(mid 17.207198 -0.292896)
		(end 16.500094 0)
		(stroke
			(width 1.524)
			(type default)
		)
		(layer "In1.Cu")
	)
	(gr_line
		(start 17.500092 -0.999998)
		(end 17.500092 -8.999982)
		(stroke
			(width 1.524)
			(type default)
		)
		(layer "In1.Cu")
	)
	(gr_arc
		(start 18.50009 -490.000036)
		(mid 17.792985 -490.292929)
		(end 17.500092 -491.000034)
		(stroke
			(width 1.524)
			(type default)
		)
		(layer "In1.Cu")
	)
	(gr_line
		(start 18.50009 -9.99998)
		(end 51.500024 -9.99998)
		(stroke
			(width 1.524)
			(type default)
		)
		(layer "In1.Cu")
	)
	(gr_line
		(start 21.082 -489.458)
		(end 21.082 -470.154)
		(stroke
			(width 0.381)
			(type default)
		)
		(layer "In1.Cu")
	)
	(gr_line
		(start 21.082 -470.154)
		(end 21.463 -469.773)
		(stroke
			(width 0.381)
			(type default)
		)
		(layer "In1.Cu")
	)
	(gr_line
		(start 21.463 -469.773)
		(end 21.971 -469.773)
		(stroke
			(width 0.381)
			(type default)
		)
		(layer "In1.Cu")
	)
	(gr_line
		(start 21.971 -469.773)
		(end 22.479 -470.281)
		(stroke
			(width 0.381)
			(type default)
		)
		(layer "In1.Cu")
	)
	(gr_line
		(start 22.479 -470.281)
		(end 22.479 -489.458)
		(stroke
			(width 0.381)
			(type default)
		)
		(layer "In1.Cu")
	)
	(gr_line
		(start 51.500024 -490.000036)
		(end 18.50009 -490.000036)
		(stroke
			(width 1.524)
			(type default)
		)
		(layer "In1.Cu")
	)
	(gr_arc
		(start 51.500024 -490.000036)
		(mid 52.207127 -489.707137)
		(end 52.500022 -489.000038)
		(stroke
			(width 1.524)
			(type default)
		)
		(layer "In1.Cu")
	)
	(gr_arc
		(start 52.500022 -10.999978)
		(mid 52.207123 -10.292878)
		(end 51.500024 -9.99998)
		(stroke
			(width 1.524)
			(type default)
		)
		(layer "In1.Cu")
	)
	(gr_line
		(start 52.500022 -10.999978)
		(end 52.500022 -489.000038)
		(stroke
			(width 1.524)
			(type default)
		)
		(layer "In1.Cu")
	)
	(gr_line
		(start 0 -499.000018)
		(end 0 -0.999998)
		(stroke
			(width 1.524)
			(type default)
		)
		(layer "In2.Cu")
	)
	(gr_arc
		(start 0 -499.000018)
		(mid 0.292892 -499.707125)
		(end 0.999998 -500.000016)
		(stroke
			(width 1.524)
			(type default)
		)
		(layer "In2.Cu")
	)
	(gr_arc
		(start 0.999998 0)
		(mid 0.292893 -0.292893)
		(end 0 -0.999998)
		(stroke
			(width 1.524)
			(type default)
		)
		(layer "In2.Cu")
	)
	(gr_line
		(start 0.999998 0)
		(end 16.500094 0)
		(stroke
			(width 1.524)
			(type default)
		)
		(layer "In2.Cu")
	)
	(gr_line
		(start 9.652 -110.744)
		(end 11.811 -112.903)
		(stroke
			(width 0.381)
			(type default)
		)
		(layer "In2.Cu")
	)
	(gr_line
		(start 9.652 -72.898)
		(end 9.652 -110.744)
		(stroke
			(width 0.381)
			(type default)
		)
		(layer "In2.Cu")
	)
	(gr_line
		(start 10.16 -120.269)
		(end 11.43 -121.539)
		(stroke
			(width 0.381)
			(type default)
		)
		(layer "In2.Cu")
	)
	(gr_line
		(start 10.16 -114.554)
		(end 10.16 -120.269)
		(stroke
			(width 0.381)
			(type default)
		)
		(layer "In2.Cu")
	)
	(gr_line
		(start 10.414 -72.136)
		(end 9.652 -72.898)
		(stroke
			(width 0.381)
			(type default)
		)
		(layer "In2.Cu")
	)
	(gr_line
		(start 11.43 -121.539)
		(end 25.654 -121.539)
		(stroke
			(width 0.381)
			(type default)
		)
		(layer "In2.Cu")
	)
	(gr_line
		(start 11.811 -112.903)
		(end 10.16 -114.554)
		(stroke
			(width 0.381)
			(type default)
		)
		(layer "In2.Cu")
	)
	(gr_line
		(start 12.319 -452.628)
		(end 12.319 -450.85)
		(stroke
			(width 0.381)
			(type default)
		)
		(layer "In2.Cu")
	)
	(gr_line
		(start 12.319 -450.85)
		(end 12.827 -450.342)
		(stroke
			(width 0.381)
			(type default)
		)
		(layer "In2.Cu")
	)
	(gr_line
		(start 12.446 -409.194)
		(end 12.446 -401.701)
		(stroke
			(width 0.381)
			(type default)
		)
		(layer "In2.Cu")
	)
	(gr_line
		(start 12.446 -401.701)
		(end 12.954 -401.193)
		(stroke
			(width 0.381)
			(type default)
		)
		(layer "In2.Cu")
	)
	(gr_line
		(start 12.827 -472.567)
		(end 12.827 -453.136)
		(stroke
			(width 0.381)
			(type default)
		)
		(layer "In2.Cu")
	)
	(gr_line
		(start 12.827 -453.136)
		(end 12.319 -452.628)
		(stroke
			(width 0.381)
			(type default)
		)
		(layer "In2.Cu")
	)
	(gr_line
		(start 12.827 -450.342)
		(end 12.827 -416.306)
		(stroke
			(width 0.381)
			(type default)
		)
		(layer "In2.Cu")
	)
	(gr_line
		(start 12.827 -416.306)
		(end 13.462 -415.671)
		(stroke
			(width 0.381)
			(type default)
		)
		(layer "In2.Cu")
	)
	(gr_line
		(start 12.954 -401.193)
		(end 46.863 -401.193)
		(stroke
			(width 0.381)
			(type default)
		)
		(layer "In2.Cu")
	)
	(gr_line
		(start 13.462 -415.671)
		(end 13.462 -410.845)
		(stroke
			(width 0.381)
			(type default)
		)
		(layer "In2.Cu")
	)
	(gr_line
		(start 13.462 -410.845)
		(end 13.716 -410.591)
		(stroke
			(width 0.381)
			(type default)
		)
		(layer "In2.Cu")
	)
	(gr_line
		(start 13.843 -410.591)
		(end 12.446 -409.194)
		(stroke
			(width 0.381)
			(type default)
		)
		(layer "In2.Cu")
	)
	(gr_line
		(start 15.875 -475.615)
		(end 12.827 -472.567)
		(stroke
			(width 0.381)
			(type default)
		)
		(layer "In2.Cu")
	)
	(gr_line
		(start 16.500094 -500.000016)
		(end 0.999998 -500.000016)
		(stroke
			(width 1.524)
			(type default)
		)
		(layer "In2.Cu")
	)
	(gr_arc
		(start 16.500094 -500.000016)
		(mid 17.20721 -499.707127)
		(end 17.500092 -499.000018)
		(stroke
			(width 1.524)
			(type default)
		)
		(layer "In2.Cu")
	)
	(gr_line
		(start 17.399 -72.136)
		(end 10.414 -72.136)
		(stroke
			(width 0.381)
			(type default)
		)
		(layer "In2.Cu")
	)
	(gr_line
		(start 17.500092 -491.000034)
		(end 17.500092 -499.000018)
		(stroke
			(width 1.524)
			(type default)
		)
		(layer "In2.Cu")
	)
	(gr_arc
		(start 17.500092 -8.999982)
		(mid 17.792985 -9.707087)
		(end 18.50009 -9.99998)
		(stroke
			(width 1.524)
			(type default)
		)
		(layer "In2.Cu")
	)
	(gr_arc
		(start 17.500092 -0.999998)
		(mid 17.207198 -0.292896)
		(end 16.500094 0)
		(stroke
			(width 1.524)
			(type default)
		)
		(layer "In2.Cu")
	)
	(gr_line
		(start 17.500092 -0.999998)
		(end 17.500092 -8.999982)
		(stroke
			(width 1.524)
			(type default)
		)
		(layer "In2.Cu")
	)
	(gr_line
		(start 18.034 -71.501)
		(end 17.399 -72.136)
		(stroke
			(width 0.381)
			(type default)
		)
		(layer "In2.Cu")
	)
	(gr_line
		(start 18.034 -65.786)
		(end 18.034 -71.501)
		(stroke
			(width 0.381)
			(type default)
		)
		(layer "In2.Cu")
	)
	(gr_arc
		(start 18.50009 -490.000036)
		(mid 17.792985 -490.292929)
		(end 17.500092 -491.000034)
		(stroke
			(width 1.524)
			(type default)
		)
		(layer "In2.Cu")
	)
	(gr_line
		(start 18.50009 -9.99998)
		(end 51.500024 -9.99998)
		(stroke
			(width 1.524)
			(type default)
		)
		(layer "In2.Cu")
	)
	(gr_line
		(start 19.812 -64.008)
		(end 18.034 -65.786)
		(stroke
			(width 0.381)
			(type default)
		)
		(layer "In2.Cu")
	)
	(gr_line
		(start 21.971 -112.776)
		(end 21.971 -110.617)
		(stroke
			(width 0.381)
			(type default)
		)
		(layer "In2.Cu")
	)
	(gr_line
		(start 21.971 -110.617)
		(end 24.257 -108.331)
		(stroke
			(width 0.381)
			(type default)
		)
		(layer "In2.Cu")
	)
	(gr_line
		(start 23.622 -94.488)
		(end 23.622 -89.662)
		(stroke
			(width 0.381)
			(type default)
		)
		(layer "In2.Cu")
	)
	(gr_line
		(start 23.622 -89.662)
		(end 24.003 -89.281)
		(stroke
			(width 0.381)
			(type default)
		)
		(layer "In2.Cu")
	)
	(gr_line
		(start 24.003 -89.281)
		(end 24.511 -89.281)
		(stroke
			(width 0.381)
			(type default)
		)
		(layer "In2.Cu")
	)
	(gr_line
		(start 24.257 -108.331)
		(end 24.257 -95.123)
		(stroke
			(width 0.381)
			(type default)
		)
		(layer "In2.Cu")
	)
	(gr_line
		(start 24.257 -95.123)
		(end 23.622 -94.488)
		(stroke
			(width 0.381)
			(type default)
		)
		(layer "In2.Cu")
	)
	(gr_line
		(start 24.511 -89.281)
		(end 25.146 -88.646)
		(stroke
			(width 0.381)
			(type default)
		)
		(layer "In2.Cu")
	)
	(gr_line
		(start 25.146 -88.646)
		(end 25.146 -81.153)
		(stroke
			(width 0.381)
			(type default)
		)
		(layer "In2.Cu")
	)
	(gr_line
		(start 25.146 -81.153)
		(end 25.781 -80.518)
		(stroke
			(width 0.381)
			(type default)
		)
		(layer "In2.Cu")
	)
	(gr_line
		(start 25.654 -80.645)
		(end 30.099 -76.2)
		(stroke
			(width 0.381)
			(type default)
		)
		(layer "In2.Cu")
	)
	(gr_line
		(start 25.781 -80.518)
		(end 25.654 -80.645)
		(stroke
			(width 0.381)
			(type default)
		)
		(layer "In2.Cu")
	)
	(gr_line
		(start 25.908 -113.03)
		(end 30.226 -113.03)
		(stroke
			(width 0.381)
			(type default)
		)
		(layer "In2.Cu")
	)
	(gr_line
		(start 28.956 -109.22)
		(end 28.956 -95.631)
		(stroke
			(width 0.381)
			(type default)
		)
		(layer "In2.Cu")
	)
	(gr_line
		(start 28.956 -95.631)
		(end 29.718 -94.869)
		(stroke
			(width 0.381)
			(type default)
		)
		(layer "In2.Cu")
	)
	(gr_line
		(start 28.956 -89.154)
		(end 28.956 -79.756)
		(stroke
			(width 0.381)
			(type default)
		)
		(layer "In2.Cu")
	)
	(gr_line
		(start 28.956 -79.756)
		(end 35.433 -73.279)
		(stroke
			(width 0.381)
			(type default)
		)
		(layer "In2.Cu")
	)
	(gr_line
		(start 29.083 -64.008)
		(end 19.812 -64.008)
		(stroke
			(width 0.381)
			(type default)
		)
		(layer "In2.Cu")
	)
	(gr_line
		(start 29.718 -94.869)
		(end 29.718 -89.916)
		(stroke
			(width 0.381)
			(type default)
		)
		(layer "In2.Cu")
	)
	(gr_line
		(start 29.718 -89.916)
		(end 28.956 -89.154)
		(stroke
			(width 0.381)
			(type default)
		)
		(layer "In2.Cu")
	)
	(gr_line
		(start 30.099 -113.03)
		(end 11.684 -113.03)
		(stroke
			(width 0.381)
			(type default)
		)
		(layer "In2.Cu")
	)
	(gr_line
		(start 30.099 -76.2)
		(end 30.099 -65.024)
		(stroke
			(width 0.381)
			(type default)
		)
		(layer "In2.Cu")
	)
	(gr_line
		(start 30.099 -65.024)
		(end 29.083 -64.008)
		(stroke
			(width 0.381)
			(type default)
		)
		(layer "In2.Cu")
	)
	(gr_line
		(start 30.226 -113.03)
		(end 31.623 -114.427)
		(stroke
			(width 0.381)
			(type default)
		)
		(layer "In2.Cu")
	)
	(gr_line
		(start 30.48 -475.615)
		(end 15.875 -475.615)
		(stroke
			(width 0.381)
			(type default)
		)
		(layer "In2.Cu")
	)
	(gr_line
		(start 30.734 -121.539)
		(end 25.654 -121.539)
		(stroke
			(width 0.381)
			(type default)
		)
		(layer "In2.Cu")
	)
	(gr_line
		(start 31.623 -120.65)
		(end 30.734 -121.539)
		(stroke
			(width 0.381)
			(type default)
		)
		(layer "In2.Cu")
	)
	(gr_line
		(start 31.623 -114.427)
		(end 31.623 -120.65)
		(stroke
			(width 0.381)
			(type default)
		)
		(layer "In2.Cu")
	)
	(gr_line
		(start 32.512 -120.904)
		(end 32.893 -121.285)
		(stroke
			(width 0.381)
			(type default)
		)
		(layer "In2.Cu")
	)
	(gr_line
		(start 32.512 -113.284)
		(end 32.512 -120.904)
		(stroke
			(width 0.381)
			(type default)
		)
		(layer "In2.Cu")
	)
	(gr_line
		(start 32.766 -113.03)
		(end 28.956 -109.22)
		(stroke
			(width 0.381)
			(type default)
		)
		(layer "In2.Cu")
	)
	(gr_line
		(start 32.766 -113.03)
		(end 32.512 -113.284)
		(stroke
			(width 0.381)
			(type default)
		)
		(layer "In2.Cu")
	)
	(gr_line
		(start 32.893 -473.202)
		(end 30.48 -475.615)
		(stroke
			(width 0.381)
			(type default)
		)
		(layer "In2.Cu")
	)
	(gr_line
		(start 32.893 -425.704)
		(end 32.893 -473.202)
		(stroke
			(width 0.381)
			(type default)
		)
		(layer "In2.Cu")
	)
	(gr_line
		(start 32.893 -121.285)
		(end 51.308 -121.285)
		(stroke
			(width 0.381)
			(type default)
		)
		(layer "In2.Cu")
	)
	(gr_line
		(start 34.798 -423.799)
		(end 32.893 -425.704)
		(stroke
			(width 0.381)
			(type default)
		)
		(layer "In2.Cu")
	)
	(gr_line
		(start 35.433 -73.279)
		(end 35.433 -65.024)
		(stroke
			(width 0.381)
			(type default)
		)
		(layer "In2.Cu")
	)
	(gr_line
		(start 35.433 -65.024)
		(end 36.957 -63.5)
		(stroke
			(width 0.381)
			(type default)
		)
		(layer "In2.Cu")
	)
	(gr_line
		(start 36.957 -63.5)
		(end 46.863 -63.5)
		(stroke
			(width 0.381)
			(type default)
		)
		(layer "In2.Cu")
	)
	(gr_line
		(start 39.497 -113.03)
		(end 32.766 -113.03)
		(stroke
			(width 0.381)
			(type default)
		)
		(layer "In2.Cu")
	)
	(gr_line
		(start 45.085 -81.788)
		(end 45.085 -112.903)
		(stroke
			(width 0.381)
			(type default)
		)
		(layer "In2.Cu")
	)
	(gr_line
		(start 45.974 -410.591)
		(end 46.863 -410.591)
		(stroke
			(width 0.381)
			(type default)
		)
		(layer "In2.Cu")
	)
	(gr_line
		(start 46.736 -423.799)
		(end 34.798 -423.799)
		(stroke
			(width 0.381)
			(type default)
		)
		(layer "In2.Cu")
	)
	(gr_line
		(start 46.736 -410.591)
		(end 45.974 -410.591)
		(stroke
			(width 0.381)
			(type default)
		)
		(layer "In2.Cu")
	)
	(gr_line
		(start 46.863 -401.193)
		(end 47.752 -402.082)
		(stroke
			(width 0.381)
			(type default)
		)
		(layer "In2.Cu")
	)
	(gr_line
		(start 46.863 -63.5)
		(end 47.752 -64.389)
		(stroke
			(width 0.381)
			(type default)
		)
		(layer "In2.Cu")
	)
	(gr_line
		(start 46.99 -410.591)
		(end 13.843 -410.591)
		(stroke
			(width 0.381)
			(type default)
		)
		(layer "In2.Cu")
	)
	(gr_line
		(start 47.117 -423.418)
		(end 46.736 -423.799)
		(stroke
			(width 0.381)
			(type default)
		)
		(layer "In2.Cu")
	)
	(gr_line
		(start 47.117 -423.418)
		(end 47.117 -410.972)
		(stroke
			(width 0.381)
			(type default)
		)
		(layer "In2.Cu")
	)
	(gr_line
		(start 47.117 -410.972)
		(end 46.736 -410.591)
		(stroke
			(width 0.381)
			(type default)
		)
		(layer "In2.Cu")
	)
	(gr_line
		(start 47.752 -409.829)
		(end 46.99 -410.591)
		(stroke
			(width 0.381)
			(type default)
		)
		(layer "In2.Cu")
	)
	(gr_line
		(start 47.752 -402.082)
		(end 47.752 -409.829)
		(stroke
			(width 0.381)
			(type default)
		)
		(layer "In2.Cu")
	)
	(gr_line
		(start 47.752 -79.121)
		(end 45.085 -81.788)
		(stroke
			(width 0.381)
			(type default)
		)
		(layer "In2.Cu")
	)
	(gr_line
		(start 47.752 -64.389)
		(end 47.752 -79.121)
		(stroke
			(width 0.381)
			(type default)
		)
		(layer "In2.Cu")
	)
	(gr_line
		(start 51.308 -121.285)
		(end 51.816 -120.777)
		(stroke
			(width 0.381)
			(type default)
		)
		(layer "In2.Cu")
	)
	(gr_line
		(start 51.500024 -490.000036)
		(end 18.50009 -490.000036)
		(stroke
			(width 1.524)
			(type default)
		)
		(layer "In2.Cu")
	)
	(gr_arc
		(start 51.500024 -490.000036)
		(mid 52.207127 -489.707137)
		(end 52.500022 -489.000038)
		(stroke
			(width 1.524)
			(type default)
		)
		(layer "In2.Cu")
	)
	(gr_line
		(start 51.689 -113.03)
		(end 32.766 -113.03)
		(stroke
			(width 0.381)
			(type default)
		)
		(layer "In2.Cu")
	)
	(gr_arc
		(start 52.500022 -10.999978)
		(mid 52.207123 -10.292878)
		(end 51.500024 -9.99998)
		(stroke
			(width 1.524)
			(type default)
		)
		(layer "In2.Cu")
	)
	(gr_line
		(start 52.500022 -10.999978)
		(end 52.500022 -489.000038)
		(stroke
			(width 1.524)
			(type default)
		)
		(layer "In2.Cu")
	)
	(gr_line
		(start 0 -499.000018)
		(end 0 -0.999998)
		(stroke
			(width 0.05)
			(type default)
		)
		(layer "Edge.Cuts")
	)
	(gr_arc
		(start 0 -499.000018)
		(mid 0.292892 -499.707125)
		(end 0.999998 -500.000016)
		(stroke
			(width 0.05)
			(type default)
		)
		(layer "Edge.Cuts")
	)
	(gr_arc
		(start 0.999998 0)
		(mid 0.292893 -0.292893)
		(end 0 -0.999998)
		(stroke
			(width 0.05)
			(type default)
		)
		(layer "Edge.Cuts")
	)
	(gr_line
		(start 0.999998 0)
		(end 16.500094 0)
		(stroke
			(width 0.05)
			(type default)
		)
		(layer "Edge.Cuts")
	)
	(gr_arc
		(start 2.750058 -340.000082)
		(mid 4.500118 -341.750142)
		(end 6.249924 -340.000082)
		(stroke
			(width 0.05)
			(type default)
		)
		(layer "Edge.Cuts")
	)
	(gr_arc
		(start 4.99999 -39.99992)
		(mid 6.999986 -41.999916)
		(end 8.999982 -39.99992)
		(stroke
			(width 0.05)
			(type default)
		)
		(layer "Edge.Cuts")
	)
	(gr_arc
		(start 5.249926 -460.000096)
		(mid 6.999986 -461.750156)
		(end 8.750046 -460.000096)
		(stroke
			(width 0.05)
			(type default)
		)
		(layer "Edge.Cuts")
	)
	(gr_arc
		(start 5.249926 -159.999934)
		(mid 6.999986 -161.749994)
		(end 8.750046 -159.999934)
		(stroke
			(width 0.05)
			(type default)
		)
		(layer "Edge.Cuts")
	)
	(gr_arc
		(start 5.80009 -493.700054)
		(mid 7.600188 -495.500152)
		(end 9.400032 -493.700054)
		(stroke
			(width 0.05)
			(type default)
		)
		(layer "Edge.Cuts")
	)
	(gr_arc
		(start 5.80009 -471.700098)
		(mid 7.600188 -473.500196)
		(end 9.400032 -471.700098)
		(stroke
			(width 0.05)
			(type default)
		)
		(layer "Edge.Cuts")
	)
	(gr_arc
		(start 5.80009 -383.659888)
		(mid 7.600188 -385.459986)
		(end 9.400032 -383.659888)
		(stroke
			(width 0.05)
			(type default)
		)
		(layer "Edge.Cuts")
	)
	(gr_arc
		(start 5.80009 -361.659932)
		(mid 7.600188 -363.46003)
		(end 9.400032 -361.659932)
		(stroke
			(width 0.05)
			(type default)
		)
		(layer "Edge.Cuts")
	)
	(gr_arc
		(start 5.80009 -317.66002)
		(mid 7.600188 -319.460118)
		(end 9.400032 -317.66002)
		(stroke
			(width 0.05)
			(type default)
		)
		(layer "Edge.Cuts")
	)
	(gr_arc
		(start 5.80009 -295.660064)
		(mid 7.600188 -297.460162)
		(end 9.400032 -295.660064)
		(stroke
			(width 0.05)
			(type default)
		)
		(layer "Edge.Cuts")
	)
	(gr_arc
		(start 5.80009 -204.339952)
		(mid 7.600188 -206.14005)
		(end 9.400032 -204.339952)
		(stroke
			(width 0.05)
			(type default)
		)
		(layer "Edge.Cuts")
	)
	(gr_arc
		(start 5.80009 -182.339996)
		(mid 7.600188 -184.140094)
		(end 9.400032 -182.339996)
		(stroke
			(width 0.05)
			(type default)
		)
		(layer "Edge.Cuts")
	)
	(gr_arc
		(start 5.80009 -138.340084)
		(mid 7.600188 -140.140182)
		(end 9.400032 -138.340084)
		(stroke
			(width 0.05)
			(type default)
		)
		(layer "Edge.Cuts")
	)
	(gr_arc
		(start 5.80009 -116.339874)
		(mid 7.600188 -118.139972)
		(end 9.400032 -116.339874)
		(stroke
			(width 0.05)
			(type default)
		)
		(layer "Edge.Cuts")
	)
	(gr_arc
		(start 5.80009 -28.299918)
		(mid 7.600188 -30.100016)
		(end 9.400032 -28.299918)
		(stroke
			(width 0.05)
			(type default)
		)
		(layer "Edge.Cuts")
	)
	(gr_arc
		(start 5.80009 -6.299962)
		(mid 7.600188 -8.10006)
		(end 9.400032 -6.299962)
		(stroke
			(width 0.05)
			(type default)
		)
		(layer "Edge.Cuts")
	)
	(gr_arc
		(start 6.249924 -340.000082)
		(mid 4.500118 -338.250276)
		(end 2.750058 -340.000082)
		(stroke
			(width 0.05)
			(type default)
		)
		(layer "Edge.Cuts")
	)
	(gr_arc
		(start 8.750046 -460.000096)
		(mid 6.999986 -458.250036)
		(end 5.249926 -460.000096)
		(stroke
			(width 0.05)
			(type default)
		)
		(layer "Edge.Cuts")
	)
	(gr_arc
		(start 8.750046 -159.999934)
		(mid 6.999986 -158.249874)
		(end 5.249926 -159.999934)
		(stroke
			(width 0.05)
			(type default)
		)
		(layer "Edge.Cuts")
	)
	(gr_arc
		(start 8.999982 -39.99992)
		(mid 6.999986 -37.999924)
		(end 4.99999 -39.99992)
		(stroke
			(width 0.05)
			(type default)
		)
		(layer "Edge.Cuts")
	)
	(gr_arc
		(start 9.400032 -493.700054)
		(mid 7.600188 -491.90021)
		(end 5.80009 -493.700054)
		(stroke
			(width 0.05)
			(type default)
		)
		(layer "Edge.Cuts")
	)
	(gr_arc
		(start 9.400032 -471.700098)
		(mid 7.600188 -469.900254)
		(end 5.80009 -471.700098)
		(stroke
			(width 0.05)
			(type default)
		)
		(layer "Edge.Cuts")
	)
	(gr_arc
		(start 9.400032 -383.659888)
		(mid 7.600188 -381.860044)
		(end 5.80009 -383.659888)
		(stroke
			(width 0.05)
			(type default)
		)
		(layer "Edge.Cuts")
	)
	(gr_arc
		(start 9.400032 -361.659932)
		(mid 7.600188 -359.860088)
		(end 5.80009 -361.659932)
		(stroke
			(width 0.05)
			(type default)
		)
		(layer "Edge.Cuts")
	)
	(gr_arc
		(start 9.400032 -317.66002)
		(mid 7.600188 -315.860176)
		(end 5.80009 -317.66002)
		(stroke
			(width 0.05)
			(type default)
		)
		(layer "Edge.Cuts")
	)
	(gr_arc
		(start 9.400032 -295.660064)
		(mid 7.600188 -293.86022)
		(end 5.80009 -295.660064)
		(stroke
			(width 0.05)
			(type default)
		)
		(layer "Edge.Cuts")
	)
	(gr_arc
		(start 9.400032 -204.339952)
		(mid 7.600188 -202.540108)
		(end 5.80009 -204.339952)
		(stroke
			(width 0.05)
			(type default)
		)
		(layer "Edge.Cuts")
	)
	(gr_arc
		(start 9.400032 -182.339996)
		(mid 7.600188 -180.540152)
		(end 5.80009 -182.339996)
		(stroke
			(width 0.05)
			(type default)
		)
		(layer "Edge.Cuts")
	)
	(gr_arc
		(start 9.400032 -138.340084)
		(mid 7.600188 -136.54024)
		(end 5.80009 -138.340084)
		(stroke
			(width 0.05)
			(type default)
		)
		(layer "Edge.Cuts")
	)
	(gr_arc
		(start 9.400032 -116.339874)
		(mid 7.600188 -114.54003)
		(end 5.80009 -116.339874)
		(stroke
			(width 0.05)
			(type default)
		)
		(layer "Edge.Cuts")
	)
	(gr_arc
		(start 9.400032 -28.299918)
		(mid 7.600188 -26.500074)
		(end 5.80009 -28.299918)
		(stroke
			(width 0.05)
			(type default)
		)
		(layer "Edge.Cuts")
	)
	(gr_arc
		(start 9.400032 -6.299962)
		(mid 7.600188 -4.500118)
		(end 5.80009 -6.299962)
		(stroke
			(width 0.05)
			(type default)
		)
		(layer "Edge.Cuts")
	)
	(gr_arc
		(start 10.54989 -482.700076)
		(mid 11.999976 -484.150162)
		(end 13.450062 -482.700076)
		(stroke
			(width 0.05)
			(type default)
		)
		(layer "Edge.Cuts")
	)
	(gr_arc
		(start 10.54989 -372.65991)
		(mid 11.999976 -374.109996)
		(end 13.450062 -372.65991)
		(stroke
			(width 0.05)
			(type default)
		)
		(layer "Edge.Cuts")
	)
	(gr_arc
		(start 10.54989 -306.660042)
		(mid 11.999976 -308.110128)
		(end 13.450062 -306.660042)
		(stroke
			(width 0.05)
			(type default)
		)
		(layer "Edge.Cuts")
	)
	(gr_arc
		(start 10.54989 -193.339974)
		(mid 11.999976 -194.79006)
		(end 13.450062 -193.339974)
		(stroke
			(width 0.05)
			(type default)
		)
		(layer "Edge.Cuts")
	)
	(gr_arc
		(start 10.54989 -127.340106)
		(mid 11.999976 -128.790192)
		(end 13.450062 -127.340106)
		(stroke
			(width 0.05)
			(type default)
		)
		(layer "Edge.Cuts")
	)
	(gr_arc
		(start 10.54989 -17.29994)
		(mid 11.999976 -18.750026)
		(end 13.450062 -17.29994)
		(stroke
			(width 0.05)
			(type default)
		)
		(layer "Edge.Cuts")
	)
	(gr_arc
		(start 13.450062 -482.700076)
		(mid 11.999976 -481.24999)
		(end 10.54989 -482.700076)
		(stroke
			(width 0.05)
			(type default)
		)
		(layer "Edge.Cuts")
	)
	(gr_arc
		(start 13.450062 -372.65991)
		(mid 11.999976 -371.209824)
		(end 10.54989 -372.65991)
		(stroke
			(width 0.05)
			(type default)
		)
		(layer "Edge.Cuts")
	)
	(gr_arc
		(start 13.450062 -306.660042)
		(mid 11.999976 -305.209956)
		(end 10.54989 -306.660042)
		(stroke
			(width 0.05)
			(type default)
		)
		(layer "Edge.Cuts")
	)
	(gr_arc
		(start 13.450062 -193.339974)
		(mid 11.999976 -191.889888)
		(end 10.54989 -193.339974)
		(stroke
			(width 0.05)
			(type default)
		)
		(layer "Edge.Cuts")
	)
	(gr_arc
		(start 13.450062 -127.340106)
		(mid 11.999976 -125.89002)
		(end 10.54989 -127.340106)
		(stroke
			(width 0.05)
			(type default)
		)
		(layer "Edge.Cuts")
	)
	(gr_arc
		(start 13.450062 -17.29994)
		(mid 11.999976 -15.849854)
		(end 10.54989 -17.29994)
		(stroke
			(width 0.05)
			(type default)
		)
		(layer "Edge.Cuts")
	)
	(gr_line
		(start 16.500094 -500.000016)
		(end 0.999998 -500.000016)
		(stroke
			(width 0.05)
			(type default)
		)
		(layer "Edge.Cuts")
	)
	(gr_arc
		(start 16.500094 -500.000016)
		(mid 17.20721 -499.707127)
		(end 17.500092 -499.000018)
		(stroke
			(width 0.05)
			(type default)
		)
		(layer "Edge.Cuts")
	)
	(gr_line
		(start 17.500092 -491.000034)
		(end 17.500092 -499.000018)
		(stroke
			(width 0.05)
			(type default)
		)
		(layer "Edge.Cuts")
	)
	(gr_arc
		(start 17.500092 -8.999982)
		(mid 17.792985 -9.707087)
		(end 18.50009 -9.99998)
		(stroke
			(width 0.05)
			(type default)
		)
		(layer "Edge.Cuts")
	)
	(gr_arc
		(start 17.500092 -0.999998)
		(mid 17.207198 -0.292896)
		(end 16.500094 0)
		(stroke
			(width 0.05)
			(type default)
		)
		(layer "Edge.Cuts")
	)
	(gr_line
		(start 17.500092 -0.999998)
		(end 17.500092 -8.999982)
		(stroke
			(width 0.05)
			(type default)
		)
		(layer "Edge.Cuts")
	)
	(gr_arc
		(start 18.50009 -490.000036)
		(mid 17.792985 -490.292929)
		(end 17.500092 -491.000034)
		(stroke
			(width 0.05)
			(type default)
		)
		(layer "Edge.Cuts")
	)
	(gr_line
		(start 18.50009 -9.99998)
		(end 51.500024 -9.99998)
		(stroke
			(width 0.05)
			(type default)
		)
		(layer "Edge.Cuts")
	)
	(gr_arc
		(start 24.500078 -465.549996)
		(mid 26.999946 -463.050128)
		(end 24.500078 -460.550006)
		(stroke
			(width 0.05)
			(type default)
		)
		(layer "Edge.Cuts")
	)
	(gr_arc
		(start 24.500078 -460.550006)
		(mid 21.999956 -463.050128)
		(end 24.500078 -465.549996)
		(stroke
			(width 0.05)
			(type default)
		)
		(layer "Edge.Cuts")
	)
	(gr_arc
		(start 24.500078 -446.449958)
		(mid 26.999946 -443.95009)
		(end 24.500078 -441.449968)
		(stroke
			(width 0.05)
			(type default)
		)
		(layer "Edge.Cuts")
	)
	(gr_arc
		(start 24.500078 -441.449968)
		(mid 21.999956 -443.95009)
		(end 24.500078 -446.449958)
		(stroke
			(width 0.05)
			(type default)
		)
		(layer "Edge.Cuts")
	)
	(gr_arc
		(start 40.999918 -465.549996)
		(mid 43.499786 -463.050128)
		(end 40.999918 -460.550006)
		(stroke
			(width 0.05)
			(type default)
		)
		(layer "Edge.Cuts")
	)
	(gr_arc
		(start 40.999918 -460.550006)
		(mid 38.499796 -463.050128)
		(end 40.999918 -465.549996)
		(stroke
			(width 0.05)
			(type default)
		)
		(layer "Edge.Cuts")
	)
	(gr_arc
		(start 40.999918 -446.449958)
		(mid 43.499786 -443.95009)
		(end 40.999918 -441.449968)
		(stroke
			(width 0.05)
			(type default)
		)
		(layer "Edge.Cuts")
	)
	(gr_arc
		(start 40.999918 -441.449968)
		(mid 38.499796 -443.95009)
		(end 40.999918 -446.449958)
		(stroke
			(width 0.05)
			(type default)
		)
		(layer "Edge.Cuts")
	)
	(gr_arc
		(start 43.50004 -480.000056)
		(mid 45.500036 -482.000052)
		(end 47.500032 -480.000056)
		(stroke
			(width 0.05)
			(type default)
		)
		(layer "Edge.Cuts")
	)
	(gr_arc
		(start 43.749976 -294.999918)
		(mid 45.500036 -296.749978)
		(end 47.250096 -294.999918)
		(stroke
			(width 0.05)
			(type default)
		)
		(layer "Edge.Cuts")
	)
	(gr_arc
		(start 43.749976 -144.999964)
		(mid 45.500036 -146.750024)
		(end 47.250096 -144.999964)
		(stroke
			(width 0.05)
			(type default)
		)
		(layer "Edge.Cuts")
	)
	(gr_arc
		(start 43.749976 -19.99996)
		(mid 45.500036 -21.75002)
		(end 47.250096 -19.99996)
		(stroke
			(width 0.05)
			(type default)
		)
		(layer "Edge.Cuts")
	)
	(gr_arc
		(start 45.449998 -340.000082)
		(mid 47.949866 -337.500214)
		(end 45.449998 -335.000092)
		(stroke
			(width 0.05)
			(type default)
		)
		(layer "Edge.Cuts")
	)
	(gr_arc
		(start 45.449998 -335.000092)
		(mid 42.949876 -337.500214)
		(end 45.449998 -340.000082)
		(stroke
			(width 0.05)
			(type default)
		)
		(layer "Edge.Cuts")
	)
	(gr_arc
		(start 47.250096 -294.999918)
		(mid 45.500036 -293.249858)
		(end 43.749976 -294.999918)
		(stroke
			(width 0.05)
			(type default)
		)
		(layer "Edge.Cuts")
	)
	(gr_arc
		(start 47.250096 -144.999964)
		(mid 45.500036 -143.249904)
		(end 43.749976 -144.999964)
		(stroke
			(width 0.05)
			(type default)
		)
		(layer "Edge.Cuts")
	)
	(gr_arc
		(start 47.250096 -19.99996)
		(mid 45.500036 -18.2499)
		(end 43.749976 -19.99996)
		(stroke
			(width 0.05)
			(type default)
		)
		(layer "Edge.Cuts")
	)
	(gr_arc
		(start 47.500032 -480.000056)
		(mid 45.500036 -478.00006)
		(end 43.50004 -480.000056)
		(stroke
			(width 0.05)
			(type default)
		)
		(layer "Edge.Cuts")
	)
	(gr_line
		(start 51.500024 -490.000036)
		(end 18.50009 -490.000036)
		(stroke
			(width 0.05)
			(type default)
		)
		(layer "Edge.Cuts")
	)
	(gr_arc
		(start 51.500024 -490.000036)
		(mid 52.207127 -489.707137)
		(end 52.500022 -489.000038)
		(stroke
			(width 0.05)
			(type default)
		)
		(layer "Edge.Cuts")
	)
	(gr_arc
		(start 52.500022 -10.999978)
		(mid 52.207123 -10.292878)
		(end 51.500024 -9.99998)
		(stroke
			(width 0.05)
			(type default)
		)
		(layer "Edge.Cuts")
	)
	(gr_line
		(start 52.500022 -10.999978)
		(end 52.500022 -489.000038)
		(stroke
			(width 0.05)
			(type default)
		)
		(layer "Edge.Cuts")
	)
	(segment
		(start 27.7368 -356.489)
		(end 27.7368 -355.7524)
		(width 0.1397)
		(layer "F.Cu")
		(net "TEMP_ALM#_G")
	)
	(segment
		(start 27.3558 -356.87)
		(end 27.7368 -356.489)
		(width 0.1397)
		(layer "F.Cu")
		(net "TEMP_ALM#_G")
	)
	(segment
		(start 25.4254 -357.6574)
		(end 26.4287 -357.6574)
		(width 0.1397)
		(layer "F.Cu")
		(net "TEMP_ALM#_G")
	)
	(segment
		(start 27.5336 -354.87356)
		(end 27.0256 -354.87356)
		(width 0.1397)
		(layer "F.Cu")
		(net "TEMP_ALM#_G")
	)
	(segment
		(start 27.7368 -355.7524)
		(end 27.7368 -355.07676)
		(width 0.1397)
		(layer "F.Cu")
		(net "TEMP_ALM#_G")
	)
	(segment
		(start 26.4287 -357.2637)
		(end 26.8224 -356.87)
		(width 0.1397)
		(layer "F.Cu")
		(net "TEMP_ALM#_G")
	)
	(segment
		(start 27.5082 -355.5238)
		(end 27.7368 -355.7524)
		(width 0.1397)
		(layer "F.Cu")
		(net "TEMP_ALM#_G")
	)
	(segment
		(start 26.8224 -356.87)
		(end 27.3558 -356.87)
		(width 0.1397)
		(layer "F.Cu")
		(net "TEMP_ALM#_G")
	)
	(segment
		(start 26.4287 -357.6574)
		(end 26.4287 -357.2637)
		(width 0.1397)
		(layer "F.Cu")
		(net "TEMP_ALM#_G")
	)
	(segment
		(start 27.0256 -355.5238)
		(end 27.5082 -355.5238)
		(width 0.1397)
		(layer "F.Cu")
		(net "TEMP_ALM#_G")
	)
	(segment
		(start 27.7368 -355.07676)
		(end 27.5336 -354.87356)
		(width 0.1397)
		(layer "F.Cu")
		(net "TEMP_ALM#_G")
	)
	(segment
		(start 25.273 -357.505)
		(end 25.4254 -357.6574)
		(width 0.1397)
		(layer "F.Cu")
		(net "TEMP_ALM#_G")
	)
	(via
		(at 25.273 -357.505)
		(size 0.7112)
		(drill 0.3556)
		(layers "F.Cu" "B.Cu")
		(net "TEMP_ALM#_G")
	)
	(segment
		(start 24.765 -353.187)
		(end 24.765 -351.155)
		(width 0.1397)
		(layer "F.Cu")
		(net "TEMP_ALM#_JP_2")
	)
	(segment
		(start 25.273 -350.647)
		(end 41.91 -350.647)
		(width 0.1397)
		(layer "F.Cu")
		(net "TEMP_ALM#_JP_2")
	)
	(segment
		(start 24.765 -351.155)
		(end 25.273 -350.647)
		(width 0.1397)
		(layer "F.Cu")
		(net "TEMP_ALM#_JP_2")
	)
	(segment
		(start 29.311346 -353.568)
		(end 25.146 -353.568)
		(width 0.1397)
		(layer "F.Cu")
		(net "TEMP_ALM#_JP_2")
	)
	(segment
		(start 28.9052 -356.17404)
		(end 29.39796 -356.17404)
		(width 0.1397)
		(layer "F.Cu")
		(net "TEMP_ALM#_JP_2")
	)
	(segment
		(start 29.39796 -356.17404)
		(end 29.819346 -355.752654)
		(width 0.1397)
		(layer "F.Cu")
		(net "TEMP_ALM#_JP_2")
	)
	(segment
		(start 25.146 -353.568)
		(end 24.765 -353.187)
		(width 0.1397)
		(layer "F.Cu")
		(net "TEMP_ALM#_JP_2")
	)
	(segment
		(start 29.819346 -354.076)
		(end 29.311346 -353.568)
		(width 0.1397)
		(layer "F.Cu")
		(net "TEMP_ALM#_JP_2")
	)
	(segment
		(start 29.819346 -355.752654)
		(end 29.819346 -354.076)
		(width 0.1397)
		(layer "F.Cu")
		(net "TEMP_ALM#_JP_2")
	)
	(segment
		(start 39.784274 -361.818174)
		(end 39.5097 -361.5436)
		(width 0.1397)
		(layer "F.Cu")
		(net "TEMP_ALM#_JP_1")
	)
	(segment
		(start 43.1546 -358.0892)
		(end 43.1546 -349.3516)
		(width 0.1397)
		(layer "F.Cu")
		(net "TEMP_ALM#_JP_1")
	)
	(segment
		(start 39.7002 -361.5436)
		(end 43.1546 -358.0892)
		(width 0.1397)
		(layer "F.Cu")
		(net "TEMP_ALM#_JP_1")
	)
	(segment
		(start 40.851074 -362.415074)
		(end 39.987474 -362.415074)
		(width 0.1397)
		(layer "F.Cu")
		(net "TEMP_ALM#_JP_1")
	)
	(segment
		(start 43.1546 -349.3516)
		(end 41.91 -348.107)
		(width 0.1397)
		(layer "F.Cu")
		(net "TEMP_ALM#_JP_1")
	)
	(segment
		(start 39.987474 -362.415074)
		(end 39.784274 -362.618274)
		(width 0.1397)
		(layer "F.Cu")
		(net "TEMP_ALM#_JP_1")
	)
	(segment
		(start 39.5097 -361.5436)
		(end 39.7002 -361.5436)
		(width 0.1397)
		(layer "F.Cu")
		(net "TEMP_ALM#_JP_1")
	)
	(segment
		(start 39.784274 -362.618274)
		(end 39.784274 -361.818174)
		(width 0.1397)
		(layer "F.Cu")
		(net "TEMP_ALM#_JP_1")
	)
	(segment
		(start 34.29 -358.8766)
		(end 34.29 -358.610916)
		(width 0.1397)
		(layer "F.Cu")
		(net "OTP_RETRY_DIODE")
	)
	(segment
		(start 34.29 -358.610916)
		(end 35.392868 -358.610916)
		(width 0.1397)
		(layer "F.Cu")
		(net "OTP_RETRY_DIODE")
	)
	(segment
		(start 35.392868 -358.610916)
		(end 35.8394 -358.164384)
		(width 0.1397)
		(layer "F.Cu")
		(net "OTP_RETRY_DIODE")
	)
	(segment
		(start 32.766 -359.77195)
		(end 33.39465 -359.77195)
		(width 0.1397)
		(layer "F.Cu")
		(net "OTP_RETRY_DIODE")
	)
	(segment
		(start 33.39465 -359.77195)
		(end 34.29 -358.8766)
		(width 0.1397)
		(layer "F.Cu")
		(net "OTP_RETRY_DIODE")
	)
	(via
		(at 32.766 -359.77195)
		(size 0.7112)
		(drill 0.3556)
		(layers "F.Cu" "B.Cu")
		(net "OTP_RETRY_DIODE")
	)
	(segment
		(start 41.148 -356.8954)
		(end 37.9222 -356.8954)
		(width 0.1397)
		(layer "F.Cu")
		(net "OTP_RETRY_B")
	)
	(segment
		(start 38.469316 -354.076)
		(end 38.3794 -354.165916)
		(width 0.1397)
		(layer "F.Cu")
		(net "OTP_RETRY_B")
	)
	(segment
		(start 41.529 -359.08615)
		(end 41.529 -357.2764)
		(width 0.1397)
		(layer "F.Cu")
		(net "OTP_RETRY_B")
	)
	(segment
		(start 37.9222 -356.8954)
		(end 37.59835 -356.57155)
		(width 0.1397)
		(layer "F.Cu")
		(net "OTP_RETRY_B")
	)
	(segment
		(start 38.3794 -354.165916)
		(end 38.3794 -355.1174)
		(width 0.1397)
		(layer "F.Cu")
		(net "OTP_RETRY_B")
	)
	(segment
		(start 38.3794 -355.1174)
		(end 37.59835 -355.89845)
		(width 0.1397)
		(layer "F.Cu")
		(net "OTP_RETRY_B")
	)
	(segment
		(start 39.508684 -360.4768)
		(end 40.13835 -360.4768)
		(width 0.1397)
		(layer "F.Cu")
		(net "OTP_RETRY_B")
	)
	(segment
		(start 41.529 -357.2764)
		(end 41.148 -356.8954)
		(width 0.1397)
		(layer "F.Cu")
		(net "OTP_RETRY_B")
	)
	(segment
		(start 40.13835 -360.4768)
		(end 41.529 -359.08615)
		(width 0.1397)
		(layer "F.Cu")
		(net "OTP_RETRY_B")
	)
	(segment
		(start 41.021 -354.076)
		(end 41.91 -353.187)
		(width 0.1397)
		(layer "F.Cu")
		(net "OTP_RETRY_B")
	)
	(segment
		(start 37.59835 -355.89845)
		(end 37.59835 -355.969316)
		(width 0.1397)
		(layer "F.Cu")
		(net "OTP_RETRY_B")
	)
	(segment
		(start 37.59835 -356.57155)
		(end 37.59835 -355.969316)
		(width 0.1397)
		(layer "F.Cu")
		(net "OTP_RETRY_B")
	)
	(segment
		(start 38.469316 -354.076)
		(end 41.021 -354.076)
		(width 0.1397)
		(layer "F.Cu")
		(net "OTP_RETRY_B")
	)
	(segment
		(start 38.5826 -357.874316)
		(end 37.682932 -357.874316)
		(width 0.1397)
		(layer "F.Cu")
		(net "OTP_RETRY_C")
	)
	(segment
		(start 39.508684 -358.8004)
		(end 38.5826 -357.874316)
		(width 0.1397)
		(layer "F.Cu")
		(net "OTP_RETRY_C")
	)
	(segment
		(start 37.682932 -357.874316)
		(end 35.8394 -356.030784)
		(width 0.1397)
		(layer "F.Cu")
		(net "OTP_RETRY_C")
	)
	(segment
		(start 39.508684 -359.41)
		(end 39.508684 -358.8004)
		(width 0.1397)
		(layer "F.Cu")
		(net "OTP_RETRY_C")
	)
	(segment
		(start 40.423592 -359.41)
		(end 39.508684 -359.41)
		(width 0.1397)
		(layer "F.Cu")
		(net "OTP_RETRY_C")
	)
	(segment
		(start 40.582596 -359.250996)
		(end 40.423592 -359.41)
		(width 0.1397)
		(layer "F.Cu")
		(net "OTP_RETRY_C")
	)
	(via
		(at 40.582596 -359.250996)
		(size 0.7112)
		(drill 0.3556)
		(layers "F.Cu" "B.Cu")
		(net "OTP_RETRY_C")
	)
	(segment
		(start 31.206948 -351.917)
		(end 35.814 -351.917)
		(width 0.1397)
		(layer "F.Cu")
		(net "OTP_RETRY_G")
	)
	(segment
		(start 30.76575 -356.096316)
		(end 30.353 -355.683566)
		(width 0.1397)
		(layer "F.Cu")
		(net "OTP_RETRY_G")
	)
	(segment
		(start 34.466784 -353.6442)
		(end 34.925 -354.102416)
		(width 0.1397)
		(layer "F.Cu")
		(net "OTP_RETRY_G")
	)
	(segment
		(start 34.925 -354.102416)
		(end 34.925 -356.108)
		(width 0.1397)
		(layer "F.Cu")
		(net "OTP_RETRY_G")
	)
	(segment
		(start 30.226 -351.917)
		(end 31.206948 -351.917)
		(width 0.1397)
		(layer "F.Cu")
		(net "OTP_RETRY_G")
	)
	(segment
		(start 36.322 -352.425)
		(end 35.433 -353.314)
		(width 0.1397)
		(layer "F.Cu")
		(net "OTP_RETRY_G")
	)
	(segment
		(start 34.796984 -353.314)
		(end 34.466784 -353.6442)
		(width 0.1397)
		(layer "F.Cu")
		(net "OTP_RETRY_G")
	)
	(segment
		(start 30.353 -355.683566)
		(end 30.353 -353.568)
		(width 0.1397)
		(layer "F.Cu")
		(net "OTP_RETRY_G")
	)
	(segment
		(start 29.718 -352.425)
		(end 30.226 -351.917)
		(width 0.1397)
		(layer "F.Cu")
		(net "OTP_RETRY_G")
	)
	(segment
		(start 29.718 -352.933)
		(end 29.718 -352.425)
		(width 0.1397)
		(layer "F.Cu")
		(net "OTP_RETRY_G")
	)
	(segment
		(start 34.925 -356.108)
		(end 34.403284 -356.629716)
		(width 0.1397)
		(layer "F.Cu")
		(net "OTP_RETRY_G")
	)
	(segment
		(start 35.433 -353.314)
		(end 34.796984 -353.314)
		(width 0.1397)
		(layer "F.Cu")
		(net "OTP_RETRY_G")
	)
	(segment
		(start 34.29 -357.721916)
		(end 34.29 -356.705916)
		(width 0.1397)
		(layer "F.Cu")
		(net "OTP_RETRY_G")
	)
	(segment
		(start 34.29 -356.705916)
		(end 34.2138 -356.629716)
		(width 0.1397)
		(layer "F.Cu")
		(net "OTP_RETRY_G")
	)
	(segment
		(start 35.814 -351.917)
		(end 36.322 -352.425)
		(width 0.1397)
		(layer "F.Cu")
		(net "OTP_RETRY_G")
	)
	(segment
		(start 30.353 -353.568)
		(end 29.718 -352.933)
		(width 0.1397)
		(layer "F.Cu")
		(net "OTP_RETRY_G")
	)
	(segment
		(start 34.403284 -356.629716)
		(end 34.2138 -356.629716)
		(width 0.1397)
		(layer "F.Cu")
		(net "OTP_RETRY_G")
	)
	(via
		(at 31.206948 -351.917)
		(size 0.7112)
		(drill 0.3556)
		(layers "F.Cu" "B.Cu")
		(net "OTP_RETRY_G")
	)
	(segment
		(start 36.5506 -362.1532)
		(end 39.650416 -365.253016)
		(width 0.1397)
		(layer "F.Cu")
		(net "TEMP_ALM#_REVERSE_R")
	)
	(segment
		(start 35.484816 -363.728)
		(end 33.8455 -363.728)
		(width 0.1397)
		(layer "F.Cu")
		(net "TEMP_ALM#_REVERSE_R")
	)
	(segment
		(start 35.228276 -361.8738)
		(end 35.228276 -361.256326)
		(width 0.1397)
		(layer "F.Cu")
		(net "TEMP_ALM#_REVERSE_R")
	)
	(segment
		(start 33.8455 -362.7882)
		(end 34.3027 -362.331)
		(width 0.1397)
		(layer "F.Cu")
		(net "TEMP_ALM#_REVERSE_R")
	)
	(segment
		(start 15.3924 -49.5427)
		(end 16.6751 -49.5427)
		(width 0.1397)
		(layer "F.Cu")
		(net "TEMP_ALM#_REVERSE_R")
	)
	(segment
		(start 34.771076 -362.331)
		(end 35.228276 -361.8738)
		(width 0.1397)
		(layer "F.Cu")
		(net "TEMP_ALM#_REVERSE_R")
	)
	(segment
		(start 37.465 -365.0615)
		(end 36.818316 -365.0615)
		(width 0.1397)
		(layer "F.Cu")
		(net "TEMP_ALM#_REVERSE_R")
	)
	(segment
		(start 36.195 -360.807)
		(end 36.5506 -361.1626)
		(width 0.1397)
		(layer "F.Cu")
		(net "TEMP_ALM#_REVERSE_R")
	)
	(segment
		(start 36.195 -360.807)
		(end 35.745674 -361.256326)
		(width 0.1397)
		(layer "F.Cu")
		(net "TEMP_ALM#_REVERSE_R")
	)
	(segment
		(start 16.6751 -49.5427)
		(end 17.907 -48.3108)
		(width 0.1397)
		(layer "F.Cu")
		(net "TEMP_ALM#_REVERSE_R")
	)
	(segment
		(start 36.818316 -365.0615)
		(end 35.484816 -363.728)
		(width 0.1397)
		(layer "F.Cu")
		(net "TEMP_ALM#_REVERSE_R")
	)
	(segment
		(start 15.3924 -50.5587)
		(end 15.3289 -50.6222)
		(width 0.1397)
		(layer "F.Cu")
		(net "TEMP_ALM#_REVERSE_R")
	)
	(segment
		(start 36.5506 -361.1626)
		(end 36.5506 -362.1532)
		(width 0.1397)
		(layer "F.Cu")
		(net "TEMP_ALM#_REVERSE_R")
	)
	(segment
		(start 33.8455 -362.7882)
		(end 33.8455 -363.728)
		(width 0.1397)
		(layer "F.Cu")
		(net "TEMP_ALM#_REVERSE_R")
	)
	(segment
		(start 15.3924 -49.5427)
		(end 15.3924 -50.5587)
		(width 0.1397)
		(layer "F.Cu")
		(net "TEMP_ALM#_REVERSE_R")
	)
	(segment
		(start 34.3027 -362.331)
		(end 34.771076 -362.331)
		(width 0.1397)
		(layer "F.Cu")
		(net "TEMP_ALM#_REVERSE_R")
	)
	(segment
		(start 39.650416 -365.253016)
		(end 40.2844 -365.253016)
		(width 0.1397)
		(layer "F.Cu")
		(net "TEMP_ALM#_REVERSE_R")
	)
	(segment
		(start 35.745674 -361.256326)
		(end 35.228276 -361.256326)
		(width 0.1397)
		(layer "F.Cu")
		(net "TEMP_ALM#_REVERSE_R")
	)
	(via
		(at 17.907 -48.3108)
		(size 0.5588)
		(drill 0.3048)
		(layers "F.Cu" "B.Cu")
		(net "TEMP_ALM#_REVERSE_R")
	)
	(via
		(at 48.769778 -122.578622)
		(size 0.7112)
		(drill 0.3556)
		(layers "F.Cu" "B.Cu")
		(net "TEMP_ALM#_REVERSE_R")
	)
	(via
		(at 36.195 -360.807)
		(size 0.5588)
		(drill 0.3048)
		(layers "F.Cu" "B.Cu")
		(net "TEMP_ALM#_REVERSE_R")
	)
	(segment
		(start 22.909022 -47.371)
		(end 21.4376 -45.899578)
		(width 0.1397)
		(layer "B.Cu")
		(net "TEMP_ALM#_REVERSE_R")
	)
	(segment
		(start 45.72 -251.0536)
		(end 46.78045 -249.99315)
		(width 0.1397)
		(layer "B.Cu")
		(net "TEMP_ALM#_REVERSE_R")
	)
	(segment
		(start 43.7642 -184.461404)
		(end 43.7642 -177.1904)
		(width 0.1397)
		(layer "B.Cu")
		(net "TEMP_ALM#_REVERSE_R")
	)
	(segment
		(start 46.31055 -197.078854)
		(end 42.70375 -193.472054)
		(width 0.1397)
		(layer "B.Cu")
		(net "TEMP_ALM#_REVERSE_R")
	)
	(segment
		(start 37.846 -261.493)
		(end 45.72 -253.619)
		(width 0.1397)
		(layer "B.Cu")
		(net "TEMP_ALM#_REVERSE_R")
	)
	(segment
		(start 46.78045 -241.19205)
		(end 46.31055 -240.72215)
		(width 0.1397)
		(layer "B.Cu")
		(net "TEMP_ALM#_REVERSE_R")
	)
	(segment
		(start 50.419 -120.9294)
		(end 50.419 -112.9792)
		(width 0.1397)
		(layer "B.Cu")
		(net "TEMP_ALM#_REVERSE_R")
	)
	(segment
		(start 17.907 -47.490634)
		(end 17.907 -48.3108)
		(width 0.1397)
		(layer "B.Cu")
		(net "TEMP_ALM#_REVERSE_R")
	)
	(segment
		(start 46.31055 -240.72215)
		(end 46.31055 -197.078854)
		(width 0.1397)
		(layer "B.Cu")
		(net "TEMP_ALM#_REVERSE_R")
	)
	(segment
		(start 46.78045 -249.99315)
		(end 46.78045 -241.19205)
		(width 0.1397)
		(layer "B.Cu")
		(net "TEMP_ALM#_REVERSE_R")
	)
	(segment
		(start 46.81855 -124.52985)
		(end 48.769778 -122.578622)
		(width 0.1397)
		(layer "B.Cu")
		(net "TEMP_ALM#_REVERSE_R")
	)
	(segment
		(start 20.118578 -45.279056)
		(end 17.907 -47.490634)
		(width 0.1397)
		(layer "B.Cu")
		(net "TEMP_ALM#_REVERSE_R")
	)
	(segment
		(start 44.69892 -65.32372)
		(end 42.1132 -62.738)
		(width 0.1397)
		(layer "B.Cu")
		(net "TEMP_ALM#_REVERSE_R")
	)
	(segment
		(start 49.47285 -106.90225)
		(end 49.47285 -69.10705)
		(width 0.1397)
		(layer "B.Cu")
		(net "TEMP_ALM#_REVERSE_R")
	)
	(segment
		(start 48.769778 -122.578622)
		(end 50.419 -120.9294)
		(width 0.1397)
		(layer "B.Cu")
		(net "TEMP_ALM#_REVERSE_R")
	)
	(segment
		(start 36.195 -279.654)
		(end 37.846 -278.003)
		(width 0.1397)
		(layer "B.Cu")
		(net "TEMP_ALM#_REVERSE_R")
	)
	(segment
		(start 36.195 -360.807)
		(end 36.195 -279.654)
		(width 0.1397)
		(layer "B.Cu")
		(net "TEMP_ALM#_REVERSE_R")
	)
	(segment
		(start 45.72 -253.619)
		(end 45.72 -251.0536)
		(width 0.1397)
		(layer "B.Cu")
		(net "TEMP_ALM#_REVERSE_R")
	)
	(segment
		(start 45.9994 -174.9552)
		(end 45.9994 -163.6776)
		(width 0.1397)
		(layer "B.Cu")
		(net "TEMP_ALM#_REVERSE_R")
	)
	(segment
		(start 45.238162 -66.180716)
		(end 44.69892 -65.641474)
		(width 0.1397)
		(layer "B.Cu")
		(net "TEMP_ALM#_REVERSE_R")
	)
	(segment
		(start 45.9994 -163.6776)
		(end 46.6852 -162.9918)
		(width 0.1397)
		(layer "B.Cu")
		(net "TEMP_ALM#_REVERSE_R")
	)
	(segment
		(start 42.70375 -193.472054)
		(end 42.70375 -185.521854)
		(width 0.1397)
		(layer "B.Cu")
		(net "TEMP_ALM#_REVERSE_R")
	)
	(segment
		(start 37.846 -278.003)
		(end 37.846 -261.493)
		(width 0.1397)
		(layer "B.Cu")
		(net "TEMP_ALM#_REVERSE_R")
	)
	(segment
		(start 20.881594 -45.279056)
		(end 20.118578 -45.279056)
		(width 0.1397)
		(layer "B.Cu")
		(net "TEMP_ALM#_REVERSE_R")
	)
	(segment
		(start 46.6852 -157.0482)
		(end 38.43655 -148.79955)
		(width 0.1397)
		(layer "B.Cu")
		(net "TEMP_ALM#_REVERSE_R")
	)
	(segment
		(start 38.43655 -148.79955)
		(end 38.43655 -143.4084)
		(width 0.1397)
		(layer "B.Cu")
		(net "TEMP_ALM#_REVERSE_R")
	)
	(segment
		(start 43.7642 -177.1904)
		(end 45.9994 -174.9552)
		(width 0.1397)
		(layer "B.Cu")
		(net "TEMP_ALM#_REVERSE_R")
	)
	(segment
		(start 46.81855 -135.0264)
		(end 46.81855 -124.52985)
		(width 0.1397)
		(layer "B.Cu")
		(net "TEMP_ALM#_REVERSE_R")
	)
	(segment
		(start 42.1132 -62.738)
		(end 42.1132 -57.023)
		(width 0.1397)
		(layer "B.Cu")
		(net "TEMP_ALM#_REVERSE_R")
	)
	(segment
		(start 46.546516 -66.180716)
		(end 45.238162 -66.180716)
		(width 0.1397)
		(layer "B.Cu")
		(net "TEMP_ALM#_REVERSE_R")
	)
	(segment
		(start 42.1132 -57.023)
		(end 40.724836 -55.634636)
		(width 0.1397)
		(layer "B.Cu")
		(net "TEMP_ALM#_REVERSE_R")
	)
	(segment
		(start 38.43655 -143.4084)
		(end 46.81855 -135.0264)
		(width 0.1397)
		(layer "B.Cu")
		(net "TEMP_ALM#_REVERSE_R")
	)
	(segment
		(start 46.6852 -162.9918)
		(end 46.6852 -157.0482)
		(width 0.1397)
		(layer "B.Cu")
		(net "TEMP_ALM#_REVERSE_R")
	)
	(segment
		(start 21.4376 -45.899578)
		(end 21.4376 -45.835062)
		(width 0.1397)
		(layer "B.Cu")
		(net "TEMP_ALM#_REVERSE_R")
	)
	(segment
		(start 37.854636 -55.634636)
		(end 29.591 -47.371)
		(width 0.1397)
		(layer "B.Cu")
		(net "TEMP_ALM#_REVERSE_R")
	)
	(segment
		(start 40.724836 -55.634636)
		(end 37.854636 -55.634636)
		(width 0.1397)
		(layer "B.Cu")
		(net "TEMP_ALM#_REVERSE_R")
	)
	(segment
		(start 50.419 -112.9792)
		(end 49.93005 -112.49025)
		(width 0.1397)
		(layer "B.Cu")
		(net "TEMP_ALM#_REVERSE_R")
	)
	(segment
		(start 29.591 -47.371)
		(end 22.909022 -47.371)
		(width 0.1397)
		(layer "B.Cu")
		(net "TEMP_ALM#_REVERSE_R")
	)
	(segment
		(start 49.93005 -112.49025)
		(end 49.93005 -107.35945)
		(width 0.1397)
		(layer "B.Cu")
		(net "TEMP_ALM#_REVERSE_R")
	)
	(segment
		(start 49.93005 -107.35945)
		(end 49.47285 -106.90225)
		(width 0.1397)
		(layer "B.Cu")
		(net "TEMP_ALM#_REVERSE_R")
	)
	(segment
		(start 49.47285 -69.10705)
		(end 46.546516 -66.180716)
		(width 0.1397)
		(layer "B.Cu")
		(net "TEMP_ALM#_REVERSE_R")
	)
	(segment
		(start 44.69892 -65.641474)
		(end 44.69892 -65.32372)
		(width 0.1397)
		(layer "B.Cu")
		(net "TEMP_ALM#_REVERSE_R")
	)
	(segment
		(start 21.4376 -45.835062)
		(end 20.881594 -45.279056)
		(width 0.1397)
		(layer "B.Cu")
		(net "TEMP_ALM#_REVERSE_R")
	)
	(segment
		(start 42.70375 -185.521854)
		(end 43.7642 -184.461404)
		(width 0.1397)
		(layer "B.Cu")
		(net "TEMP_ALM#_REVERSE_R")
	)
	(segment
		(start 44.254674 -55.825136)
		(end 45.619924 -54.459886)
		(width 0.1397)
		(layer "F.Cu")
		(net "SD_LATCH_RELEASE_L")
	)
	(segment
		(start 37.219636 -55.634636)
		(end 38.9001 -55.634636)
		(width 0.1397)
		(layer "F.Cu")
		(net "SD_LATCH_RELEASE_L")
	)
	(segment
		(start 15.3289 -47.5742)
		(end 15.573756 -47.819056)
		(width 0.1397)
		(layer "F.Cu")
		(net "SD_LATCH_RELEASE_L")
	)
	(segment
		(start 15.573756 -47.819056)
		(end 29.404056 -47.819056)
		(width 0.1397)
		(layer "F.Cu")
		(net "SD_LATCH_RELEASE_L")
	)
	(segment
		(start 15.3289 -47.5742)
		(end 15.3289 -48.5902)
		(width 0.1397)
		(layer "F.Cu")
		(net "SD_LATCH_RELEASE_L")
	)
	(segment
		(start 29.404056 -47.819056)
		(end 37.219636 -55.634636)
		(width 0.1397)
		(layer "F.Cu")
		(net "SD_LATCH_RELEASE_L")
	)
	(segment
		(start 39.0906 -55.825136)
		(end 44.254674 -55.825136)
		(width 0.1397)
		(layer "F.Cu")
		(net "SD_LATCH_RELEASE_L")
	)
	(segment
		(start 38.9001 -55.634636)
		(end 39.0906 -55.825136)
		(width 0.1397)
		(layer "F.Cu")
		(net "SD_LATCH_RELEASE_L")
	)
	(segment
		(start 15.3289 -48.5902)
		(end 15.3924 -48.6537)
		(width 0.1397)
		(layer "F.Cu")
		(net "SD_LATCH_RELEASE_L")
	)
	(segment
		(start 14.4399 -50.6222)
		(end 14.4399 -49.6062)
		(width 0.1397)
		(layer "F.Cu")
		(net "SD_LATCH_RELEASE_U")
	)
	(segment
		(start 14.859 -51.0032)
		(end 14.8209 -51.0032)
		(width 0.1397)
		(layer "F.Cu")
		(net "SD_LATCH_RELEASE_U")
	)
	(segment
		(start 16.256 -50.7238)
		(end 15.88135 -51.09845)
		(width 0.1397)
		(layer "F.Cu")
		(net "SD_LATCH_RELEASE_U")
	)
	(segment
		(start 14.8209 -51.0032)
		(end 14.4399 -50.6222)
		(width 0.1397)
		(layer "F.Cu")
		(net "SD_LATCH_RELEASE_U")
	)
	(segment
		(start 15.88135 -51.09845)
		(end 14.95425 -51.09845)
		(width 0.1397)
		(layer "F.Cu")
		(net "SD_LATCH_RELEASE_U")
	)
	(segment
		(start 14.95425 -51.09845)
		(end 14.859 -51.0032)
		(width 0.1397)
		(layer "F.Cu")
		(net "SD_LATCH_RELEASE_U")
	)
	(segment
		(start 14.4399 -49.6062)
		(end 14.3764 -49.5427)
		(width 0.1397)
		(layer "F.Cu")
		(net "SD_LATCH_RELEASE_U")
	)
	(via
		(at 16.256 -50.7238)
		(size 0.5588)
		(drill 0.3048)
		(layers "F.Cu" "B.Cu")
		(net "SD_LATCH_RELEASE_U")
	)
	(segment
		(start 22.883622 -49.8856)
		(end 25.476708 -49.8856)
		(width 0.1397)
		(layer "B.Cu")
		(net "SD_LATCH_RELEASE_U")
	)
	(segment
		(start 27.178 -51.586892)
		(end 27.178 -53.5178)
		(width 0.1397)
		(layer "B.Cu")
		(net "SD_LATCH_RELEASE_U")
	)
	(segment
		(start 21.4376 -48.375062)
		(end 21.4376 -48.439578)
		(width 0.1397)
		(layer "B.Cu")
		(net "SD_LATCH_RELEASE_U")
	)
	(segment
		(start 20.881594 -47.819056)
		(end 21.4376 -48.375062)
		(width 0.1397)
		(layer "B.Cu")
		(net "SD_LATCH_RELEASE_U")
	)
	(segment
		(start 21.4376 -48.439578)
		(end 22.883622 -49.8856)
		(width 0.1397)
		(layer "B.Cu")
		(net "SD_LATCH_RELEASE_U")
	)
	(segment
		(start 20.118578 -47.819056)
		(end 20.881594 -47.819056)
		(width 0.1397)
		(layer "B.Cu")
		(net "SD_LATCH_RELEASE_U")
	)
	(segment
		(start 27.178 -53.5178)
		(end 28.120086 -54.459886)
		(width 0.1397)
		(layer "B.Cu")
		(net "SD_LATCH_RELEASE_U")
	)
	(segment
		(start 17.213834 -50.7238)
		(end 20.118578 -47.819056)
		(width 0.1397)
		(layer "B.Cu")
		(net "SD_LATCH_RELEASE_U")
	)
	(segment
		(start 16.256 -50.7238)
		(end 17.213834 -50.7238)
		(width 0.1397)
		(layer "B.Cu")
		(net "SD_LATCH_RELEASE_U")
	)
	(segment
		(start 25.476708 -49.8856)
		(end 27.178 -51.586892)
		(width 0.1397)
		(layer "B.Cu")
		(net "SD_LATCH_RELEASE_U")
	)
	(segment
		(start 20.774914 -172.239686)
		(end 21.2979 -172.239686)
		(width 0.1397)
		(layer "F.Cu")
		(net "THERMHOT#_R")
	)
	(segment
		(start 18.28673 -173.42993)
		(end 18.28673 -173.000924)
		(width 0.1397)
		(layer "F.Cu")
		(net "THERMHOT#_R")
	)
	(segment
		(start 20.3073 -172.7073)
		(end 20.774914 -172.239686)
		(width 0.1397)
		(layer "F.Cu")
		(net "THERMHOT#_R")
	)
	(segment
		(start 19.3294 -174.4726)
		(end 18.28673 -173.42993)
		(width 0.1397)
		(layer "F.Cu")
		(net "THERMHOT#_R")
	)
	(segment
		(start 20.3073 -173.2788)
		(end 20.3073 -172.7073)
		(width 0.1397)
		(layer "F.Cu")
		(net "THERMHOT#_R")
	)
	(via
		(at 19.3294 -174.4726)
		(size 0.5588)
		(drill 0.3048)
		(layers "F.Cu" "B.Cu")
		(net "THERMHOT#_R")
	)
	(via
		(at 20.441666 -173.715934)
		(size 0.7112)
		(drill 0.3556)
		(layers "F.Cu" "B.Cu")
		(net "THERMHOT#_R")
	)
	(via
		(at 21.2979 -172.239686)
		(size 0.5588)
		(drill 0.3048)
		(layers "F.Cu" "B.Cu")
		(net "THERMHOT#_R")
	)
	(segment
		(start 21.2979 -172.8597)
		(end 21.2979 -172.239686)
		(width 0.1397)
		(layer "B.Cu")
		(net "THERMHOT#_R")
	)
	(segment
		(start 20.441666 -173.715934)
		(end 21.2979 -172.8597)
		(width 0.1397)
		(layer "B.Cu")
		(net "THERMHOT#_R")
	)
	(segment
		(start 19.3294 -174.4726)
		(end 19.685 -174.4726)
		(width 0.1397)
		(layer "B.Cu")
		(net "THERMHOT#_R")
	)
	(segment
		(start 19.685 -174.4726)
		(end 20.441666 -173.715934)
		(width 0.1397)
		(layer "B.Cu")
		(net "THERMHOT#_R")
	)
	(segment
		(start 28.20924 -214.961216)
		(end 28.20924 -216.19464)
		(width 0.1397)
		(layer "F.Cu")
		(net "PWM_BUFFER_IN_FAN3_FAN4")
	)
	(segment
		(start 11.0236 -69.1642)
		(end 9.2075 -69.1642)
		(width 0.1397)
		(layer "F.Cu")
		(net "PWM_BUFFER_IN_FAN3_FAN4")
	)
	(segment
		(start 28.956 -168.0845)
		(end 28.956 -168.4909)
		(width 0.1397)
		(layer "F.Cu")
		(net "PWM_BUFFER_IN_FAN3_FAN4")
	)
	(segment
		(start 28.85948 -220.600016)
		(end 28.85948 -219.05468)
		(width 0.1397)
		(layer "F.Cu")
		(net "PWM_BUFFER_IN_FAN3_FAN4")
	)
	(segment
		(start 28.956 -168.4909)
		(end 27.813 -168.4909)
		(width 0.1397)
		(layer "F.Cu")
		(net "PWM_BUFFER_IN_FAN3_FAN4")
	)
	(segment
		(start 28.20924 -216.19464)
		(end 28.321 -216.3064)
		(width 0.1397)
		(layer "F.Cu")
		(net "PWM_BUFFER_IN_FAN3_FAN4")
	)
	(segment
		(start 29.3497 -167.6908)
		(end 28.956 -168.0845)
		(width 0.1397)
		(layer "F.Cu")
		(net "PWM_BUFFER_IN_FAN3_FAN4")
	)
	(segment
		(start 28.85948 -219.05468)
		(end 28.8036 -218.9988)
		(width 0.1397)
		(layer "F.Cu")
		(net "PWM_BUFFER_IN_FAN3_FAN4")
	)
	(segment
		(start 27.813 -168.4909)
		(end 27.5209 -168.1988)
		(width 0.1397)
		(layer "F.Cu")
		(net "PWM_BUFFER_IN_FAN3_FAN4")
	)
	(via
		(at 28.956 -168.4909)
		(size 0.5588)
		(drill 0.3048)
		(layers "F.Cu" "B.Cu")
		(net "PWM_BUFFER_IN_FAN3_FAN4")
	)
	(via
		(at 11.0236 -69.1642)
		(size 0.5588)
		(drill 0.3048)
		(layers "F.Cu" "B.Cu")
		(net "PWM_BUFFER_IN_FAN3_FAN4")
	)
	(via
		(at 28.321 -216.3064)
		(size 0.5588)
		(drill 0.3048)
		(layers "F.Cu" "B.Cu")
		(net "PWM_BUFFER_IN_FAN3_FAN4")
	)
	(via
		(at 29.566108 -197.968108)
		(size 0.7112)
		(drill 0.3556)
		(layers "F.Cu" "B.Cu")
		(net "PWM_BUFFER_IN_FAN3_FAN4")
	)
	(via
		(at 28.8036 -218.9988)
		(size 0.5588)
		(drill 0.3048)
		(layers "F.Cu" "B.Cu")
		(net "PWM_BUFFER_IN_FAN3_FAN4")
	)
	(segment
		(start 10.134346 -110.369096)
		(end 10.134346 -109.092238)
		(width 0.1397)
		(layer "B.Cu")
		(net "PWM_BUFFER_IN_FAN3_FAN4")
	)
	(segment
		(start 10.1346 -109.091984)
		(end 10.1346 -92.518738)
		(width 0.1397)
		(layer "B.Cu")
		(net "PWM_BUFFER_IN_FAN3_FAN4")
	)
	(segment
		(start 28.321 -216.3064)
		(end 28.321 -214.1728)
		(width 0.1397)
		(layer "B.Cu")
		(net "PWM_BUFFER_IN_FAN3_FAN4")
	)
	(segment
		(start 28.956 -168.4909)
		(end 29.616146 -167.830754)
		(width 0.1397)
		(layer "B.Cu")
		(net "PWM_BUFFER_IN_FAN3_FAN4")
	)
	(segment
		(start 19.9644 -154.202892)
		(end 19.9644 -150.8506)
		(width 0.1397)
		(layer "B.Cu")
		(net "PWM_BUFFER_IN_FAN3_FAN4")
	)
	(segment
		(start 30.13075 -212.36305)
		(end 30.13075 -198.53275)
		(width 0.1397)
		(layer "B.Cu")
		(net "PWM_BUFFER_IN_FAN3_FAN4")
	)
	(segment
		(start 10.5918 -69.596)
		(end 11.0236 -69.1642)
		(width 0.1397)
		(layer "B.Cu")
		(net "PWM_BUFFER_IN_FAN3_FAN4")
	)
	(segment
		(start 29.616146 -167.830754)
		(end 29.984954 -167.830754)
		(width 0.1397)
		(layer "B.Cu")
		(net "PWM_BUFFER_IN_FAN3_FAN4")
	)
	(segment
		(start 19.9644 -150.8506)
		(end 15.9512 -146.8374)
		(width 0.1397)
		(layer "B.Cu")
		(net "PWM_BUFFER_IN_FAN3_FAN4")
	)
	(segment
		(start 10.134346 -109.092238)
		(end 10.1346 -109.091984)
		(width 0.1397)
		(layer "B.Cu")
		(net "PWM_BUFFER_IN_FAN3_FAN4")
	)
	(segment
		(start 30.13075 -198.53275)
		(end 29.566108 -197.968108)
		(width 0.1397)
		(layer "B.Cu")
		(net "PWM_BUFFER_IN_FAN3_FAN4")
	)
	(segment
		(start 28.321 -216.3064)
		(end 28.321 -218.5162)
		(width 0.1397)
		(layer "B.Cu")
		(net "PWM_BUFFER_IN_FAN3_FAN4")
	)
	(segment
		(start 10.134092 -110.36935)
		(end 10.134346 -110.369096)
		(width 0.1397)
		(layer "B.Cu")
		(net "PWM_BUFFER_IN_FAN3_FAN4")
	)
	(segment
		(start 10.39495 -92.258642)
		(end 10.5918 -92.061792)
		(width 0.1397)
		(layer "B.Cu")
		(net "PWM_BUFFER_IN_FAN3_FAN4")
	)
	(segment
		(start 10.16 -132.887974)
		(end 10.16 -123.8758)
		(width 0.1397)
		(layer "B.Cu")
		(net "PWM_BUFFER_IN_FAN3_FAN4")
	)
	(segment
		(start 15.9512 -146.8374)
		(end 15.9512 -145.2372)
		(width 0.1397)
		(layer "B.Cu")
		(net "PWM_BUFFER_IN_FAN3_FAN4")
	)
	(segment
		(start 31.59125 -165.829742)
		(end 19.9644 -154.202892)
		(width 0.1397)
		(layer "B.Cu")
		(net "PWM_BUFFER_IN_FAN3_FAN4")
	)
	(segment
		(start 11.4173 -112.757458)
		(end 10.134092 -111.47425)
		(width 0.1397)
		(layer "B.Cu")
		(net "PWM_BUFFER_IN_FAN3_FAN4")
	)
	(segment
		(start 28.2956 -169.1513)
		(end 28.956 -168.4909)
		(width 0.1397)
		(layer "B.Cu")
		(net "PWM_BUFFER_IN_FAN3_FAN4")
	)
	(segment
		(start 13.462 -136.189974)
		(end 10.16 -132.887974)
		(width 0.1397)
		(layer "B.Cu")
		(net "PWM_BUFFER_IN_FAN3_FAN4")
	)
	(segment
		(start 28.321 -214.1728)
		(end 30.13075 -212.36305)
		(width 0.1397)
		(layer "B.Cu")
		(net "PWM_BUFFER_IN_FAN3_FAN4")
	)
	(segment
		(start 10.394696 -92.258642)
		(end 10.39495 -92.258642)
		(width 0.1397)
		(layer "B.Cu")
		(net "PWM_BUFFER_IN_FAN3_FAN4")
	)
	(segment
		(start 27.90825 -196.31025)
		(end 27.90825 -177.78095)
		(width 0.1397)
		(layer "B.Cu")
		(net "PWM_BUFFER_IN_FAN3_FAN4")
	)
	(segment
		(start 11.4173 -122.6185)
		(end 11.4173 -112.757458)
		(width 0.1397)
		(layer "B.Cu")
		(net "PWM_BUFFER_IN_FAN3_FAN4")
	)
	(segment
		(start 28.2956 -177.3936)
		(end 28.2956 -169.1513)
		(width 0.1397)
		(layer "B.Cu")
		(net "PWM_BUFFER_IN_FAN3_FAN4")
	)
	(segment
		(start 15.9512 -145.2372)
		(end 13.462 -142.748)
		(width 0.1397)
		(layer "B.Cu")
		(net "PWM_BUFFER_IN_FAN3_FAN4")
	)
	(segment
		(start 13.462 -142.748)
		(end 13.462 -136.189974)
		(width 0.1397)
		(layer "B.Cu")
		(net "PWM_BUFFER_IN_FAN3_FAN4")
	)
	(segment
		(start 29.566108 -197.968108)
		(end 27.90825 -196.31025)
		(width 0.1397)
		(layer "B.Cu")
		(net "PWM_BUFFER_IN_FAN3_FAN4")
	)
	(segment
		(start 10.5918 -92.061792)
		(end 10.5918 -69.596)
		(width 0.1397)
		(layer "B.Cu")
		(net "PWM_BUFFER_IN_FAN3_FAN4")
	)
	(segment
		(start 31.59125 -166.224458)
		(end 31.59125 -165.829742)
		(width 0.1397)
		(layer "B.Cu")
		(net "PWM_BUFFER_IN_FAN3_FAN4")
	)
	(segment
		(start 10.16 -123.8758)
		(end 11.4173 -122.6185)
		(width 0.1397)
		(layer "B.Cu")
		(net "PWM_BUFFER_IN_FAN3_FAN4")
	)
	(segment
		(start 10.1346 -92.518738)
		(end 10.394696 -92.258642)
		(width 0.1397)
		(layer "B.Cu")
		(net "PWM_BUFFER_IN_FAN3_FAN4")
	)
	(segment
		(start 29.984954 -167.830754)
		(end 31.59125 -166.224458)
		(width 0.1397)
		(layer "B.Cu")
		(net "PWM_BUFFER_IN_FAN3_FAN4")
	)
	(segment
		(start 10.134092 -111.47425)
		(end 10.134092 -110.36935)
		(width 0.1397)
		(layer "B.Cu")
		(net "PWM_BUFFER_IN_FAN3_FAN4")
	)
	(segment
		(start 27.90825 -177.78095)
		(end 28.2956 -177.3936)
		(width 0.1397)
		(layer "B.Cu")
		(net "PWM_BUFFER_IN_FAN3_FAN4")
	)
	(segment
		(start 28.321 -218.5162)
		(end 28.8036 -218.9988)
		(width 0.1397)
		(layer "B.Cu")
		(net "PWM_BUFFER_IN_FAN3_FAN4")
	)
	(segment
		(start 25.60955 -214.961216)
		(end 25.60955 -213.74735)
		(width 0.1397)
		(layer "F.Cu")
		(net "PWM_BUFFER_IN_FAN5_FAN6")
	)
	(segment
		(start 26.6446 -168.2115)
		(end 26.6319 -168.1988)
		(width 0.1397)
		(layer "F.Cu")
		(net "PWM_BUFFER_IN_FAN5_FAN6")
	)
	(segment
		(start 27.026616 -213.557358)
		(end 27.026616 -213.5378)
		(width 0.1397)
		(layer "F.Cu")
		(net "PWM_BUFFER_IN_FAN5_FAN6")
	)
	(segment
		(start 27.68727 -169.13606)
		(end 27.56916 -169.13606)
		(width 0.1397)
		(layer "F.Cu")
		(net "PWM_BUFFER_IN_FAN5_FAN6")
	)
	(segment
		(start 24.1808 -168.2115)
		(end 24.3713 -168.021)
		(width 0.1397)
		(layer "F.Cu")
		(net "PWM_BUFFER_IN_FAN5_FAN6")
	)
	(segment
		(start 26.4541 -168.021)
		(end 26.6319 -168.1988)
		(width 0.1397)
		(layer "F.Cu")
		(net "PWM_BUFFER_IN_FAN5_FAN6")
	)
	(segment
		(start 27.56916 -169.13606)
		(end 26.6446 -168.2115)
		(width 0.1397)
		(layer "F.Cu")
		(net "PWM_BUFFER_IN_FAN5_FAN6")
	)
	(segment
		(start 24.3713 -168.021)
		(end 26.4541 -168.021)
		(width 0.1397)
		(layer "F.Cu")
		(net "PWM_BUFFER_IN_FAN5_FAN6")
	)
	(segment
		(start 26.90876 -213.675214)
		(end 27.026616 -213.557358)
		(width 0.1397)
		(layer "F.Cu")
		(net "PWM_BUFFER_IN_FAN5_FAN6")
	)
	(segment
		(start 25.60955 -213.74735)
		(end 25.4762 -213.614)
		(width 0.1397)
		(layer "F.Cu")
		(net "PWM_BUFFER_IN_FAN5_FAN6")
	)
	(segment
		(start 26.90876 -214.961216)
		(end 26.90876 -213.675214)
		(width 0.1397)
		(layer "F.Cu")
		(net "PWM_BUFFER_IN_FAN5_FAN6")
	)
	(via
		(at 25.4762 -213.614)
		(size 0.5588)
		(drill 0.3048)
		(layers "F.Cu" "B.Cu")
		(net "PWM_BUFFER_IN_FAN5_FAN6")
	)
	(via
		(at 27.026616 -213.5378)
		(size 0.5588)
		(drill 0.3048)
		(layers "F.Cu" "B.Cu")
		(net "PWM_BUFFER_IN_FAN5_FAN6")
	)
	(via
		(at 27.68727 -169.13606)
		(size 0.5588)
		(drill 0.3048)
		(layers "F.Cu" "B.Cu")
		(net "PWM_BUFFER_IN_FAN5_FAN6")
	)
	(via
		(at 28.2194 -200.2028)
		(size 0.7112)
		(drill 0.3556)
		(layers "F.Cu" "B.Cu")
		(net "PWM_BUFFER_IN_FAN5_FAN6")
	)
	(segment
		(start 27.40025 -187.2234)
		(end 27.399742 -187.222892)
		(width 0.1397)
		(layer "B.Cu")
		(net "PWM_BUFFER_IN_FAN5_FAN6")
	)
	(segment
		(start 27.399742 -177.285904)
		(end 27.006042 -176.892204)
		(width 0.1397)
		(layer "B.Cu")
		(net "PWM_BUFFER_IN_FAN5_FAN6")
	)
	(segment
		(start 27.40025 -179.888642)
		(end 27.399742 -179.888134)
		(width 0.1397)
		(layer "B.Cu")
		(net "PWM_BUFFER_IN_FAN5_FAN6")
	)
	(segment
		(start 27.399742 -179.888134)
		(end 27.399742 -177.285904)
		(width 0.1397)
		(layer "B.Cu")
		(net "PWM_BUFFER_IN_FAN5_FAN6")
	)
	(segment
		(start 27.399742 -180.283866)
		(end 27.40025 -180.283358)
		(width 0.1397)
		(layer "B.Cu")
		(net "PWM_BUFFER_IN_FAN5_FAN6")
	)
	(segment
		(start 29.68625 -208.93405)
		(end 28.2194 -207.4672)
		(width 0.1397)
		(layer "B.Cu")
		(net "PWM_BUFFER_IN_FAN5_FAN6")
	)
	(segment
		(start 26.950416 -213.614)
		(end 27.026616 -213.5378)
		(width 0.1397)
		(layer "B.Cu")
		(net "PWM_BUFFER_IN_FAN5_FAN6")
	)
	(segment
		(start 27.759152 -171.757848)
		(end 27.759152 -170.967146)
		(width 0.1397)
		(layer "B.Cu")
		(net "PWM_BUFFER_IN_FAN5_FAN6")
	)
	(segment
		(start 27.758898 -169.207688)
		(end 27.68727 -169.13606)
		(width 0.1397)
		(layer "B.Cu")
		(net "PWM_BUFFER_IN_FAN5_FAN6")
	)
	(segment
		(start 28.2194 -200.2028)
		(end 28.2194 -198.9328)
		(width 0.1397)
		(layer "B.Cu")
		(net "PWM_BUFFER_IN_FAN5_FAN6")
	)
	(segment
		(start 27.026616 -213.5378)
		(end 27.471116 -213.5378)
		(width 0.1397)
		(layer "B.Cu")
		(net "PWM_BUFFER_IN_FAN5_FAN6")
	)
	(segment
		(start 28.2194 -198.9328)
		(end 27.40025 -198.11365)
		(width 0.1397)
		(layer "B.Cu")
		(net "PWM_BUFFER_IN_FAN5_FAN6")
	)
	(segment
		(start 29.68625 -211.322666)
		(end 29.68625 -208.93405)
		(width 0.1397)
		(layer "B.Cu")
		(net "PWM_BUFFER_IN_FAN5_FAN6")
	)
	(segment
		(start 27.40025 -198.11365)
		(end 27.40025 -187.2234)
		(width 0.1397)
		(layer "B.Cu")
		(net "PWM_BUFFER_IN_FAN5_FAN6")
	)
	(segment
		(start 27.40025 -180.283358)
		(end 27.40025 -179.888642)
		(width 0.1397)
		(layer "B.Cu")
		(net "PWM_BUFFER_IN_FAN5_FAN6")
	)
	(segment
		(start 28.2194 -207.4672)
		(end 28.2194 -200.2028)
		(width 0.1397)
		(layer "B.Cu")
		(net "PWM_BUFFER_IN_FAN5_FAN6")
	)
	(segment
		(start 25.4762 -213.614)
		(end 26.950416 -213.614)
		(width 0.1397)
		(layer "B.Cu")
		(net "PWM_BUFFER_IN_FAN5_FAN6")
	)
	(segment
		(start 27.399742 -187.222892)
		(end 27.399742 -180.283866)
		(width 0.1397)
		(layer "B.Cu")
		(net "PWM_BUFFER_IN_FAN5_FAN6")
	)
	(segment
		(start 27.006042 -172.510958)
		(end 27.759152 -171.757848)
		(width 0.1397)
		(layer "B.Cu")
		(net "PWM_BUFFER_IN_FAN5_FAN6")
	)
	(segment
		(start 27.758898 -170.966892)
		(end 27.758898 -169.207688)
		(width 0.1397)
		(layer "B.Cu")
		(net "PWM_BUFFER_IN_FAN5_FAN6")
	)
	(segment
		(start 27.471116 -213.5378)
		(end 29.68625 -211.322666)
		(width 0.1397)
		(layer "B.Cu")
		(net "PWM_BUFFER_IN_FAN5_FAN6")
	)
	(segment
		(start 27.006042 -176.892204)
		(end 27.006042 -172.510958)
		(width 0.1397)
		(layer "B.Cu")
		(net "PWM_BUFFER_IN_FAN5_FAN6")
	)
	(segment
		(start 27.759152 -170.967146)
		(end 27.758898 -170.966892)
		(width 0.1397)
		(layer "B.Cu")
		(net "PWM_BUFFER_IN_FAN5_FAN6")
	)
	(segment
		(start 29.06395 -169.13225)
		(end 29.6926 -168.5036)
		(width 0.1397)
		(layer "F.Cu")
		(net "PWM_BUFFER_IN_FAN1_FAN2")
	)
	(segment
		(start 25.9842 -219.313252)
		(end 26.25852 -219.587572)
		(width 0.1397)
		(layer "F.Cu")
		(net "PWM_BUFFER_IN_FAN1_FAN2")
	)
	(segment
		(start 30.2387 -168.269158)
		(end 30.2387 -167.6908)
		(width 0.1397)
		(layer "F.Cu")
		(net "PWM_BUFFER_IN_FAN1_FAN2")
	)
	(segment
		(start 12.192 -71.12)
		(end 11.6332 -70.5612)
		(width 0.1397)
		(layer "F.Cu")
		(net "PWM_BUFFER_IN_FAN1_FAN2")
	)
	(segment
		(start 14.4399 -71.12)
		(end 12.192 -71.12)
		(width 0.1397)
		(layer "F.Cu")
		(net "PWM_BUFFER_IN_FAN1_FAN2")
	)
	(segment
		(start 29.06395 -169.85615)
		(end 29.06395 -169.13225)
		(width 0.1397)
		(layer "F.Cu")
		(net "PWM_BUFFER_IN_FAN1_FAN2")
	)
	(segment
		(start 29.5529 -170.3324)
		(end 29.5402 -170.3324)
		(width 0.1397)
		(layer "F.Cu")
		(net "PWM_BUFFER_IN_FAN1_FAN2")
	)
	(segment
		(start 26.25852 -219.587572)
		(end 26.25852 -220.600016)
		(width 0.1397)
		(layer "F.Cu")
		(net "PWM_BUFFER_IN_FAN1_FAN2")
	)
	(segment
		(start 30.004258 -168.5036)
		(end 30.2387 -168.269158)
		(width 0.1397)
		(layer "F.Cu")
		(net "PWM_BUFFER_IN_FAN1_FAN2")
	)
	(segment
		(start 29.6926 -168.5036)
		(end 30.004258 -168.5036)
		(width 0.1397)
		(layer "F.Cu")
		(net "PWM_BUFFER_IN_FAN1_FAN2")
	)
	(segment
		(start 29.5402 -170.3324)
		(end 29.06395 -169.85615)
		(width 0.1397)
		(layer "F.Cu")
		(net "PWM_BUFFER_IN_FAN1_FAN2")
	)
	(segment
		(start 27.559 -220.600016)
		(end 27.559 -219.359734)
		(width 0.1397)
		(layer "F.Cu")
		(net "PWM_BUFFER_IN_FAN1_FAN2")
	)
	(segment
		(start 27.559 -219.359734)
		(end 27.219656 -219.02039)
		(width 0.1397)
		(layer "F.Cu")
		(net "PWM_BUFFER_IN_FAN1_FAN2")
	)
	(via
		(at 11.6332 -70.5612)
		(size 0.5588)
		(drill 0.3048)
		(layers "F.Cu" "B.Cu")
		(net "PWM_BUFFER_IN_FAN1_FAN2")
	)
	(via
		(at 27.219656 -219.02039)
		(size 0.5588)
		(drill 0.3048)
		(layers "F.Cu" "B.Cu")
		(net "PWM_BUFFER_IN_FAN1_FAN2")
	)
	(via
		(at 25.9842 -219.313252)
		(size 0.5588)
		(drill 0.3048)
		(layers "F.Cu" "B.Cu")
		(net "PWM_BUFFER_IN_FAN1_FAN2")
	)
	(via
		(at 29.265118 -194.441318)
		(size 0.7112)
		(drill 0.3556)
		(layers "F.Cu" "B.Cu")
		(net "PWM_BUFFER_IN_FAN1_FAN2")
	)
	(via
		(at 30.004258 -168.5036)
		(size 0.5588)
		(drill 0.3048)
		(layers "F.Cu" "B.Cu")
		(net "PWM_BUFFER_IN_FAN1_FAN2")
	)
	(segment
		(start 28.35275 -193.52895)
		(end 28.35275 -177.97145)
		(width 0.1397)
		(layer "B.Cu")
		(net "PWM_BUFFER_IN_FAN1_FAN2")
	)
	(segment
		(start 32.17545 -197.35165)
		(end 29.265118 -194.441318)
		(width 0.1397)
		(layer "B.Cu")
		(net "PWM_BUFFER_IN_FAN1_FAN2")
	)
	(segment
		(start 32.03575 -166.46525)
		(end 30.004258 -168.496742)
		(width 0.1397)
		(layer "B.Cu")
		(net "PWM_BUFFER_IN_FAN1_FAN2")
	)
	(segment
		(start 16.4084 -146.6596)
		(end 20.4216 -150.6728)
		(width 0.1397)
		(layer "B.Cu")
		(net "PWM_BUFFER_IN_FAN1_FAN2")
	)
	(segment
		(start 27.219656 -219.02039)
		(end 27.674316 -219.47505)
		(width 0.1397)
		(layer "B.Cu")
		(net "PWM_BUFFER_IN_FAN1_FAN2")
	)
	(segment
		(start 30.004258 -168.496742)
		(end 30.004258 -168.5036)
		(width 0.1397)
		(layer "B.Cu")
		(net "PWM_BUFFER_IN_FAN1_FAN2")
	)
	(segment
		(start 16.4084 -145.0594)
		(end 16.4084 -146.6596)
		(width 0.1397)
		(layer "B.Cu")
		(net "PWM_BUFFER_IN_FAN1_FAN2")
	)
	(segment
		(start 11.6332 -70.5612)
		(end 11.0363 -71.1581)
		(width 0.1397)
		(layer "B.Cu")
		(net "PWM_BUFFER_IN_FAN1_FAN2")
	)
	(segment
		(start 27.674316 -219.47505)
		(end 29.000958 -219.47505)
		(width 0.1397)
		(layer "B.Cu")
		(net "PWM_BUFFER_IN_FAN1_FAN2")
	)
	(segment
		(start 20.4216 -150.6728)
		(end 20.4216 -154.031442)
		(width 0.1397)
		(layer "B.Cu")
		(net "PWM_BUFFER_IN_FAN1_FAN2")
	)
	(segment
		(start 10.578592 -110.5535)
		(end 10.578592 -111.2901)
		(width 0.1397)
		(layer "B.Cu")
		(net "PWM_BUFFER_IN_FAN1_FAN2")
	)
	(segment
		(start 28.7528 -169.755058)
		(end 30.004258 -168.5036)
		(width 0.1397)
		(layer "B.Cu")
		(net "PWM_BUFFER_IN_FAN1_FAN2")
	)
	(segment
		(start 14.1224 -125.0696)
		(end 14.1224 -142.7734)
		(width 0.1397)
		(layer "B.Cu")
		(net "PWM_BUFFER_IN_FAN1_FAN2")
	)
	(segment
		(start 28.7528 -177.5714)
		(end 28.7528 -169.755058)
		(width 0.1397)
		(layer "B.Cu")
		(net "PWM_BUFFER_IN_FAN1_FAN2")
	)
	(segment
		(start 10.578846 -109.276388)
		(end 10.578846 -110.553246)
		(width 0.1397)
		(layer "B.Cu")
		(net "PWM_BUFFER_IN_FAN1_FAN2")
	)
	(segment
		(start 10.5791 -109.276134)
		(end 10.578846 -109.276388)
		(width 0.1397)
		(layer "B.Cu")
		(net "PWM_BUFFER_IN_FAN1_FAN2")
	)
	(segment
		(start 14.1224 -142.7734)
		(end 16.4084 -145.0594)
		(width 0.1397)
		(layer "B.Cu")
		(net "PWM_BUFFER_IN_FAN1_FAN2")
	)
	(segment
		(start 28.35275 -177.97145)
		(end 28.7528 -177.5714)
		(width 0.1397)
		(layer "B.Cu")
		(net "PWM_BUFFER_IN_FAN1_FAN2")
	)
	(segment
		(start 11.8618 -112.573308)
		(end 11.8618 -122.809)
		(width 0.1397)
		(layer "B.Cu")
		(net "PWM_BUFFER_IN_FAN1_FAN2")
	)
	(segment
		(start 27.219656 -219.02039)
		(end 26.277062 -219.02039)
		(width 0.1397)
		(layer "B.Cu")
		(net "PWM_BUFFER_IN_FAN1_FAN2")
	)
	(segment
		(start 29.000958 -219.47505)
		(end 32.17545 -216.300558)
		(width 0.1397)
		(layer "B.Cu")
		(net "PWM_BUFFER_IN_FAN1_FAN2")
	)
	(segment
		(start 29.265118 -194.441318)
		(end 28.35275 -193.52895)
		(width 0.1397)
		(layer "B.Cu")
		(net "PWM_BUFFER_IN_FAN1_FAN2")
	)
	(segment
		(start 11.8618 -122.809)
		(end 14.1224 -125.0696)
		(width 0.1397)
		(layer "B.Cu")
		(net "PWM_BUFFER_IN_FAN1_FAN2")
	)
	(segment
		(start 32.17545 -216.300558)
		(end 32.17545 -197.35165)
		(width 0.1397)
		(layer "B.Cu")
		(net "PWM_BUFFER_IN_FAN1_FAN2")
	)
	(segment
		(start 32.03575 -165.645592)
		(end 32.03575 -166.46525)
		(width 0.1397)
		(layer "B.Cu")
		(net "PWM_BUFFER_IN_FAN1_FAN2")
	)
	(segment
		(start 20.4216 -154.031442)
		(end 32.03575 -165.645592)
		(width 0.1397)
		(layer "B.Cu")
		(net "PWM_BUFFER_IN_FAN1_FAN2")
	)
	(segment
		(start 26.277062 -219.02039)
		(end 25.9842 -219.313252)
		(width 0.1397)
		(layer "B.Cu")
		(net "PWM_BUFFER_IN_FAN1_FAN2")
	)
	(segment
		(start 11.0363 -71.1581)
		(end 11.0363 -92.245942)
		(width 0.1397)
		(layer "B.Cu")
		(net "PWM_BUFFER_IN_FAN1_FAN2")
	)
	(segment
		(start 10.578592 -111.2901)
		(end 11.8618 -112.573308)
		(width 0.1397)
		(layer "B.Cu")
		(net "PWM_BUFFER_IN_FAN1_FAN2")
	)
	(segment
		(start 11.0363 -92.245942)
		(end 10.5791 -92.703142)
		(width 0.1397)
		(layer "B.Cu")
		(net "PWM_BUFFER_IN_FAN1_FAN2")
	)
	(segment
		(start 10.578846 -110.553246)
		(end 10.578592 -110.5535)
		(width 0.1397)
		(layer "B.Cu")
		(net "PWM_BUFFER_IN_FAN1_FAN2")
	)
	(segment
		(start 10.5791 -92.703142)
		(end 10.5791 -109.276134)
		(width 0.1397)
		(layer "B.Cu")
		(net "PWM_BUFFER_IN_FAN1_FAN2")
	)
	(segment
		(start 27.199336 -61.159136)
		(end 25.580086 -59.539886)
		(width 0.1397)
		(layer "F.Cu")
		(net "P12VU_2490_EN_2")
	)
	(segment
		(start 24.511 -143.1798)
		(end 24.4602 -143.129)
		(width 0.1397)
		(layer "F.Cu")
		(net "P12VU_2490_EN_2")
	)
	(segment
		(start 23.1902 -144.7165)
		(end 23.9649 -144.7165)
		(width 0.1397)
		(layer "F.Cu")
		(net "P12VU_2490_EN_2")
	)
	(segment
		(start 27.3304 -141.4272)
		(end 28.6004 -140.1572)
		(width 0.1397)
		(layer "F.Cu")
		(net "P12VU_2490_EN_2")
	)
	(segment
		(start 28.6004 -140.1572)
		(end 29.2862 -140.1572)
		(width 0.1397)
		(layer "F.Cu")
		(net "P12VU_2490_EN_2")
	)
	(segment
		(start 27.3304 -141.8082)
		(end 27.3304 -141.4272)
		(width 0.1397)
		(layer "F.Cu")
		(net "P12VU_2490_EN_2")
	)
	(segment
		(start 22.69109 -144.21739)
		(end 23.1902 -144.7165)
		(width 0.1397)
		(layer "F.Cu")
		(net "P12VU_2490_EN_2")
	)
	(segment
		(start 32.3088 -62.484)
		(end 30.983936 -61.159136)
		(width 0.1397)
		(layer "F.Cu")
		(net "P12VU_2490_EN_2")
	)
	(segment
		(start 22.69109 -142.5067)
		(end 22.69109 -144.21739)
		(width 0.1397)
		(layer "F.Cu")
		(net "P12VU_2490_EN_2")
	)
	(segment
		(start 30.983936 -61.159136)
		(end 27.199336 -61.159136)
		(width 0.1397)
		(layer "F.Cu")
		(net "P12VU_2490_EN_2")
	)
	(segment
		(start 24.4602 -143.129)
		(end 25.0952 -143.129)
		(width 0.1397)
		(layer "F.Cu")
		(net "P12VU_2490_EN_2")
	)
	(segment
		(start 23.9649 -144.7165)
		(end 24.511 -144.1704)
		(width 0.1397)
		(layer "F.Cu")
		(net "P12VU_2490_EN_2")
	)
	(segment
		(start 25.0952 -143.129)
		(end 25.781 -142.4432)
		(width 0.1397)
		(layer "F.Cu")
		(net "P12VU_2490_EN_2")
	)
	(segment
		(start 24.511 -144.1704)
		(end 24.511 -143.1798)
		(width 0.1397)
		(layer "F.Cu")
		(net "P12VU_2490_EN_2")
	)
	(segment
		(start 26.6954 -142.4432)
		(end 27.3304 -141.8082)
		(width 0.1397)
		(layer "F.Cu")
		(net "P12VU_2490_EN_2")
	)
	(segment
		(start 25.781 -142.4432)
		(end 26.6954 -142.4432)
		(width 0.1397)
		(layer "F.Cu")
		(net "P12VU_2490_EN_2")
	)
	(via
		(at 29.2862 -140.1572)
		(size 0.5588)
		(drill 0.3048)
		(layers "F.Cu" "B.Cu")
		(net "P12VU_2490_EN_2")
	)
	(via
		(at 24.511 -144.1704)
		(size 0.7112)
		(drill 0.3556)
		(layers "F.Cu" "B.Cu")
		(net "P12VU_2490_EN_2")
	)
	(via
		(at 32.3088 -62.484)
		(size 0.5588)
		(drill 0.3048)
		(layers "F.Cu" "B.Cu")
		(net "P12VU_2490_EN_2")
	)
	(segment
		(start 29.2862 -140.1572)
		(end 29.622496 -140.1572)
		(width 0.1397)
		(layer "B.Cu")
		(net "P12VU_2490_EN_2")
	)
	(segment
		(start 34.499296 -112.98555)
		(end 32.3088 -110.795054)
		(width 0.1397)
		(layer "B.Cu")
		(net "P12VU_2490_EN_2")
	)
	(segment
		(start 37.12845 -132.651246)
		(end 37.12845 -115.341146)
		(width 0.1397)
		(layer "B.Cu")
		(net "P12VU_2490_EN_2")
	)
	(segment
		(start 37.12845 -115.341146)
		(end 34.772854 -112.98555)
		(width 0.1397)
		(layer "B.Cu")
		(net "P12VU_2490_EN_2")
	)
	(segment
		(start 29.622496 -140.1572)
		(end 37.12845 -132.651246)
		(width 0.1397)
		(layer "B.Cu")
		(net "P12VU_2490_EN_2")
	)
	(segment
		(start 32.3088 -110.795054)
		(end 32.3088 -62.484)
		(width 0.1397)
		(layer "B.Cu")
		(net "P12VU_2490_EN_2")
	)
	(segment
		(start 34.772854 -112.98555)
		(end 34.499296 -112.98555)
		(width 0.1397)
		(layer "B.Cu")
		(net "P12VU_2490_EN_2")
	)
	(segment
		(start 37.5666 -149.3774)
		(end 38.5191 -149.3774)
		(width 0.1397)
		(layer "F.Cu")
		(net "P12VU_2490_EN_1")
	)
	(segment
		(start 38.5191 -149.3774)
		(end 38.7985 -149.098)
		(width 0.1397)
		(layer "F.Cu")
		(net "P12VU_2490_EN_1")
	)
	(via
		(at 37.5666 -149.3774)
		(size 0.5588)
		(drill 0.3048)
		(layers "F.Cu" "B.Cu")
		(net "P12VU_2490_EN_1")
	)
	(segment
		(start 35.9156 -107.4928)
		(end 35.9156 -97.4344)
		(width 0.1397)
		(layer "B.Cu")
		(net "P12VU_2490_EN_1")
	)
	(segment
		(start 37.4904 -149.3012)
		(end 37.4904 -141.5034)
		(width 0.1397)
		(layer "B.Cu")
		(net "P12VU_2490_EN_1")
	)
	(segment
		(start 34.4932 -62.5348)
		(end 33.3756 -61.4172)
		(width 0.1397)
		(layer "B.Cu")
		(net "P12VU_2490_EN_1")
	)
	(segment
		(start 26.7716 -63.2714)
		(end 26.0858 -62.5856)
		(width 0.1397)
		(layer "B.Cu")
		(net "P12VU_2490_EN_1")
	)
	(segment
		(start 26.0604 -62.5602)
		(end 25.580086 -62.079886)
		(width 0.1397)
		(layer "B.Cu")
		(net "P12VU_2490_EN_1")
	)
	(segment
		(start 37.5666 -149.3774)
		(end 37.4904 -149.3012)
		(width 0.1397)
		(layer "B.Cu")
		(net "P12VU_2490_EN_1")
	)
	(segment
		(start 34.798 -111.2012)
		(end 34.798 -108.6104)
		(width 0.1397)
		(layer "B.Cu")
		(net "P12VU_2490_EN_1")
	)
	(segment
		(start 37.4904 -141.5034)
		(end 38.4048 -140.589)
		(width 0.1397)
		(layer "B.Cu")
		(net "P12VU_2490_EN_1")
	)
	(segment
		(start 35.9156 -97.4344)
		(end 34.4932 -96.012)
		(width 0.1397)
		(layer "B.Cu")
		(net "P12VU_2490_EN_1")
	)
	(segment
		(start 26.0858 -62.5602)
		(end 26.0604 -62.5602)
		(width 0.1397)
		(layer "B.Cu")
		(net "P12VU_2490_EN_1")
	)
	(segment
		(start 34.798 -108.6104)
		(end 35.9156 -107.4928)
		(width 0.1397)
		(layer "B.Cu")
		(net "P12VU_2490_EN_1")
	)
	(segment
		(start 38.4048 -114.808)
		(end 34.798 -111.2012)
		(width 0.1397)
		(layer "B.Cu")
		(net "P12VU_2490_EN_1")
	)
	(segment
		(start 28.6258 -63.2714)
		(end 26.7716 -63.2714)
		(width 0.1397)
		(layer "B.Cu")
		(net "P12VU_2490_EN_1")
	)
	(segment
		(start 34.4932 -96.012)
		(end 34.4932 -62.5348)
		(width 0.1397)
		(layer "B.Cu")
		(net "P12VU_2490_EN_1")
	)
	(segment
		(start 38.4048 -140.589)
		(end 38.4048 -114.808)
		(width 0.1397)
		(layer "B.Cu")
		(net "P12VU_2490_EN_1")
	)
	(segment
		(start 30.48 -61.4172)
		(end 28.6258 -63.2714)
		(width 0.1397)
		(layer "B.Cu")
		(net "P12VU_2490_EN_1")
	)
	(segment
		(start 26.0858 -62.5856)
		(end 26.0858 -62.5602)
		(width 0.1397)
		(layer "B.Cu")
		(net "P12VU_2490_EN_1")
	)
	(segment
		(start 33.3756 -61.4172)
		(end 30.48 -61.4172)
		(width 0.1397)
		(layer "B.Cu")
		(net "P12VU_2490_EN_1")
	)
	(segment
		(start 14.3891 -171.0309)
		(end 14.5796 -171.0309)
		(width 0.1397)
		(layer "F.Cu")
		(net "SEB_PEER_1A_1B_HB_OUT")
	)
	(segment
		(start 15.718536 -169.642536)
		(end 16.24965 -170.17365)
		(width 0.1397)
		(layer "F.Cu")
		(net "SEB_PEER_1A_1B_HB_OUT")
	)
	(segment
		(start 14.5288 -169.642536)
		(end 15.718536 -169.642536)
		(width 0.1397)
		(layer "F.Cu")
		(net "SEB_PEER_1A_1B_HB_OUT")
	)
	(segment
		(start 10.8585 -174.10176)
		(end 12.08786 -172.8724)
		(width 0.1397)
		(layer "F.Cu")
		(net "SEB_PEER_1A_1B_HB_OUT")
	)
	(segment
		(start 13.95095 -171.469304)
		(end 13.95095 -171.46905)
		(width 0.1397)
		(layer "F.Cu")
		(net "SEB_PEER_1A_1B_HB_OUT")
	)
	(segment
		(start 12.547854 -172.8724)
		(end 13.95095 -171.469304)
		(width 0.1397)
		(layer "F.Cu")
		(net "SEB_PEER_1A_1B_HB_OUT")
	)
	(segment
		(start 12.08786 -172.8724)
		(end 12.547854 -172.8724)
		(width 0.1397)
		(layer "F.Cu")
		(net "SEB_PEER_1A_1B_HB_OUT")
	)
	(segment
		(start 16.24965 -170.17365)
		(end 16.5989 -170.17365)
		(width 0.1397)
		(layer "F.Cu")
		(net "SEB_PEER_1A_1B_HB_OUT")
	)
	(segment
		(start 14.5796 -171.0309)
		(end 14.5288 -170.9801)
		(width 0.1397)
		(layer "F.Cu")
		(net "SEB_PEER_1A_1B_HB_OUT")
	)
	(segment
		(start 14.5288 -170.9801)
		(end 14.5288 -169.642536)
		(width 0.1397)
		(layer "F.Cu")
		(net "SEB_PEER_1A_1B_HB_OUT")
	)
	(segment
		(start 13.95095 -171.46905)
		(end 14.3891 -171.0309)
		(width 0.1397)
		(layer "F.Cu")
		(net "SEB_PEER_1A_1B_HB_OUT")
	)
	(segment
		(start 16.5989 -170.17365)
		(end 16.98625 -170.561)
		(width 0.1397)
		(layer "F.Cu")
		(net "SEB_PEER_1A_1B_HB_OUT")
	)
	(segment
		(start 16.98625 -170.561)
		(end 16.98625 -171.349924)
		(width 0.1397)
		(layer "F.Cu")
		(net "SEB_PEER_1A_1B_HB_OUT")
	)
	(via
		(at 14.5288 -169.642536)
		(size 0.7112)
		(drill 0.3556)
		(layers "F.Cu" "B.Cu")
		(net "SEB_PEER_1A_1B_HB_OUT")
	)
	(segment
		(start 12.2682 -50.7238)
		(end 12.1412 -50.5968)
		(width 0.1397)
		(layer "F.Cu")
		(net "SELF_1A_HB")
	)
	(segment
		(start 14.4399 -44.5262)
		(end 13.3604 -44.5262)
		(width 0.1397)
		(layer "F.Cu")
		(net "SELF_1A_HB")
	)
	(segment
		(start 13.3604 -44.5262)
		(end 13.335 -44.5008)
		(width 0.1397)
		(layer "F.Cu")
		(net "SELF_1A_HB")
	)
	(segment
		(start 13.589 -50.7238)
		(end 12.2682 -50.7238)
		(width 0.1397)
		(layer "F.Cu")
		(net "SELF_1A_HB")
	)
	(via
		(at 12.1412 -50.5968)
		(size 0.5588)
		(drill 0.3048)
		(layers "F.Cu" "B.Cu")
		(net "SELF_1A_HB")
	)
	(via
		(at 13.589 -50.7238)
		(size 0.5588)
		(drill 0.3048)
		(layers "F.Cu" "B.Cu")
		(net "SELF_1A_HB")
	)
	(via
		(at 13.335 -44.5008)
		(size 0.5588)
		(drill 0.3048)
		(layers "F.Cu" "B.Cu")
		(net "SELF_1A_HB")
	)
	(segment
		(start 12.1412 -50.5968)
		(end 12.192 -50.546)
		(width 0.1397)
		(layer "B.Cu")
		(net "SELF_1A_HB")
	)
	(segment
		(start 26.500836 -56.079136)
		(end 25.580086 -56.999886)
		(width 0.1397)
		(layer "B.Cu")
		(net "SELF_1A_HB")
	)
	(segment
		(start 21.281136 -50.110136)
		(end 21.5138 -50.3428)
		(width 0.1397)
		(layer "B.Cu")
		(net "SELF_1A_HB")
	)
	(segment
		(start 13.589 -50.7238)
		(end 14.06525 -51.20005)
		(width 0.1397)
		(layer "B.Cu")
		(net "SELF_1A_HB")
	)
	(segment
		(start 25.305258 -50.3428)
		(end 26.500836 -51.538378)
		(width 0.1397)
		(layer "B.Cu")
		(net "SELF_1A_HB")
	)
	(segment
		(start 19.7104 -50.1142)
		(end 19.714464 -50.110136)
		(width 0.1397)
		(layer "B.Cu")
		(net "SELF_1A_HB")
	)
	(segment
		(start 19.714464 -50.110136)
		(end 21.281136 -50.110136)
		(width 0.1397)
		(layer "B.Cu")
		(net "SELF_1A_HB")
	)
	(segment
		(start 12.192 -47.9044)
		(end 13.335 -46.7614)
		(width 0.1397)
		(layer "B.Cu")
		(net "SELF_1A_HB")
	)
	(segment
		(start 12.192 -50.546)
		(end 12.192 -47.9044)
		(width 0.1397)
		(layer "B.Cu")
		(net "SELF_1A_HB")
	)
	(segment
		(start 26.500836 -51.538378)
		(end 26.500836 -56.079136)
		(width 0.1397)
		(layer "B.Cu")
		(net "SELF_1A_HB")
	)
	(segment
		(start 14.06525 -51.20005)
		(end 17.366234 -51.20005)
		(width 0.1397)
		(layer "B.Cu")
		(net "SELF_1A_HB")
	)
	(segment
		(start 21.5138 -50.3428)
		(end 25.305258 -50.3428)
		(width 0.1397)
		(layer "B.Cu")
		(net "SELF_1A_HB")
	)
	(segment
		(start 17.366234 -51.20005)
		(end 18.452084 -50.1142)
		(width 0.1397)
		(layer "B.Cu")
		(net "SELF_1A_HB")
	)
	(segment
		(start 18.452084 -50.1142)
		(end 19.7104 -50.1142)
		(width 0.1397)
		(layer "B.Cu")
		(net "SELF_1A_HB")
	)
	(segment
		(start 13.335 -46.7614)
		(end 13.335 -44.5008)
		(width 0.1397)
		(layer "B.Cu")
		(net "SELF_1A_HB")
	)
	(segment
		(start 15.35684 -173.36516)
		(end 14.7955 -173.9265)
		(width 0.1397)
		(layer "F.Cu")
		(net "SEB_PEER_2A_2B_HB_OUT")
	)
	(segment
		(start 15.85595 -171.29125)
		(end 15.5956 -171.0309)
		(width 0.1397)
		(layer "F.Cu")
		(net "SEB_PEER_2A_2B_HB_OUT")
	)
	(segment
		(start 16.701262 -172.156374)
		(end 16.22425 -171.679362)
		(width 0.1397)
		(layer "F.Cu")
		(net "SEB_PEER_2A_2B_HB_OUT")
	)
	(segment
		(start 17.63649 -171.349924)
		(end 17.63649 -171.84751)
		(width 0.1397)
		(layer "F.Cu")
		(net "SEB_PEER_2A_2B_HB_OUT")
	)
	(segment
		(start 17.327626 -172.156374)
		(end 16.701262 -172.156374)
		(width 0.1397)
		(layer "F.Cu")
		(net "SEB_PEER_2A_2B_HB_OUT")
	)
	(segment
		(start 16.22425 -171.679362)
		(end 16.22425 -171.659296)
		(width 0.1397)
		(layer "F.Cu")
		(net "SEB_PEER_2A_2B_HB_OUT")
	)
	(segment
		(start 15.367 -173.36516)
		(end 15.35684 -173.36516)
		(width 0.1397)
		(layer "F.Cu")
		(net "SEB_PEER_2A_2B_HB_OUT")
	)
	(segment
		(start 17.63649 -171.84751)
		(end 17.327626 -172.156374)
		(width 0.1397)
		(layer "F.Cu")
		(net "SEB_PEER_2A_2B_HB_OUT")
	)
	(segment
		(start 15.5956 -170.3578)
		(end 15.5956 -171.0309)
		(width 0.1397)
		(layer "F.Cu")
		(net "SEB_PEER_2A_2B_HB_OUT")
	)
	(segment
		(start 15.856204 -171.29125)
		(end 15.85595 -171.29125)
		(width 0.1397)
		(layer "F.Cu")
		(net "SEB_PEER_2A_2B_HB_OUT")
	)
	(segment
		(start 16.22425 -171.659296)
		(end 15.856204 -171.29125)
		(width 0.1397)
		(layer "F.Cu")
		(net "SEB_PEER_2A_2B_HB_OUT")
	)
	(segment
		(start 14.7955 -173.9265)
		(end 14.7955 -174.10176)
		(width 0.1397)
		(layer "F.Cu")
		(net "SEB_PEER_2A_2B_HB_OUT")
	)
	(segment
		(start 15.4686 -170.2308)
		(end 15.5956 -170.3578)
		(width 0.1397)
		(layer "F.Cu")
		(net "SEB_PEER_2A_2B_HB_OUT")
	)
	(via
		(at 15.367 -173.36516)
		(size 0.5588)
		(drill 0.3048)
		(layers "F.Cu" "B.Cu")
		(net "SEB_PEER_2A_2B_HB_OUT")
	)
	(via
		(at 15.4686 -170.2308)
		(size 0.5588)
		(drill 0.3048)
		(layers "F.Cu" "B.Cu")
		(net "SEB_PEER_2A_2B_HB_OUT")
	)
	(via
		(at 15.367 -171.3738)
		(size 0.7112)
		(drill 0.3556)
		(layers "F.Cu" "B.Cu")
		(net "SEB_PEER_2A_2B_HB_OUT")
	)
	(segment
		(start 15.367 -170.3324)
		(end 15.367 -171.3738)
		(width 0.1397)
		(layer "B.Cu")
		(net "SEB_PEER_2A_2B_HB_OUT")
	)
	(segment
		(start 15.367 -171.3738)
		(end 15.367 -173.36516)
		(width 0.1397)
		(layer "B.Cu")
		(net "SEB_PEER_2A_2B_HB_OUT")
	)
	(segment
		(start 15.4686 -170.2308)
		(end 15.367 -170.3324)
		(width 0.1397)
		(layer "B.Cu")
		(net "SEB_PEER_2A_2B_HB_OUT")
	)
	(segment
		(start 15.3543 -46.5836)
		(end 15.3289 -46.5582)
		(width 0.1397)
		(layer "F.Cu")
		(net "SELF_2A_HB")
	)
	(segment
		(start 16.3576 -46.5836)
		(end 15.3543 -46.5836)
		(width 0.1397)
		(layer "F.Cu")
		(net "SELF_2A_HB")
	)
	(via
		(at 16.3576 -46.5836)
		(size 0.5588)
		(drill 0.3048)
		(layers "F.Cu" "B.Cu")
		(net "SELF_2A_HB")
	)
	(segment
		(start 21.085556 -44.834556)
		(end 19.934428 -44.834556)
		(width 0.1397)
		(layer "B.Cu")
		(net "SELF_2A_HB")
	)
	(segment
		(start 21.463 -45.212)
		(end 21.085556 -44.834556)
		(width 0.1397)
		(layer "B.Cu")
		(net "SELF_2A_HB")
	)
	(segment
		(start 36.83 -53.539136)
		(end 28.502864 -45.212)
		(width 0.1397)
		(layer "B.Cu")
		(net "SELF_2A_HB")
	)
	(segment
		(start 19.934428 -44.834556)
		(end 18.185384 -46.5836)
		(width 0.1397)
		(layer "B.Cu")
		(net "SELF_2A_HB")
	)
	(segment
		(start 41.8084 -54.0766)
		(end 41.270936 -53.539136)
		(width 0.1397)
		(layer "B.Cu")
		(net "SELF_2A_HB")
	)
	(segment
		(start 43.07967 -56.999886)
		(end 41.8084 -55.728616)
		(width 0.1397)
		(layer "B.Cu")
		(net "SELF_2A_HB")
	)
	(segment
		(start 41.8084 -55.728616)
		(end 41.8084 -54.0766)
		(width 0.1397)
		(layer "B.Cu")
		(net "SELF_2A_HB")
	)
	(segment
		(start 18.185384 -46.5836)
		(end 16.3576 -46.5836)
		(width 0.1397)
		(layer "B.Cu")
		(net "SELF_2A_HB")
	)
	(segment
		(start 28.502864 -45.212)
		(end 21.463 -45.212)
		(width 0.1397)
		(layer "B.Cu")
		(net "SELF_2A_HB")
	)
	(segment
		(start 41.270936 -53.539136)
		(end 36.83 -53.539136)
		(width 0.1397)
		(layer "B.Cu")
		(net "SELF_2A_HB")
	)
	(segment
		(start 43.079924 -56.999886)
		(end 43.07967 -56.999886)
		(width 0.1397)
		(layer "B.Cu")
		(net "SELF_2A_HB")
	)
	(segment
		(start 15.3289 -42.4942)
		(end 17.5514 -44.7167)
		(width 0.1397)
		(layer "F.Cu")
		(net "SELF_2B_HB")
	)
	(segment
		(start 38.92042 -51.538378)
		(end 38.92042 -52.840636)
		(width 0.1397)
		(layer "F.Cu")
		(net "SELF_2B_HB")
	)
	(segment
		(start 17.5514 -44.7167)
		(end 29.20365 -44.7167)
		(width 0.1397)
		(layer "F.Cu")
		(net "SELF_2B_HB")
	)
	(segment
		(start 36.013136 -50.999136)
		(end 38.381178 -50.999136)
		(width 0.1397)
		(layer "F.Cu")
		(net "SELF_2B_HB")
	)
	(segment
		(start 29.203904 -44.716446)
		(end 29.571696 -44.716446)
		(width 0.1397)
		(layer "F.Cu")
		(net "SELF_2B_HB")
	)
	(segment
		(start 38.381178 -50.999136)
		(end 38.92042 -51.538378)
		(width 0.1397)
		(layer "F.Cu")
		(net "SELF_2B_HB")
	)
	(segment
		(start 29.20365 -44.7167)
		(end 29.203904 -44.716446)
		(width 0.1397)
		(layer "F.Cu")
		(net "SELF_2B_HB")
	)
	(segment
		(start 29.7307 -44.7167)
		(end 36.013136 -50.999136)
		(width 0.1397)
		(layer "F.Cu")
		(net "SELF_2B_HB")
	)
	(segment
		(start 29.57195 -44.7167)
		(end 29.7307 -44.7167)
		(width 0.1397)
		(layer "F.Cu")
		(net "SELF_2B_HB")
	)
	(segment
		(start 29.571696 -44.716446)
		(end 29.57195 -44.7167)
		(width 0.1397)
		(layer "F.Cu")
		(net "SELF_2B_HB")
	)
	(segment
		(start 40.53967 -54.459886)
		(end 40.539924 -54.459886)
		(width 0.1397)
		(layer "F.Cu")
		(net "SELF_2B_HB")
	)
	(segment
		(start 38.92042 -52.840636)
		(end 40.53967 -54.459886)
		(width 0.1397)
		(layer "F.Cu")
		(net "SELF_2B_HB")
	)
	(segment
		(start 13.3858 -41.2242)
		(end 13.3858 -40.894)
		(width 0.1397)
		(layer "F.Cu")
		(net "SELF_1B_HB")
	)
	(segment
		(start 13.506196 -52.16525)
		(end 18.99285 -52.16525)
		(width 0.1397)
		(layer "F.Cu")
		(net "SELF_1B_HB")
	)
	(segment
		(start 12.6238 -53.047646)
		(end 13.506196 -52.16525)
		(width 0.1397)
		(layer "F.Cu")
		(net "SELF_1B_HB")
	)
	(segment
		(start 13.8176 -40.4622)
		(end 14.4399 -40.4622)
		(width 0.1397)
		(layer "F.Cu")
		(net "SELF_1B_HB")
	)
	(segment
		(start 20.0406 -53.213)
		(end 21.7932 -53.213)
		(width 0.1397)
		(layer "F.Cu")
		(net "SELF_1B_HB")
	)
	(segment
		(start 21.7932 -53.213)
		(end 23.040086 -54.459886)
		(width 0.1397)
		(layer "F.Cu")
		(net "SELF_1B_HB")
	)
	(segment
		(start 13.3858 -40.894)
		(end 13.8176 -40.4622)
		(width 0.1397)
		(layer "F.Cu")
		(net "SELF_1B_HB")
	)
	(segment
		(start 12.6238 -53.2638)
		(end 12.6238 -53.047646)
		(width 0.1397)
		(layer "F.Cu")
		(net "SELF_1B_HB")
	)
	(segment
		(start 18.99285 -52.16525)
		(end 20.0406 -53.213)
		(width 0.1397)
		(layer "F.Cu")
		(net "SELF_1B_HB")
	)
	(via
		(at 12.6238 -53.2638)
		(size 0.5588)
		(drill 0.3048)
		(layers "F.Cu" "B.Cu")
		(net "SELF_1B_HB")
	)
	(via
		(at 13.3858 -41.2242)
		(size 0.5588)
		(drill 0.3048)
		(layers "F.Cu" "B.Cu")
		(net "SELF_1B_HB")
	)
	(segment
		(start 12.5984 -43.0022)
		(end 12.5984 -46.863)
		(width 0.1397)
		(layer "B.Cu")
		(net "SELF_1B_HB")
	)
	(segment
		(start 12.6238 -52.7558)
		(end 12.6238 -53.2638)
		(width 0.1397)
		(layer "B.Cu")
		(net "SELF_1B_HB")
	)
	(segment
		(start 13.3858 -41.2242)
		(end 13.3858 -42.2148)
		(width 0.1397)
		(layer "B.Cu")
		(net "SELF_1B_HB")
	)
	(segment
		(start 13.3858 -42.2148)
		(end 12.5984 -43.0022)
		(width 0.1397)
		(layer "B.Cu")
		(net "SELF_1B_HB")
	)
	(segment
		(start 11.46175 -47.99965)
		(end 11.46175 -51.59375)
		(width 0.1397)
		(layer "B.Cu")
		(net "SELF_1B_HB")
	)
	(segment
		(start 11.46175 -51.59375)
		(end 12.6238 -52.7558)
		(width 0.1397)
		(layer "B.Cu")
		(net "SELF_1B_HB")
	)
	(segment
		(start 12.5984 -46.863)
		(end 11.46175 -47.99965)
		(width 0.1397)
		(layer "B.Cu")
		(net "SELF_1B_HB")
	)
	(segment
		(start 44.2468 -62.3062)
		(end 44.941236 -63.000636)
		(width 0.1397)
		(layer "F.Cu")
		(net "SELF_TRAY_PRESENT_LOWER")
	)
	(segment
		(start 43.561 -61.159136)
		(end 44.2468 -61.844936)
		(width 0.1397)
		(layer "F.Cu")
		(net "SELF_TRAY_PRESENT_LOWER")
	)
	(segment
		(start 31.1658 -60.706)
		(end 31.618936 -61.159136)
		(width 0.1397)
		(layer "F.Cu")
		(net "SELF_TRAY_PRESENT_LOWER")
	)
	(segment
		(start 27.178 -59.900058)
		(end 27.983942 -60.706)
		(width 0.1397)
		(layer "F.Cu")
		(net "SELF_TRAY_PRESENT_LOWER")
	)
	(segment
		(start 27.983942 -60.706)
		(end 31.1658 -60.706)
		(width 0.1397)
		(layer "F.Cu")
		(net "SELF_TRAY_PRESENT_LOWER")
	)
	(segment
		(start 25.961594 -58.619136)
		(end 27.178 -59.835542)
		(width 0.1397)
		(layer "F.Cu")
		(net "SELF_TRAY_PRESENT_LOWER")
	)
	(segment
		(start 44.2468 -61.844936)
		(end 44.2468 -62.3062)
		(width 0.1397)
		(layer "F.Cu")
		(net "SELF_TRAY_PRESENT_LOWER")
	)
	(segment
		(start 13.582396 -56.76265)
		(end 12.6873 -55.867554)
		(width 0.1397)
		(layer "F.Cu")
		(net "SELF_TRAY_PRESENT_LOWER")
	)
	(segment
		(start 21.761704 -58.6994)
		(end 21.841968 -58.619136)
		(width 0.1397)
		(layer "F.Cu")
		(net "SELF_TRAY_PRESENT_LOWER")
	)
	(segment
		(start 46.295564 -63.000636)
		(end 46.98492 -62.31128)
		(width 0.1397)
		(layer "F.Cu")
		(net "SELF_TRAY_PRESENT_LOWER")
	)
	(segment
		(start 18.3134 -56.3118)
		(end 17.86255 -56.76265)
		(width 0.1397)
		(layer "F.Cu")
		(net "SELF_TRAY_PRESENT_LOWER")
	)
	(segment
		(start 17.86255 -56.76265)
		(end 13.582396 -56.76265)
		(width 0.1397)
		(layer "F.Cu")
		(net "SELF_TRAY_PRESENT_LOWER")
	)
	(segment
		(start 46.98492 -53.284882)
		(end 45.619924 -51.919886)
		(width 0.1397)
		(layer "F.Cu")
		(net "SELF_TRAY_PRESENT_LOWER")
	)
	(segment
		(start 27.178 -59.835542)
		(end 27.178 -59.900058)
		(width 0.1397)
		(layer "F.Cu")
		(net "SELF_TRAY_PRESENT_LOWER")
	)
	(segment
		(start 21.841968 -58.619136)
		(end 25.961594 -58.619136)
		(width 0.1397)
		(layer "F.Cu")
		(net "SELF_TRAY_PRESENT_LOWER")
	)
	(segment
		(start 46.98492 -62.31128)
		(end 46.98492 -53.284882)
		(width 0.1397)
		(layer "F.Cu")
		(net "SELF_TRAY_PRESENT_LOWER")
	)
	(segment
		(start 44.941236 -63.000636)
		(end 46.295564 -63.000636)
		(width 0.1397)
		(layer "F.Cu")
		(net "SELF_TRAY_PRESENT_LOWER")
	)
	(segment
		(start 31.618936 -61.159136)
		(end 43.561 -61.159136)
		(width 0.1397)
		(layer "F.Cu")
		(net "SELF_TRAY_PRESENT_LOWER")
	)
	(segment
		(start 12.6873 -55.867554)
		(end 12.6873 -55.2196)
		(width 0.1397)
		(layer "F.Cu")
		(net "SELF_TRAY_PRESENT_LOWER")
	)
	(via
		(at 18.3134 -56.3118)
		(size 0.5588)
		(drill 0.3048)
		(layers "F.Cu" "B.Cu")
		(net "SELF_TRAY_PRESENT_LOWER")
	)
	(via
		(at 21.761704 -58.6994)
		(size 0.5588)
		(drill 0.3048)
		(layers "F.Cu" "B.Cu")
		(net "SELF_TRAY_PRESENT_LOWER")
	)
	(segment
		(start 18.546064 -56.079136)
		(end 18.3134 -56.3118)
		(width 0.1397)
		(layer "B.Cu")
		(net "SELF_TRAY_PRESENT_LOWER")
	)
	(segment
		(start 21.4376 -58.375296)
		(end 21.4376 -56.635142)
		(width 0.1397)
		(layer "B.Cu")
		(net "SELF_TRAY_PRESENT_LOWER")
	)
	(segment
		(start 20.881594 -56.079136)
		(end 18.546064 -56.079136)
		(width 0.1397)
		(layer "B.Cu")
		(net "SELF_TRAY_PRESENT_LOWER")
	)
	(segment
		(start 21.4376 -56.635142)
		(end 20.881594 -56.079136)
		(width 0.1397)
		(layer "B.Cu")
		(net "SELF_TRAY_PRESENT_LOWER")
	)
	(segment
		(start 21.761704 -58.6994)
		(end 21.4376 -58.375296)
		(width 0.1397)
		(layer "B.Cu")
		(net "SELF_TRAY_PRESENT_LOWER")
	)
	(segment
		(start 18.4658 -54.3306)
		(end 12.8143 -54.3306)
		(width 0.1397)
		(layer "F.Cu")
		(net "PEER_TRAY PRESENT_LOWER")
	)
	(segment
		(start 12.8143 -54.3306)
		(end 12.6873 -54.2036)
		(width 0.1397)
		(layer "F.Cu")
		(net "PEER_TRAY PRESENT_LOWER")
	)
	(segment
		(start 46.54042 -61.15939)
		(end 45.619924 -62.079886)
		(width 0.1397)
		(layer "F.Cu")
		(net "PEER_TRAY PRESENT_LOWER")
	)
	(segment
		(start 46.147736 -58.619136)
		(end 46.54042 -59.01182)
		(width 0.1397)
		(layer "F.Cu")
		(net "PEER_TRAY PRESENT_LOWER")
	)
	(segment
		(start 46.54042 -59.01182)
		(end 46.54042 -61.15939)
		(width 0.1397)
		(layer "F.Cu")
		(net "PEER_TRAY PRESENT_LOWER")
	)
	(segment
		(start 31.0134 -58.4454)
		(end 31.187136 -58.619136)
		(width 0.1397)
		(layer "F.Cu")
		(net "PEER_TRAY PRESENT_LOWER")
	)
	(segment
		(start 31.187136 -58.619136)
		(end 46.147736 -58.619136)
		(width 0.1397)
		(layer "F.Cu")
		(net "PEER_TRAY PRESENT_LOWER")
	)
	(segment
		(start 19.1262 -53.6702)
		(end 18.4658 -54.3306)
		(width 0.1397)
		(layer "F.Cu")
		(net "PEER_TRAY PRESENT_LOWER")
	)
	(via
		(at 19.1262 -53.6702)
		(size 0.5588)
		(drill 0.3048)
		(layers "F.Cu" "B.Cu")
		(net "PEER_TRAY PRESENT_LOWER")
	)
	(via
		(at 31.0134 -58.4454)
		(size 0.5588)
		(drill 0.3048)
		(layers "F.Cu" "B.Cu")
		(net "PEER_TRAY PRESENT_LOWER")
	)
	(segment
		(start 20.881594 -53.539136)
		(end 19.257264 -53.539136)
		(width 0.1397)
		(layer "B.Cu")
		(net "PEER_TRAY PRESENT_LOWER")
	)
	(segment
		(start 30.988 -58.42)
		(end 25.069292 -58.42)
		(width 0.1397)
		(layer "B.Cu")
		(net "PEER_TRAY PRESENT_LOWER")
	)
	(segment
		(start 23.9776 -57.328308)
		(end 23.9776 -56.635142)
		(width 0.1397)
		(layer "B.Cu")
		(net "PEER_TRAY PRESENT_LOWER")
	)
	(segment
		(start 21.4376 -54.095142)
		(end 20.881594 -53.539136)
		(width 0.1397)
		(layer "B.Cu")
		(net "PEER_TRAY PRESENT_LOWER")
	)
	(segment
		(start 23.9776 -56.635142)
		(end 23.400258 -56.0578)
		(width 0.1397)
		(layer "B.Cu")
		(net "PEER_TRAY PRESENT_LOWER")
	)
	(segment
		(start 21.4376 -54.788308)
		(end 21.4376 -54.095142)
		(width 0.1397)
		(layer "B.Cu")
		(net "PEER_TRAY PRESENT_LOWER")
	)
	(segment
		(start 22.707092 -56.0578)
		(end 21.4376 -54.788308)
		(width 0.1397)
		(layer "B.Cu")
		(net "PEER_TRAY PRESENT_LOWER")
	)
	(segment
		(start 23.400258 -56.0578)
		(end 22.707092 -56.0578)
		(width 0.1397)
		(layer "B.Cu")
		(net "PEER_TRAY PRESENT_LOWER")
	)
	(segment
		(start 31.0134 -58.4454)
		(end 30.988 -58.42)
		(width 0.1397)
		(layer "B.Cu")
		(net "PEER_TRAY PRESENT_LOWER")
	)
	(segment
		(start 25.069292 -58.42)
		(end 23.9776 -57.328308)
		(width 0.1397)
		(layer "B.Cu")
		(net "PEER_TRAY PRESENT_LOWER")
	)
	(segment
		(start 19.257264 -53.539136)
		(end 19.1262 -53.6702)
		(width 0.1397)
		(layer "B.Cu")
		(net "PEER_TRAY PRESENT_LOWER")
	)
	(segment
		(start 38.182042 -53.34)
		(end 39.2176 -54.375558)
		(width 0.1397)
		(layer "F.Cu")
		(net "SEB_PEER_2A_HB")
	)
	(segment
		(start 39.2176 -54.483)
		(end 40.115236 -55.380636)
		(width 0.1397)
		(layer "F.Cu")
		(net "SEB_PEER_2A_HB")
	)
	(segment
		(start 16.764 -45.1612)
		(end 28.9052 -45.1612)
		(width 0.1397)
		(layer "F.Cu")
		(net "SEB_PEER_2A_HB")
	)
	(segment
		(start 15.3289 -44.5262)
		(end 15.3289 -43.5102)
		(width 0.1397)
		(layer "F.Cu")
		(net "SEB_PEER_2A_HB")
	)
	(segment
		(start 12.93876 -175.40224)
		(end 13.1445 -175.40224)
		(width 0.1397)
		(layer "F.Cu")
		(net "SEB_PEER_2A_HB")
	)
	(segment
		(start 11.303 -177.038)
		(end 12.93876 -175.40224)
		(width 0.1397)
		(layer "F.Cu")
		(net "SEB_PEER_2A_HB")
	)
	(segment
		(start 39.2176 -54.375558)
		(end 39.2176 -54.483)
		(width 0.1397)
		(layer "F.Cu")
		(net "SEB_PEER_2A_HB")
	)
	(segment
		(start 28.9052 -45.1612)
		(end 37.084 -53.34)
		(width 0.1397)
		(layer "F.Cu")
		(net "SEB_PEER_2A_HB")
	)
	(segment
		(start 16.129 -44.5262)
		(end 16.764 -45.1612)
		(width 0.1397)
		(layer "F.Cu")
		(net "SEB_PEER_2A_HB")
	)
	(segment
		(start 8.23595 -45.1866)
		(end 8.36295 -45.0596)
		(width 0.1397)
		(layer "F.Cu")
		(net "SEB_PEER_2A_HB")
	)
	(segment
		(start 40.115236 -55.380636)
		(end 42.159174 -55.380636)
		(width 0.1397)
		(layer "F.Cu")
		(net "SEB_PEER_2A_HB")
	)
	(segment
		(start 14.7955 -45.0596)
		(end 15.3289 -44.5262)
		(width 0.1397)
		(layer "F.Cu")
		(net "SEB_PEER_2A_HB")
	)
	(segment
		(start 8.36295 -45.0596)
		(end 14.7955 -45.0596)
		(width 0.1397)
		(layer "F.Cu")
		(net "SEB_PEER_2A_HB")
	)
	(segment
		(start 15.3289 -44.5262)
		(end 16.129 -44.5262)
		(width 0.1397)
		(layer "F.Cu")
		(net "SEB_PEER_2A_HB")
	)
	(segment
		(start 42.159174 -55.380636)
		(end 43.079924 -54.459886)
		(width 0.1397)
		(layer "F.Cu")
		(net "SEB_PEER_2A_HB")
	)
	(segment
		(start 11.303 -177.165)
		(end 11.303 -177.038)
		(width 0.1397)
		(layer "F.Cu")
		(net "SEB_PEER_2A_HB")
	)
	(segment
		(start 37.084 -53.34)
		(end 38.182042 -53.34)
		(width 0.1397)
		(layer "F.Cu")
		(net "SEB_PEER_2A_HB")
	)
	(via
		(at 8.23595 -45.1866)
		(size 0.5588)
		(drill 0.3048)
		(layers "F.Cu" "B.Cu")
		(net "SEB_PEER_2A_HB")
	)
	(via
		(at 11.303 -177.165)
		(size 0.5588)
		(drill 0.3048)
		(layers "F.Cu" "B.Cu")
		(net "SEB_PEER_2A_HB")
	)
	(segment
		(start 2.243074 -119.37238)
		(end 2.243074 -167.610282)
		(width 0.1397)
		(layer "B.Cu")
		(net "SEB_PEER_2A_HB")
	)
	(segment
		(start 2.243074 -80.676242)
		(end 2.243074 -113.43767)
		(width 0.1397)
		(layer "B.Cu")
		(net "SEB_PEER_2A_HB")
	)
	(segment
		(start 8.23595 -52.330096)
		(end 8.321802 -52.415948)
		(width 0.1397)
		(layer "B.Cu")
		(net "SEB_PEER_2A_HB")
	)
	(segment
		(start 8.279638 -56.9468)
		(end 7.837932 -56.9468)
		(width 0.1397)
		(layer "B.Cu")
		(net "SEB_PEER_2A_HB")
	)
	(segment
		(start 8.781796 -56.444642)
		(end 8.279638 -56.9468)
		(width 0.1397)
		(layer "B.Cu")
		(net "SEB_PEER_2A_HB")
	)
	(segment
		(start 2.242566 -113.438178)
		(end 2.242566 -119.371872)
		(width 0.1397)
		(layer "B.Cu")
		(net "SEB_PEER_2A_HB")
	)
	(segment
		(start 8.23595 -45.1866)
		(end 8.23595 -52.330096)
		(width 0.1397)
		(layer "B.Cu")
		(net "SEB_PEER_2A_HB")
	)
	(segment
		(start 11.1633 -177.165)
		(end 11.303 -177.165)
		(width 0.1397)
		(layer "B.Cu")
		(net "SEB_PEER_2A_HB")
	)
	(segment
		(start 7.837932 -56.9468)
		(end 3.9878 -60.796932)
		(width 0.1397)
		(layer "B.Cu")
		(net "SEB_PEER_2A_HB")
	)
	(segment
		(start 8.321802 -52.416202)
		(end 8.781796 -52.876196)
		(width 0.1397)
		(layer "B.Cu")
		(net "SEB_PEER_2A_HB")
	)
	(segment
		(start 8.781796 -52.876196)
		(end 8.781796 -56.444642)
		(width 0.1397)
		(layer "B.Cu")
		(net "SEB_PEER_2A_HB")
	)
	(segment
		(start 8.321802 -52.415948)
		(end 8.321802 -52.416202)
		(width 0.1397)
		(layer "B.Cu")
		(net "SEB_PEER_2A_HB")
	)
	(segment
		(start 10.470896 -175.83785)
		(end 10.470896 -176.472596)
		(width 0.1397)
		(layer "B.Cu")
		(net "SEB_PEER_2A_HB")
	)
	(segment
		(start 2.503424 -167.870378)
		(end 10.470896 -175.83785)
		(width 0.1397)
		(layer "B.Cu")
		(net "SEB_PEER_2A_HB")
	)
	(segment
		(start 3.9878 -78.931516)
		(end 2.243074 -80.676242)
		(width 0.1397)
		(layer "B.Cu")
		(net "SEB_PEER_2A_HB")
	)
	(segment
		(start 2.243074 -113.43767)
		(end 2.242566 -113.438178)
		(width 0.1397)
		(layer "B.Cu")
		(net "SEB_PEER_2A_HB")
	)
	(segment
		(start 2.243074 -167.610282)
		(end 2.50317 -167.870378)
		(width 0.1397)
		(layer "B.Cu")
		(net "SEB_PEER_2A_HB")
	)
	(segment
		(start 2.242566 -119.371872)
		(end 2.243074 -119.37238)
		(width 0.1397)
		(layer "B.Cu")
		(net "SEB_PEER_2A_HB")
	)
	(segment
		(start 2.50317 -167.870378)
		(end 2.503424 -167.870378)
		(width 0.1397)
		(layer "B.Cu")
		(net "SEB_PEER_2A_HB")
	)
	(segment
		(start 10.470896 -176.472596)
		(end 11.1633 -177.165)
		(width 0.1397)
		(layer "B.Cu")
		(net "SEB_PEER_2A_HB")
	)
	(segment
		(start 3.9878 -60.796932)
		(end 3.9878 -78.931516)
		(width 0.1397)
		(layer "B.Cu")
		(net "SEB_PEER_2A_HB")
	)
	(segment
		(start 8.40105 -176.7967)
		(end 8.40105 -174.98695)
		(width 0.1397)
		(layer "F.Cu")
		(net "SEB_PEER_1B_HB")
	)
	(segment
		(start 8.40105 -174.98695)
		(end 8.636 -174.752)
		(width 0.1397)
		(layer "F.Cu")
		(net "SEB_PEER_1B_HB")
	)
	(segment
		(start 10.0203 -57.6707)
		(end 9.652 -58.039)
		(width 0.1397)
		(layer "F.Cu")
		(net "SEB_PEER_1B_HB")
	)
	(segment
		(start 15.5702 -58.2676)
		(end 14.9733 -57.6707)
		(width 0.1397)
		(layer "F.Cu")
		(net "SEB_PEER_1B_HB")
	)
	(segment
		(start 8.636 -174.752)
		(end 9.2075 -174.752)
		(width 0.1397)
		(layer "F.Cu")
		(net "SEB_PEER_1B_HB")
	)
	(segment
		(start 14.4399 -41.4782)
		(end 14.4399 -42.4942)
		(width 0.1397)
		(layer "F.Cu")
		(net "SEB_PEER_1B_HB")
	)
	(segment
		(start 10.80135 -179.197)
		(end 8.40105 -176.7967)
		(width 0.1397)
		(layer "F.Cu")
		(net "SEB_PEER_1B_HB")
	)
	(segment
		(start 11.811 -179.197)
		(end 10.80135 -179.197)
		(width 0.1397)
		(layer "F.Cu")
		(net "SEB_PEER_1B_HB")
	)
	(segment
		(start 12.80795 -42.4942)
		(end 11.0236 -44.27855)
		(width 0.1397)
		(layer "F.Cu")
		(net "SEB_PEER_1B_HB")
	)
	(segment
		(start 14.9733 -57.6707)
		(end 10.0203 -57.6707)
		(width 0.1397)
		(layer "F.Cu")
		(net "SEB_PEER_1B_HB")
	)
	(segment
		(start 14.4399 -42.4942)
		(end 12.80795 -42.4942)
		(width 0.1397)
		(layer "F.Cu")
		(net "SEB_PEER_1B_HB")
	)
	(via
		(at 11.811 -179.197)
		(size 0.5588)
		(drill 0.3048)
		(layers "F.Cu" "B.Cu")
		(net "SEB_PEER_1B_HB")
	)
	(via
		(at 15.5702 -58.2676)
		(size 0.5588)
		(drill 0.3048)
		(layers "F.Cu" "B.Cu")
		(net "SEB_PEER_1B_HB")
	)
	(via
		(at 9.652 -58.039)
		(size 0.5588)
		(drill 0.3048)
		(layers "F.Cu" "B.Cu")
		(net "SEB_PEER_1B_HB")
	)
	(via
		(at 11.0236 -44.27855)
		(size 0.5588)
		(drill 0.3048)
		(layers "F.Cu" "B.Cu")
		(net "SEB_PEER_1B_HB")
	)
	(segment
		(start 9.7536 -52.578)
		(end 9.7536 -57.9374)
		(width 0.1397)
		(layer "B.Cu")
		(net "SEB_PEER_1B_HB")
	)
	(segment
		(start 4.9022 -69.355716)
		(end 5.6134 -68.644516)
		(width 0.1397)
		(layer "B.Cu")
		(net "SEB_PEER_1B_HB")
	)
	(segment
		(start 3.131566 -119.003572)
		(end 3.131566 -113.806478)
		(width 0.1397)
		(layer "B.Cu")
		(net "SEB_PEER_1B_HB")
	)
	(segment
		(start 15.5702 -58.2676)
		(end 15.5702 -54.761892)
		(width 0.1397)
		(layer "B.Cu")
		(net "SEB_PEER_1B_HB")
	)
	(segment
		(start 24.659336 -50.999136)
		(end 25.580086 -51.919886)
		(width 0.1397)
		(layer "B.Cu")
		(net "SEB_PEER_1B_HB")
	)
	(segment
		(start 10.96645 -44.27855)
		(end 9.20623 -46.03877)
		(width 0.1397)
		(layer "B.Cu")
		(net "SEB_PEER_1B_HB")
	)
	(segment
		(start 9.20623 -52.03063)
		(end 9.7536 -52.578)
		(width 0.1397)
		(layer "B.Cu")
		(net "SEB_PEER_1B_HB")
	)
	(segment
		(start 7.48665 -144.51965)
		(end 4.977384 -142.010384)
		(width 0.1397)
		(layer "B.Cu")
		(net "SEB_PEER_1B_HB")
	)
	(segment
		(start 5.6134 -62.357)
		(end 9.652 -58.3184)
		(width 0.1397)
		(layer "B.Cu")
		(net "SEB_PEER_1B_HB")
	)
	(segment
		(start 4.977384 -142.010384)
		(end 4.977384 -134.976616)
		(width 0.1397)
		(layer "B.Cu")
		(net "SEB_PEER_1B_HB")
	)
	(segment
		(start 7.48665 -146.42465)
		(end 7.48665 -144.51965)
		(width 0.1397)
		(layer "B.Cu")
		(net "SEB_PEER_1B_HB")
	)
	(segment
		(start 3.131566 -113.806478)
		(end 3.605784 -113.33226)
		(width 0.1397)
		(layer "B.Cu")
		(net "SEB_PEER_1B_HB")
	)
	(segment
		(start 9.652 -58.3184)
		(end 9.652 -58.039)
		(width 0.1397)
		(layer "B.Cu")
		(net "SEB_PEER_1B_HB")
	)
	(segment
		(start 12.33805 -151.27605)
		(end 7.48665 -146.42465)
		(width 0.1397)
		(layer "B.Cu")
		(net "SEB_PEER_1B_HB")
	)
	(segment
		(start 11.811 -178.308)
		(end 12.33805 -177.78095)
		(width 0.1397)
		(layer "B.Cu")
		(net "SEB_PEER_1B_HB")
	)
	(segment
		(start 5.951474 -121.82348)
		(end 3.131566 -119.003572)
		(width 0.1397)
		(layer "B.Cu")
		(net "SEB_PEER_1B_HB")
	)
	(segment
		(start 4.977384 -134.976616)
		(end 5.951474 -134.002526)
		(width 0.1397)
		(layer "B.Cu")
		(net "SEB_PEER_1B_HB")
	)
	(segment
		(start 5.6134 -68.644516)
		(end 5.6134 -62.357)
		(width 0.1397)
		(layer "B.Cu")
		(net "SEB_PEER_1B_HB")
	)
	(segment
		(start 3.605784 -113.33226)
		(end 3.605784 -82.666332)
		(width 0.1397)
		(layer "B.Cu")
		(net "SEB_PEER_1B_HB")
	)
	(segment
		(start 9.20623 -46.03877)
		(end 9.20623 -52.03063)
		(width 0.1397)
		(layer "B.Cu")
		(net "SEB_PEER_1B_HB")
	)
	(segment
		(start 5.951474 -134.002526)
		(end 5.951474 -121.82348)
		(width 0.1397)
		(layer "B.Cu")
		(net "SEB_PEER_1B_HB")
	)
	(segment
		(start 11.811 -179.197)
		(end 11.811 -178.308)
		(width 0.1397)
		(layer "B.Cu")
		(net "SEB_PEER_1B_HB")
	)
	(segment
		(start 11.0236 -44.27855)
		(end 10.96645 -44.27855)
		(width 0.1397)
		(layer "B.Cu")
		(net "SEB_PEER_1B_HB")
	)
	(segment
		(start 9.7536 -57.9374)
		(end 9.652 -58.039)
		(width 0.1397)
		(layer "B.Cu")
		(net "SEB_PEER_1B_HB")
	)
	(segment
		(start 12.33805 -177.78095)
		(end 12.33805 -151.27605)
		(width 0.1397)
		(layer "B.Cu")
		(net "SEB_PEER_1B_HB")
	)
	(segment
		(start 15.5702 -54.761892)
		(end 19.777456 -50.554636)
		(width 0.1397)
		(layer "B.Cu")
		(net "SEB_PEER_1B_HB")
	)
	(segment
		(start 4.9022 -81.369916)
		(end 4.9022 -69.355716)
		(width 0.1397)
		(layer "B.Cu")
		(net "SEB_PEER_1B_HB")
	)
	(segment
		(start 3.605784 -82.666332)
		(end 4.9022 -81.369916)
		(width 0.1397)
		(layer "B.Cu")
		(net "SEB_PEER_1B_HB")
	)
	(segment
		(start 21.090636 -50.554636)
		(end 21.535136 -50.999136)
		(width 0.1397)
		(layer "B.Cu")
		(net "SEB_PEER_1B_HB")
	)
	(segment
		(start 21.535136 -50.999136)
		(end 24.659336 -50.999136)
		(width 0.1397)
		(layer "B.Cu")
		(net "SEB_PEER_1B_HB")
	)
	(segment
		(start 19.777456 -50.554636)
		(end 21.090636 -50.554636)
		(width 0.1397)
		(layer "B.Cu")
		(net "SEB_PEER_1B_HB")
	)
	(segment
		(start 26.0858 -60.7822)
		(end 27.383486 -62.079886)
		(width 0.1397)
		(layer "F.Cu")
		(net "PEER_TRAY PRESENT_UPPER")
	)
	(segment
		(start 18.9992 -58.8772)
		(end 18.9992 -59.341258)
		(width 0.1397)
		(layer "F.Cu")
		(net "PEER_TRAY PRESENT_UPPER")
	)
	(segment
		(start 18.9992 -59.341258)
		(end 20.440142 -60.7822)
		(width 0.1397)
		(layer "F.Cu")
		(net "PEER_TRAY PRESENT_UPPER")
	)
	(segment
		(start 13.0048 -57.2262)
		(end 17.4244 -57.2262)
		(width 0.1397)
		(layer "F.Cu")
		(net "PEER_TRAY PRESENT_UPPER")
	)
	(segment
		(start 27.383486 -62.079886)
		(end 28.120086 -62.079886)
		(width 0.1397)
		(layer "F.Cu")
		(net "PEER_TRAY PRESENT_UPPER")
	)
	(segment
		(start 17.4244 -57.2262)
		(end 17.6276 -57.4294)
		(width 0.1397)
		(layer "F.Cu")
		(net "PEER_TRAY PRESENT_UPPER")
	)
	(segment
		(start 11.7983 -56.0197)
		(end 13.0048 -57.2262)
		(width 0.1397)
		(layer "F.Cu")
		(net "PEER_TRAY PRESENT_UPPER")
	)
	(segment
		(start 11.7983 -55.2196)
		(end 11.7983 -56.0197)
		(width 0.1397)
		(layer "F.Cu")
		(net "PEER_TRAY PRESENT_UPPER")
	)
	(segment
		(start 20.440142 -60.7822)
		(end 26.0858 -60.7822)
		(width 0.1397)
		(layer "F.Cu")
		(net "PEER_TRAY PRESENT_UPPER")
	)
	(via
		(at 17.6276 -57.4294)
		(size 0.5588)
		(drill 0.3048)
		(layers "F.Cu" "B.Cu")
		(net "PEER_TRAY PRESENT_UPPER")
	)
	(via
		(at 18.9992 -58.8772)
		(size 0.5588)
		(drill 0.3048)
		(layers "F.Cu" "B.Cu")
		(net "PEER_TRAY PRESENT_UPPER")
	)
	(segment
		(start 18.9992 -58.8772)
		(end 18.9992 -58.801)
		(width 0.1397)
		(layer "B.Cu")
		(net "PEER_TRAY PRESENT_UPPER")
	)
	(segment
		(start 18.9992 -58.801)
		(end 17.6276 -57.4294)
		(width 0.1397)
		(layer "B.Cu")
		(net "PEER_TRAY PRESENT_UPPER")
	)
	(segment
		(start 21.4249 -63.0047)
		(end 20.500086 -62.079886)
		(width 0.1397)
		(layer "F.Cu")
		(net "I2C_C_SDA_CONN_R")
	)
	(segment
		(start 34.948114 -62.079886)
		(end 34.0233 -63.0047)
		(width 0.1397)
		(layer "F.Cu")
		(net "I2C_C_SDA_CONN_R")
	)
	(segment
		(start 16.002 -66.1162)
		(end 15.9258 -66.04)
		(width 0.1397)
		(layer "F.Cu")
		(net "I2C_C_SDA_CONN_R")
	)
	(segment
		(start 14.8082 -66.0019)
		(end 15.8877 -66.0019)
		(width 0.1397)
		(layer "F.Cu")
		(net "I2C_C_SDA_CONN_R")
	)
	(segment
		(start 15.8877 -66.0019)
		(end 15.9258 -66.04)
		(width 0.1397)
		(layer "F.Cu")
		(net "I2C_C_SDA_CONN_R")
	)
	(segment
		(start 16.002 -67.1195)
		(end 16.002 -66.1162)
		(width 0.1397)
		(layer "F.Cu")
		(net "I2C_C_SDA_CONN_R")
	)
	(segment
		(start 16.1925 -67.1195)
		(end 16.002 -67.1195)
		(width 0.1397)
		(layer "F.Cu")
		(net "I2C_C_SDA_CONN_R")
	)
	(segment
		(start 37.999924 -62.079886)
		(end 34.948114 -62.079886)
		(width 0.1397)
		(layer "F.Cu")
		(net "I2C_C_SDA_CONN_R")
	)
	(segment
		(start 20.500086 -62.079886)
		(end 20.500086 -62.811914)
		(width 0.1397)
		(layer "F.Cu")
		(net "I2C_C_SDA_CONN_R")
	)
	(segment
		(start 34.0233 -63.0047)
		(end 21.4249 -63.0047)
		(width 0.1397)
		(layer "F.Cu")
		(net "I2C_C_SDA_CONN_R")
	)
	(segment
		(start 20.500086 -62.811914)
		(end 16.1925 -67.1195)
		(width 0.1397)
		(layer "F.Cu")
		(net "I2C_C_SDA_CONN_R")
	)
	(segment
		(start 13.433806 -51.54295)
		(end 16.50365 -51.54295)
		(width 0.1397)
		(layer "F.Cu")
		(net "SELF_TRAY_PRESENT_UPPER")
	)
	(segment
		(start 16.50365 -51.54295)
		(end 17.491964 -50.554636)
		(width 0.1397)
		(layer "F.Cu")
		(net "SELF_TRAY_PRESENT_UPPER")
	)
	(segment
		(start 26.754836 -50.554636)
		(end 28.120086 -51.919886)
		(width 0.1397)
		(layer "F.Cu")
		(net "SELF_TRAY_PRESENT_UPPER")
	)
	(segment
		(start 11.7983 -54.2036)
		(end 11.7983 -53.178456)
		(width 0.1397)
		(layer "F.Cu")
		(net "SELF_TRAY_PRESENT_UPPER")
	)
	(segment
		(start 11.7983 -53.178456)
		(end 13.433806 -51.54295)
		(width 0.1397)
		(layer "F.Cu")
		(net "SELF_TRAY_PRESENT_UPPER")
	)
	(segment
		(start 17.491964 -50.554636)
		(end 26.754836 -50.554636)
		(width 0.1397)
		(layer "F.Cu")
		(net "SELF_TRAY_PRESENT_UPPER")
	)
	(segment
		(start 29.8704 -59.6646)
		(end 30.7594 -59.6646)
		(width 0.1397)
		(layer "F.Cu")
		(net "LOWER_TRAY_ID")
	)
	(segment
		(start 17.0688 -56.134)
		(end 17.9324 -55.2704)
		(width 0.1397)
		(layer "F.Cu")
		(net "LOWER_TRAY_ID")
	)
	(segment
		(start 31.555436 -60.460636)
		(end 44.699174 -60.460636)
		(width 0.1397)
		(layer "F.Cu")
		(net "LOWER_TRAY_ID")
	)
	(segment
		(start 30.7594 -59.6646)
		(end 31.555436 -60.460636)
		(width 0.1397)
		(layer "F.Cu")
		(net "LOWER_TRAY_ID")
	)
	(segment
		(start 44.699174 -60.460636)
		(end 45.619924 -59.539886)
		(width 0.1397)
		(layer "F.Cu")
		(net "LOWER_TRAY_ID")
	)
	(segment
		(start 15.5575 -56.134)
		(end 17.0688 -56.134)
		(width 0.1397)
		(layer "F.Cu")
		(net "LOWER_TRAY_ID")
	)
	(segment
		(start 15.5575 -56.134)
		(end 15.5575 -55.118)
		(width 0.1397)
		(layer "F.Cu")
		(net "LOWER_TRAY_ID")
	)
	(via
		(at 17.9324 -55.2704)
		(size 0.5588)
		(drill 0.3048)
		(layers "F.Cu" "B.Cu")
		(net "LOWER_TRAY_ID")
	)
	(via
		(at 29.8704 -59.6646)
		(size 0.5588)
		(drill 0.3048)
		(layers "F.Cu" "B.Cu")
		(net "LOWER_TRAY_ID")
	)
	(segment
		(start 25.198578 -60.460636)
		(end 24.638 -59.900058)
		(width 0.1397)
		(layer "B.Cu")
		(net "LOWER_TRAY_ID")
	)
	(segment
		(start 18.0594 -55.3974)
		(end 17.9324 -55.2704)
		(width 0.1397)
		(layer "B.Cu")
		(net "LOWER_TRAY_ID")
	)
	(segment
		(start 29.074364 -60.460636)
		(end 25.198578 -60.460636)
		(width 0.1397)
		(layer "B.Cu")
		(net "LOWER_TRAY_ID")
	)
	(segment
		(start 21.8948 -57.156858)
		(end 21.8948 -56.463692)
		(width 0.1397)
		(layer "B.Cu")
		(net "LOWER_TRAY_ID")
	)
	(segment
		(start 23.273258 -58.4708)
		(end 23.208742 -58.4708)
		(width 0.1397)
		(layer "B.Cu")
		(net "LOWER_TRAY_ID")
	)
	(segment
		(start 24.638 -59.835542)
		(end 23.273258 -58.4708)
		(width 0.1397)
		(layer "B.Cu")
		(net "LOWER_TRAY_ID")
	)
	(segment
		(start 21.8948 -56.463692)
		(end 20.828508 -55.3974)
		(width 0.1397)
		(layer "B.Cu")
		(net "LOWER_TRAY_ID")
	)
	(segment
		(start 24.638 -59.900058)
		(end 24.638 -59.835542)
		(width 0.1397)
		(layer "B.Cu")
		(net "LOWER_TRAY_ID")
	)
	(segment
		(start 20.828508 -55.3974)
		(end 18.0594 -55.3974)
		(width 0.1397)
		(layer "B.Cu")
		(net "LOWER_TRAY_ID")
	)
	(segment
		(start 23.208742 -58.4708)
		(end 21.8948 -57.156858)
		(width 0.1397)
		(layer "B.Cu")
		(net "LOWER_TRAY_ID")
	)
	(segment
		(start 29.8704 -59.6646)
		(end 29.074364 -60.460636)
		(width 0.1397)
		(layer "B.Cu")
		(net "LOWER_TRAY_ID")
	)
	(segment
		(start 15.9004 -63.3095)
		(end 15.2273 -63.3095)
		(width 0.1397)
		(layer "F.Cu")
		(net "I2C_C_SCL_CONN_R")
	)
	(segment
		(start 18.4785 -59.6519)
		(end 18.63725 -59.81065)
		(width 0.1397)
		(layer "F.Cu")
		(net "I2C_C_SCL_CONN_R")
	)
	(segment
		(start 21.420836 -56.079136)
		(end 25.961594 -56.079136)
		(width 0.1397)
		(layer "F.Cu")
		(net "I2C_C_SCL_CONN_R")
	)
	(segment
		(start 13.7922 -64.7446)
		(end 14.3256 -64.2112)
		(width 0.1397)
		(layer "F.Cu")
		(net "I2C_C_SCL_CONN_R")
	)
	(segment
		(start 37.079174 -57.920636)
		(end 37.999924 -56.999886)
		(width 0.1397)
		(layer "F.Cu")
		(net "I2C_C_SCL_CONN_R")
	)
	(segment
		(start 26.5176 -56.699658)
		(end 27.738578 -57.920636)
		(width 0.1397)
		(layer "F.Cu")
		(net "I2C_C_SCL_CONN_R")
	)
	(segment
		(start 20.500086 -56.999886)
		(end 19.979386 -56.999886)
		(width 0.1397)
		(layer "F.Cu")
		(net "I2C_C_SCL_CONN_R")
	)
	(segment
		(start 16.92275 -64.33185)
		(end 15.9004 -63.3095)
		(width 0.1397)
		(layer "F.Cu")
		(net "I2C_C_SCL_CONN_R")
	)
	(segment
		(start 18.2245 -64.33185)
		(end 16.92275 -64.33185)
		(width 0.1397)
		(layer "F.Cu")
		(net "I2C_C_SCL_CONN_R")
	)
	(segment
		(start 26.5176 -56.635142)
		(end 26.5176 -56.699658)
		(width 0.1397)
		(layer "F.Cu")
		(net "I2C_C_SCL_CONN_R")
	)
	(segment
		(start 19.979386 -56.999886)
		(end 18.4785 -58.500772)
		(width 0.1397)
		(layer "F.Cu")
		(net "I2C_C_SCL_CONN_R")
	)
	(segment
		(start 18.63725 -59.81065)
		(end 18.63725 -63.9191)
		(width 0.1397)
		(layer "F.Cu")
		(net "I2C_C_SCL_CONN_R")
	)
	(segment
		(start 15.2273 -63.3095)
		(end 14.3256 -64.2112)
		(width 0.1397)
		(layer "F.Cu")
		(net "I2C_C_SCL_CONN_R")
	)
	(segment
		(start 18.4785 -58.500772)
		(end 18.4785 -59.6519)
		(width 0.1397)
		(layer "F.Cu")
		(net "I2C_C_SCL_CONN_R")
	)
	(segment
		(start 27.738578 -57.920636)
		(end 37.079174 -57.920636)
		(width 0.1397)
		(layer "F.Cu")
		(net "I2C_C_SCL_CONN_R")
	)
	(segment
		(start 25.961594 -56.079136)
		(end 26.5176 -56.635142)
		(width 0.1397)
		(layer "F.Cu")
		(net "I2C_C_SCL_CONN_R")
	)
	(segment
		(start 13.7922 -66.0019)
		(end 13.7922 -64.7446)
		(width 0.1397)
		(layer "F.Cu")
		(net "I2C_C_SCL_CONN_R")
	)
	(segment
		(start 20.500086 -56.999886)
		(end 21.420836 -56.079136)
		(width 0.1397)
		(layer "F.Cu")
		(net "I2C_C_SCL_CONN_R")
	)
	(segment
		(start 18.63725 -63.9191)
		(end 18.2245 -64.33185)
		(width 0.1397)
		(layer "F.Cu")
		(net "I2C_C_SCL_CONN_R")
	)
	(segment
		(start 19.7866 -58.174636)
		(end 26.754836 -58.174636)
		(width 0.1397)
		(layer "F.Cu")
		(net "UPPER_TRAY_ID")
	)
	(segment
		(start 15.9639 -60.9727)
		(end 15.494 -60.9727)
		(width 0.1397)
		(layer "F.Cu")
		(net "UPPER_TRAY_ID")
	)
	(segment
		(start 17.145 -60.706)
		(end 16.2306 -60.706)
		(width 0.1397)
		(layer "F.Cu")
		(net "UPPER_TRAY_ID")
	)
	(segment
		(start 26.754836 -58.174636)
		(end 28.120086 -59.539886)
		(width 0.1397)
		(layer "F.Cu")
		(net "UPPER_TRAY_ID")
	)
	(segment
		(start 14.4526 -60.9727)
		(end 15.494 -60.9727)
		(width 0.1397)
		(layer "F.Cu")
		(net "UPPER_TRAY_ID")
	)
	(segment
		(start 17.7546 -60.0964)
		(end 17.145 -60.706)
		(width 0.1397)
		(layer "F.Cu")
		(net "UPPER_TRAY_ID")
	)
	(segment
		(start 16.2306 -60.706)
		(end 15.9639 -60.9727)
		(width 0.1397)
		(layer "F.Cu")
		(net "UPPER_TRAY_ID")
	)
	(via
		(at 19.7866 -58.174636)
		(size 0.5588)
		(drill 0.3048)
		(layers "F.Cu" "B.Cu")
		(net "UPPER_TRAY_ID")
	)
	(via
		(at 17.7546 -60.0964)
		(size 0.5588)
		(drill 0.3048)
		(layers "F.Cu" "B.Cu")
		(net "UPPER_TRAY_ID")
	)
	(segment
		(start 19.7866 -58.763408)
		(end 19.7866 -58.174636)
		(width 0.1397)
		(layer "B.Cu")
		(net "UPPER_TRAY_ID")
	)
	(segment
		(start 18.606008 -59.944)
		(end 19.7866 -58.763408)
		(width 0.1397)
		(layer "B.Cu")
		(net "UPPER_TRAY_ID")
	)
	(segment
		(start 17.7546 -60.0964)
		(end 17.907 -59.944)
		(width 0.1397)
		(layer "B.Cu")
		(net "UPPER_TRAY_ID")
	)
	(segment
		(start 17.907 -59.944)
		(end 18.606008 -59.944)
		(width 0.1397)
		(layer "B.Cu")
		(net "UPPER_TRAY_ID")
	)
	(segment
		(start 29.040836 -56.079136)
		(end 38.381178 -56.079136)
		(width 0.1397)
		(layer "F.Cu")
		(net "FCB_HW_REVISION")
	)
	(segment
		(start 44.699174 -57.920636)
		(end 45.619924 -56.999886)
		(width 0.1397)
		(layer "F.Cu")
		(net "FCB_HW_REVISION")
	)
	(segment
		(start 39.2938 -56.991758)
		(end 39.2938 -57.056274)
		(width 0.1397)
		(layer "F.Cu")
		(net "FCB_HW_REVISION")
	)
	(segment
		(start 28.120086 -56.999886)
		(end 29.040836 -56.079136)
		(width 0.1397)
		(layer "F.Cu")
		(net "FCB_HW_REVISION")
	)
	(segment
		(start 38.381178 -56.079136)
		(end 39.2938 -56.991758)
		(width 0.1397)
		(layer "F.Cu")
		(net "FCB_HW_REVISION")
	)
	(segment
		(start 15.6464 -53.6829)
		(end 17.3228 -53.6829)
		(width 0.1397)
		(layer "F.Cu")
		(net "FCB_HW_REVISION")
	)
	(segment
		(start 14.5796 -53.6829)
		(end 15.6464 -53.6829)
		(width 0.1397)
		(layer "F.Cu")
		(net "FCB_HW_REVISION")
	)
	(segment
		(start 17.3228 -53.6829)
		(end 18.1356 -52.8701)
		(width 0.1397)
		(layer "F.Cu")
		(net "FCB_HW_REVISION")
	)
	(segment
		(start 39.2938 -57.056274)
		(end 40.158162 -57.920636)
		(width 0.1397)
		(layer "F.Cu")
		(net "FCB_HW_REVISION")
	)
	(segment
		(start 40.158162 -57.920636)
		(end 44.699174 -57.920636)
		(width 0.1397)
		(layer "F.Cu")
		(net "FCB_HW_REVISION")
	)
	(via
		(at 18.1356 -52.8701)
		(size 0.5588)
		(drill 0.3048)
		(layers "F.Cu" "B.Cu")
		(net "FCB_HW_REVISION")
	)
	(segment
		(start 20.881594 -50.999136)
		(end 22.098 -52.215542)
		(width 0.1397)
		(layer "B.Cu")
		(net "FCB_HW_REVISION")
	)
	(segment
		(start 24.4348 -56.463692)
		(end 24.4348 -57.156858)
		(width 0.1397)
		(layer "B.Cu")
		(net "FCB_HW_REVISION")
	)
	(segment
		(start 22.098 -54.820058)
		(end 22.878542 -55.6006)
		(width 0.1397)
		(layer "B.Cu")
		(net "FCB_HW_REVISION")
	)
	(segment
		(start 20.006564 -50.999136)
		(end 20.881594 -50.999136)
		(width 0.1397)
		(layer "B.Cu")
		(net "FCB_HW_REVISION")
	)
	(segment
		(start 25.198578 -57.920636)
		(end 27.199336 -57.920636)
		(width 0.1397)
		(layer "B.Cu")
		(net "FCB_HW_REVISION")
	)
	(segment
		(start 27.199336 -57.920636)
		(end 28.120086 -56.999886)
		(width 0.1397)
		(layer "B.Cu")
		(net "FCB_HW_REVISION")
	)
	(segment
		(start 22.098 -52.215542)
		(end 22.098 -54.820058)
		(width 0.1397)
		(layer "B.Cu")
		(net "FCB_HW_REVISION")
	)
	(segment
		(start 23.571708 -55.6006)
		(end 24.4348 -56.463692)
		(width 0.1397)
		(layer "B.Cu")
		(net "FCB_HW_REVISION")
	)
	(segment
		(start 18.1356 -52.8701)
		(end 20.006564 -50.999136)
		(width 0.1397)
		(layer "B.Cu")
		(net "FCB_HW_REVISION")
	)
	(segment
		(start 22.878542 -55.6006)
		(end 23.571708 -55.6006)
		(width 0.1397)
		(layer "B.Cu")
		(net "FCB_HW_REVISION")
	)
	(segment
		(start 24.4348 -57.156858)
		(end 25.198578 -57.920636)
		(width 0.1397)
		(layer "B.Cu")
		(net "FCB_HW_REVISION")
	)
	(segment
		(start 11.6332 -46.5582)
		(end 11.0998 -46.0248)
		(width 0.1397)
		(layer "F.Cu")
		(net "SEB_PEER_1A_HB")
	)
	(segment
		(start 20.349972 -55.380636)
		(end 24.659336 -55.380636)
		(width 0.1397)
		(layer "F.Cu")
		(net "SEB_PEER_1A_HB")
	)
	(segment
		(start 14.4399 -46.5582)
		(end 14.4399 -45.5422)
		(width 0.1397)
		(layer "F.Cu")
		(net "SEB_PEER_1A_HB")
	)
	(segment
		(start 12.573 -178.689)
		(end 10.922 -178.689)
		(width 0.1397)
		(layer "F.Cu")
		(net "SEB_PEER_1A_HB")
	)
	(segment
		(start 10.4394 -58.674)
		(end 10.86485 -58.24855)
		(width 0.1397)
		(layer "F.Cu")
		(net "SEB_PEER_1A_HB")
	)
	(segment
		(start 10.86485 -58.24855)
		(end 14.877542 -58.24855)
		(width 0.1397)
		(layer "F.Cu")
		(net "SEB_PEER_1A_HB")
	)
	(segment
		(start 15.372842 -58.74385)
		(end 16.986758 -58.74385)
		(width 0.1397)
		(layer "F.Cu")
		(net "SEB_PEER_1A_HB")
	)
	(segment
		(start 10.922 -178.689)
		(end 9.2075 -176.9745)
		(width 0.1397)
		(layer "F.Cu")
		(net "SEB_PEER_1A_HB")
	)
	(segment
		(start 14.4399 -46.5582)
		(end 11.6332 -46.5582)
		(width 0.1397)
		(layer "F.Cu")
		(net "SEB_PEER_1A_HB")
	)
	(segment
		(start 24.659336 -55.380636)
		(end 25.580086 -54.459886)
		(width 0.1397)
		(layer "F.Cu")
		(net "SEB_PEER_1A_HB")
	)
	(segment
		(start 9.2075 -176.9745)
		(end 9.2075 -175.40224)
		(width 0.1397)
		(layer "F.Cu")
		(net "SEB_PEER_1A_HB")
	)
	(segment
		(start 16.986758 -58.74385)
		(end 20.349972 -55.380636)
		(width 0.1397)
		(layer "F.Cu")
		(net "SEB_PEER_1A_HB")
	)
	(segment
		(start 14.877542 -58.24855)
		(end 15.372842 -58.74385)
		(width 0.1397)
		(layer "F.Cu")
		(net "SEB_PEER_1A_HB")
	)
	(via
		(at 11.0998 -46.0248)
		(size 0.5588)
		(drill 0.3048)
		(layers "F.Cu" "B.Cu")
		(net "SEB_PEER_1A_HB")
	)
	(via
		(at 10.4394 -58.674)
		(size 0.5588)
		(drill 0.3048)
		(layers "F.Cu" "B.Cu")
		(net "SEB_PEER_1A_HB")
	)
	(via
		(at 12.573 -178.689)
		(size 0.5588)
		(drill 0.3048)
		(layers "F.Cu" "B.Cu")
		(net "SEB_PEER_1A_HB")
	)
	(segment
		(start 10.01395 -52.20335)
		(end 10.01395 -47.11065)
		(width 0.1397)
		(layer "B.Cu")
		(net "SEB_PEER_1A_HB")
	)
	(segment
		(start 8.001 -144.399)
		(end 8.001 -146.177)
		(width 0.1397)
		(layer "B.Cu")
		(net "SEB_PEER_1A_HB")
	)
	(segment
		(start 6.395974 -134.193026)
		(end 5.421884 -135.167116)
		(width 0.1397)
		(layer "B.Cu")
		(net "SEB_PEER_1A_HB")
	)
	(segment
		(start 4.050284 -82.868516)
		(end 4.050284 -113.51641)
		(width 0.1397)
		(layer "B.Cu")
		(net "SEB_PEER_1A_HB")
	)
	(segment
		(start 5.3594 -81.5594)
		(end 4.050284 -82.868516)
		(width 0.1397)
		(layer "B.Cu")
		(net "SEB_PEER_1A_HB")
	)
	(segment
		(start 10.01395 -47.11065)
		(end 11.0998 -46.0248)
		(width 0.1397)
		(layer "B.Cu")
		(net "SEB_PEER_1A_HB")
	)
	(segment
		(start 6.395974 -121.63933)
		(end 6.395974 -134.193026)
		(width 0.1397)
		(layer "B.Cu")
		(net "SEB_PEER_1A_HB")
	)
	(segment
		(start 10.4394 -58.674)
		(end 6.0706 -63.0428)
		(width 0.1397)
		(layer "B.Cu")
		(net "SEB_PEER_1A_HB")
	)
	(segment
		(start 12.78255 -178.47945)
		(end 12.573 -178.689)
		(width 0.1397)
		(layer "B.Cu")
		(net "SEB_PEER_1A_HB")
	)
	(segment
		(start 8.001 -146.177)
		(end 12.78255 -150.95855)
		(width 0.1397)
		(layer "B.Cu")
		(net "SEB_PEER_1A_HB")
	)
	(segment
		(start 3.576066 -118.819422)
		(end 6.395974 -121.63933)
		(width 0.1397)
		(layer "B.Cu")
		(net "SEB_PEER_1A_HB")
	)
	(segment
		(start 6.0706 -63.0428)
		(end 6.0706 -68.834)
		(width 0.1397)
		(layer "B.Cu")
		(net "SEB_PEER_1A_HB")
	)
	(segment
		(start 5.3594 -69.5452)
		(end 5.3594 -81.5594)
		(width 0.1397)
		(layer "B.Cu")
		(net "SEB_PEER_1A_HB")
	)
	(segment
		(start 6.0706 -68.834)
		(end 5.3594 -69.5452)
		(width 0.1397)
		(layer "B.Cu")
		(net "SEB_PEER_1A_HB")
	)
	(segment
		(start 10.4394 -52.6288)
		(end 10.01395 -52.20335)
		(width 0.1397)
		(layer "B.Cu")
		(net "SEB_PEER_1A_HB")
	)
	(segment
		(start 3.576066 -113.990628)
		(end 3.576066 -118.819422)
		(width 0.1397)
		(layer "B.Cu")
		(net "SEB_PEER_1A_HB")
	)
	(segment
		(start 5.421884 -135.167116)
		(end 5.421884 -141.819884)
		(width 0.1397)
		(layer "B.Cu")
		(net "SEB_PEER_1A_HB")
	)
	(segment
		(start 12.78255 -150.95855)
		(end 12.78255 -178.47945)
		(width 0.1397)
		(layer "B.Cu")
		(net "SEB_PEER_1A_HB")
	)
	(segment
		(start 10.4394 -58.674)
		(end 10.4394 -52.6288)
		(width 0.1397)
		(layer "B.Cu")
		(net "SEB_PEER_1A_HB")
	)
	(segment
		(start 5.421884 -141.819884)
		(end 8.001 -144.399)
		(width 0.1397)
		(layer "B.Cu")
		(net "SEB_PEER_1A_HB")
	)
	(segment
		(start 4.050284 -113.51641)
		(end 3.576066 -113.990628)
		(width 0.1397)
		(layer "B.Cu")
		(net "SEB_PEER_1A_HB")
	)
	(segment
		(start 12.6238 -41.021)
		(end 14.1986 -39.4462)
		(width 0.1397)
		(layer "F.Cu")
		(net "SEB_PEER_2B_HB")
	)
	(segment
		(start 36.449 -50.546)
		(end 41.706038 -50.546)
		(width 0.1397)
		(layer "F.Cu")
		(net "SEB_PEER_2B_HB")
	)
	(segment
		(start 41.706038 -50.546)
		(end 43.079924 -51.919886)
		(width 0.1397)
		(layer "F.Cu")
		(net "SEB_PEER_2B_HB")
	)
	(segment
		(start 9.9822 -44.2976)
		(end 12.6238 -41.656)
		(width 0.1397)
		(layer "F.Cu")
		(net "SEB_PEER_2B_HB")
	)
	(segment
		(start 12.617196 -174.752)
		(end 11.020552 -176.348644)
		(width 0.1397)
		(layer "F.Cu")
		(net "SEB_PEER_2B_HB")
	)
	(segment
		(start 28.1432 -42.2402)
		(end 36.449 -50.546)
		(width 0.1397)
		(layer "F.Cu")
		(net "SEB_PEER_2B_HB")
	)
	(segment
		(start 16.3576 -40.4622)
		(end 18.1356 -42.2402)
		(width 0.1397)
		(layer "F.Cu")
		(net "SEB_PEER_2B_HB")
	)
	(segment
		(start 14.1986 -39.4462)
		(end 14.4399 -39.4462)
		(width 0.1397)
		(layer "F.Cu")
		(net "SEB_PEER_2B_HB")
	)
	(segment
		(start 14.4399 -39.5732)
		(end 15.3289 -40.4622)
		(width 0.1397)
		(layer "F.Cu")
		(net "SEB_PEER_2B_HB")
	)
	(segment
		(start 12.6238 -41.656)
		(end 12.6238 -41.021)
		(width 0.1397)
		(layer "F.Cu")
		(net "SEB_PEER_2B_HB")
	)
	(segment
		(start 13.1445 -174.752)
		(end 12.617196 -174.752)
		(width 0.1397)
		(layer "F.Cu")
		(net "SEB_PEER_2B_HB")
	)
	(segment
		(start 18.1356 -42.2402)
		(end 28.1432 -42.2402)
		(width 0.1397)
		(layer "F.Cu")
		(net "SEB_PEER_2B_HB")
	)
	(segment
		(start 9.9822 -44.577)
		(end 9.9822 -44.2976)
		(width 0.1397)
		(layer "F.Cu")
		(net "SEB_PEER_2B_HB")
	)
	(segment
		(start 15.3289 -40.4622)
		(end 16.3576 -40.4622)
		(width 0.1397)
		(layer "F.Cu")
		(net "SEB_PEER_2B_HB")
	)
	(segment
		(start 14.4399 -39.4462)
		(end 14.4399 -39.5732)
		(width 0.1397)
		(layer "F.Cu")
		(net "SEB_PEER_2B_HB")
	)
	(via
		(at 11.020552 -176.348644)
		(size 0.5588)
		(drill 0.3048)
		(layers "F.Cu" "B.Cu")
		(net "SEB_PEER_2B_HB")
	)
	(via
		(at 9.9822 -44.577)
		(size 0.5588)
		(drill 0.3048)
		(layers "F.Cu" "B.Cu")
		(net "SEB_PEER_2B_HB")
	)
	(segment
		(start 2.687066 -119.187722)
		(end 2.687066 -113.622328)
		(width 0.1397)
		(layer "B.Cu")
		(net "SEB_PEER_2B_HB")
	)
	(segment
		(start 11.020552 -175.758856)
		(end 2.687574 -167.425878)
		(width 0.1397)
		(layer "B.Cu")
		(net "SEB_PEER_2B_HB")
	)
	(segment
		(start 8.009382 -57.404)
		(end 8.451088 -57.404)
		(width 0.1397)
		(layer "B.Cu")
		(net "SEB_PEER_2B_HB")
	)
	(segment
		(start 2.687574 -80.878426)
		(end 4.445 -79.121)
		(width 0.1397)
		(layer "B.Cu")
		(net "SEB_PEER_2B_HB")
	)
	(segment
		(start 8.451088 -57.404)
		(end 9.226296 -56.628792)
		(width 0.1397)
		(layer "B.Cu")
		(net "SEB_PEER_2B_HB")
	)
	(segment
		(start 2.687066 -113.622328)
		(end 2.687574 -113.62182)
		(width 0.1397)
		(layer "B.Cu")
		(net "SEB_PEER_2B_HB")
	)
	(segment
		(start 2.687574 -119.18823)
		(end 2.687066 -119.187722)
		(width 0.1397)
		(layer "B.Cu")
		(net "SEB_PEER_2B_HB")
	)
	(segment
		(start 4.445 -60.968382)
		(end 8.009382 -57.404)
		(width 0.1397)
		(layer "B.Cu")
		(net "SEB_PEER_2B_HB")
	)
	(segment
		(start 9.226296 -56.628792)
		(end 9.226296 -52.685696)
		(width 0.1397)
		(layer "B.Cu")
		(net "SEB_PEER_2B_HB")
	)
	(segment
		(start 8.75665 -45.80255)
		(end 9.9822 -44.577)
		(width 0.1397)
		(layer "B.Cu")
		(net "SEB_PEER_2B_HB")
	)
	(segment
		(start 2.687574 -113.62182)
		(end 2.687574 -80.878426)
		(width 0.1397)
		(layer "B.Cu")
		(net "SEB_PEER_2B_HB")
	)
	(segment
		(start 9.226296 -52.685696)
		(end 8.75665 -52.21605)
		(width 0.1397)
		(layer "B.Cu")
		(net "SEB_PEER_2B_HB")
	)
	(segment
		(start 11.020552 -176.348644)
		(end 11.020552 -175.758856)
		(width 0.1397)
		(layer "B.Cu")
		(net "SEB_PEER_2B_HB")
	)
	(segment
		(start 8.75665 -52.21605)
		(end 8.75665 -45.80255)
		(width 0.1397)
		(layer "B.Cu")
		(net "SEB_PEER_2B_HB")
	)
	(segment
		(start 4.445 -79.121)
		(end 4.445 -60.968382)
		(width 0.1397)
		(layer "B.Cu")
		(net "SEB_PEER_2B_HB")
	)
	(segment
		(start 2.687574 -167.425878)
		(end 2.687574 -119.18823)
		(width 0.1397)
		(layer "B.Cu")
		(net "SEB_PEER_2B_HB")
	)
	(segment
		(start 44.647104 -139.4714)
		(end 43.7134 -139.4714)
		(width 0.1397)
		(layer "F.Cu")
		(net "P12VL_2490_EN_2")
	)
	(segment
		(start 38.89629 -142.0495)
		(end 38.89629 -143.81099)
		(width 0.1397)
		(layer "F.Cu")
		(net "P12VL_2490_EN_2")
	)
	(segment
		(start 43.2054 -139.4714)
		(end 42.1386 -140.5382)
		(width 0.1397)
		(layer "F.Cu")
		(net "P12VL_2490_EN_2")
	)
	(segment
		(start 39.3065 -143.5862)
		(end 38.989 -143.9037)
		(width 0.1397)
		(layer "F.Cu")
		(net "P12VL_2490_EN_2")
	)
	(segment
		(start 43.7134 -139.4714)
		(end 43.2054 -139.4714)
		(width 0.1397)
		(layer "F.Cu")
		(net "P12VL_2490_EN_2")
	)
	(segment
		(start 38.89629 -143.81099)
		(end 38.989 -143.9037)
		(width 0.1397)
		(layer "F.Cu")
		(net "P12VL_2490_EN_2")
	)
	(segment
		(start 42.1386 -140.5382)
		(end 40.7162 -141.9606)
		(width 0.1397)
		(layer "F.Cu")
		(net "P12VL_2490_EN_2")
	)
	(segment
		(start 39.3065 -143.3957)
		(end 39.3065 -143.5862)
		(width 0.1397)
		(layer "F.Cu")
		(net "P12VL_2490_EN_2")
	)
	(segment
		(start 46.377352 -137.741152)
		(end 44.647104 -139.4714)
		(width 0.1397)
		(layer "F.Cu")
		(net "P12VL_2490_EN_2")
	)
	(segment
		(start 40.7162 -141.9606)
		(end 40.7162 -141.986)
		(width 0.1397)
		(layer "F.Cu")
		(net "P12VL_2490_EN_2")
	)
	(segment
		(start 40.7162 -141.986)
		(end 39.3065 -143.3957)
		(width 0.1397)
		(layer "F.Cu")
		(net "P12VL_2490_EN_2")
	)
	(via
		(at 46.377352 -137.741152)
		(size 0.5588)
		(drill 0.3048)
		(layers "F.Cu" "B.Cu")
		(net "P12VL_2490_EN_2")
	)
	(segment
		(start 51.60645 -104.966008)
		(end 51.60645 -122.402854)
		(width 0.1397)
		(layer "B.Cu")
		(net "P12VL_2490_EN_2")
	)
	(segment
		(start 43.079924 -59.539886)
		(end 43.079924 -59.54014)
		(width 0.1397)
		(layer "B.Cu")
		(net "P12VL_2490_EN_2")
	)
	(segment
		(start 51.60645 -122.402854)
		(end 49.86655 -124.142754)
		(width 0.1397)
		(layer "B.Cu")
		(net "P12VL_2490_EN_2")
	)
	(segment
		(start 49.86655 -134.251954)
		(end 46.377352 -137.741152)
		(width 0.1397)
		(layer "B.Cu")
		(net "P12VL_2490_EN_2")
	)
	(segment
		(start 49.86655 -124.142754)
		(end 49.86655 -134.251954)
		(width 0.1397)
		(layer "B.Cu")
		(net "P12VL_2490_EN_2")
	)
	(segment
		(start 50.362104 -64.916304)
		(end 50.362104 -103.721662)
		(width 0.1397)
		(layer "B.Cu")
		(net "P12VL_2490_EN_2")
	)
	(segment
		(start 43.079924 -59.54014)
		(end 44.372784 -60.833)
		(width 0.1397)
		(layer "B.Cu")
		(net "P12VL_2490_EN_2")
	)
	(segment
		(start 50.362104 -103.721662)
		(end 51.60645 -104.966008)
		(width 0.1397)
		(layer "B.Cu")
		(net "P12VL_2490_EN_2")
	)
	(segment
		(start 44.372784 -60.833)
		(end 46.2788 -60.833)
		(width 0.1397)
		(layer "B.Cu")
		(net "P12VL_2490_EN_2")
	)
	(segment
		(start 46.2788 -60.833)
		(end 50.362104 -64.916304)
		(width 0.1397)
		(layer "B.Cu")
		(net "P12VL_2490_EN_2")
	)
	(segment
		(start 39.9034 -145.8595)
		(end 39.9034 -143.6116)
		(width 0.1397)
		(layer "F.Cu")
		(net "P12VL_2490_EN_1")
	)
	(segment
		(start 39.9034 -143.6116)
		(end 40.64 -142.875)
		(width 0.1397)
		(layer "F.Cu")
		(net "P12VL_2490_EN_1")
	)
	(segment
		(start 40.132 -146.0881)
		(end 39.9034 -145.8595)
		(width 0.1397)
		(layer "F.Cu")
		(net "P12VL_2490_EN_1")
	)
	(via
		(at 40.64 -142.875)
		(size 0.5588)
		(drill 0.3048)
		(layers "F.Cu" "B.Cu")
		(net "P12VL_2490_EN_1")
	)
	(via
		(at 46.736762 -136.270238)
		(size 0.7112)
		(drill 0.3556)
		(layers "F.Cu" "B.Cu")
		(net "P12VL_2490_EN_1")
	)
	(segment
		(start 40.64 -142.875)
		(end 40.64 -142.367)
		(width 0.1397)
		(layer "B.Cu")
		(net "P12VL_2490_EN_1")
	)
	(segment
		(start 47.4853 -135.5217)
		(end 46.736762 -136.270238)
		(width 0.1397)
		(layer "B.Cu")
		(net "P12VL_2490_EN_1")
	)
	(segment
		(start 44.220384 -63.2206)
		(end 45.67555 -63.2206)
		(width 0.1397)
		(layer "B.Cu")
		(net "P12VL_2490_EN_1")
	)
	(segment
		(start 50.37455 -111.354108)
		(end 50.927 -111.906558)
		(width 0.1397)
		(layer "B.Cu")
		(net "P12VL_2490_EN_1")
	)
	(segment
		(start 50.37455 -107.16895)
		(end 50.37455 -111.354108)
		(width 0.1397)
		(layer "B.Cu")
		(net "P12VL_2490_EN_1")
	)
	(segment
		(start 49.91735 -67.4624)
		(end 49.91735 -106.71175)
		(width 0.1397)
		(layer "B.Cu")
		(net "P12VL_2490_EN_1")
	)
	(segment
		(start 50.927 -121.3866)
		(end 48.21555 -124.09805)
		(width 0.1397)
		(layer "B.Cu")
		(net "P12VL_2490_EN_1")
	)
	(segment
		(start 49.91735 -106.71175)
		(end 50.37455 -107.16895)
		(width 0.1397)
		(layer "B.Cu")
		(net "P12VL_2490_EN_1")
	)
	(segment
		(start 50.927 -111.906558)
		(end 50.927 -121.3866)
		(width 0.1397)
		(layer "B.Cu")
		(net "P12VL_2490_EN_1")
	)
	(segment
		(start 48.21555 -132.250942)
		(end 47.4853 -132.981192)
		(width 0.1397)
		(layer "B.Cu")
		(net "P12VL_2490_EN_1")
	)
	(segment
		(start 45.67555 -63.2206)
		(end 49.91735 -67.4624)
		(width 0.1397)
		(layer "B.Cu")
		(net "P12VL_2490_EN_1")
	)
	(segment
		(start 43.079924 -62.079886)
		(end 43.079924 -62.08014)
		(width 0.1397)
		(layer "B.Cu")
		(net "P12VL_2490_EN_1")
	)
	(segment
		(start 47.4853 -132.981192)
		(end 47.4853 -135.5217)
		(width 0.1397)
		(layer "B.Cu")
		(net "P12VL_2490_EN_1")
	)
	(segment
		(start 43.079924 -62.08014)
		(end 44.220384 -63.2206)
		(width 0.1397)
		(layer "B.Cu")
		(net "P12VL_2490_EN_1")
	)
	(segment
		(start 40.64 -142.367)
		(end 46.736762 -136.270238)
		(width 0.1397)
		(layer "B.Cu")
		(net "P12VL_2490_EN_1")
	)
	(segment
		(start 48.21555 -124.09805)
		(end 48.21555 -132.250942)
		(width 0.1397)
		(layer "B.Cu")
		(net "P12VL_2490_EN_1")
	)
	(segment
		(start 18.3388 -398.4498)
		(end 19.1516 -399.2626)
		(width 0.508)
		(layer "F.Cu")
		(net "ADM1276_GATE_DRV0")
	)
	(segment
		(start 17.1958 -398.4498)
		(end 18.3388 -398.4498)
		(width 0.508)
		(layer "F.Cu")
		(net "ADM1276_GATE_DRV0")
	)
	(segment
		(start 33.6042 -378.7394)
		(end 35.0139 -378.7394)
		(width 0.508)
		(layer "F.Cu")
		(net "ADM1276_GATE_DRV0")
	)
	(segment
		(start 19.1516 -399.2626)
		(end 19.1516 -400.2024)
		(width 0.508)
		(layer "F.Cu")
		(net "ADM1276_GATE_DRV0")
	)
	(segment
		(start 35.0139 -378.7394)
		(end 35.0266 -378.7521)
		(width 0.508)
		(layer "F.Cu")
		(net "ADM1276_GATE_DRV0")
	)
	(via
		(at 17.1958 -398.4498)
		(size 0.5588)
		(drill 0.3048)
		(layers "F.Cu" "B.Cu")
		(net "ADM1276_GATE_DRV0")
	)
	(via
		(at 20.8026 -383.5908)
		(size 0.7112)
		(drill 0.3556)
		(layers "F.Cu" "B.Cu")
		(net "ADM1276_GATE_DRV0")
	)
	(via
		(at 33.6042 -378.7394)
		(size 0.5588)
		(drill 0.3048)
		(layers "F.Cu" "B.Cu")
		(net "ADM1276_GATE_DRV0")
	)
	(segment
		(start 32.2072 -380.1364)
		(end 33.6042 -378.7394)
		(width 0.508)
		(layer "B.Cu")
		(net "ADM1276_GATE_DRV0")
	)
	(segment
		(start 20.8026 -383.5908)
		(end 24.257 -380.1364)
		(width 0.508)
		(layer "B.Cu")
		(net "ADM1276_GATE_DRV0")
	)
	(segment
		(start 17.1958 -398.4498)
		(end 17.1958 -387.1976)
		(width 0.508)
		(layer "B.Cu")
		(net "ADM1276_GATE_DRV0")
	)
	(segment
		(start 17.1958 -387.1976)
		(end 20.8026 -383.5908)
		(width 0.508)
		(layer "B.Cu")
		(net "ADM1276_GATE_DRV0")
	)
	(segment
		(start 24.257 -380.1364)
		(end 32.2072 -380.1364)
		(width 0.508)
		(layer "B.Cu")
		(net "ADM1276_GATE_DRV0")
	)
	(segment
		(start 48.4505 -110.901988)
		(end 48.4505 -111.633)
		(width 0.508)
		(layer "F.Cu")
		(net "P12VL_2490_GATE_DRV_2")
	)
	(segment
		(start 48.241712 -110.6932)
		(end 48.4505 -110.901988)
		(width 0.508)
		(layer "F.Cu")
		(net "P12VL_2490_GATE_DRV_2")
	)
	(segment
		(start 46.736 -111.633)
		(end 48.4505 -111.633)
		(width 0.508)
		(layer "F.Cu")
		(net "P12VL_2490_GATE_DRV_2")
	)
	(via
		(at 48.241712 -110.6932)
		(size 0.7112)
		(drill 0.3556)
		(layers "F.Cu" "B.Cu")
		(net "P12VL_2490_GATE_DRV_2")
	)
	(segment
		(start 21.336 -111.76)
		(end 21.336 -110.998)
		(width 0.508)
		(layer "F.Cu")
		(net "P12VU_2490_GATE_DRV_2")
	)
	(segment
		(start 17.9705 -109.7915)
		(end 17.9705 -109.5502)
		(width 0.508)
		(layer "F.Cu")
		(net "P12VU_2490_GATE_DRV_2")
	)
	(segment
		(start 17.9705 -109.5502)
		(end 17.9705 -108.5469)
		(width 0.508)
		(layer "F.Cu")
		(net "P12VU_2490_GATE_DRV_2")
	)
	(segment
		(start 21.336 -110.998)
		(end 20.7772 -110.4392)
		(width 0.508)
		(layer "F.Cu")
		(net "P12VU_2490_GATE_DRV_2")
	)
	(segment
		(start 18.6182 -110.4392)
		(end 17.9705 -109.7915)
		(width 0.508)
		(layer "F.Cu")
		(net "P12VU_2490_GATE_DRV_2")
	)
	(segment
		(start 20.7772 -110.4392)
		(end 18.6182 -110.4392)
		(width 0.508)
		(layer "F.Cu")
		(net "P12VU_2490_GATE_DRV_2")
	)
	(segment
		(start 17.9705 -108.5469)
		(end 18.0086 -108.5088)
		(width 0.508)
		(layer "F.Cu")
		(net "P12VU_2490_GATE_DRV_2")
	)
	(via
		(at 18.0086 -108.5088)
		(size 0.7112)
		(drill 0.3556)
		(layers "F.Cu" "B.Cu")
		(net "P12VU_2490_GATE_DRV_2")
	)
	(segment
		(start 42.82948 -180.366416)
		(end 42.82948 -179.52212)
		(width 0.1397)
		(layer "F.Cu")
		(net "D_LATCH_Q#")
	)
	(segment
		(start 42.82948 -179.52212)
		(end 43.1292 -179.2224)
		(width 0.1397)
		(layer "F.Cu")
		(net "D_LATCH_Q#")
	)
	(segment
		(start 43.1292 -179.2224)
		(end 45.2374 -179.2224)
		(width 0.1397)
		(layer "F.Cu")
		(net "D_LATCH_Q#")
	)
	(segment
		(start 45.2374 -179.2224)
		(end 45.466 -179.451)
		(width 0.1397)
		(layer "F.Cu")
		(net "D_LATCH_Q#")
	)
	(segment
		(start 6.8072 -430.7713)
		(end 6.0071 -429.9712)
		(width 0.1397)
		(layer "F.Cu")
		(net "LED_DR_LED0_BLUE")
	)
	(segment
		(start 5.947918 -433.671472)
		(end 6.044946 -433.7685)
		(width 0.1397)
		(layer "F.Cu")
		(net "LED_DR_LED0_BLUE")
	)
	(segment
		(start 7.936992 -433.7685)
		(end 8.369046 -434.200554)
		(width 0.1397)
		(layer "F.Cu")
		(net "LED_DR_LED0_BLUE")
	)
	(segment
		(start 5.947918 -432.456082)
		(end 6.8072 -431.5968)
		(width 0.1397)
		(layer "F.Cu")
		(net "LED_DR_LED0_BLUE")
	)
	(segment
		(start 9.017 -440.292998)
		(end 7.949946 -441.360052)
		(width 0.1397)
		(layer "F.Cu")
		(net "LED_DR_LED0_BLUE")
	)
	(segment
		(start 6.8072 -431.5968)
		(end 6.8072 -430.7713)
		(width 0.1397)
		(layer "F.Cu")
		(net "LED_DR_LED0_BLUE")
	)
	(segment
		(start 8.369046 -434.200554)
		(end 9.017 -434.848508)
		(width 0.1397)
		(layer "F.Cu")
		(net "LED_DR_LED0_BLUE")
	)
	(segment
		(start 6.044946 -433.7685)
		(end 7.936992 -433.7685)
		(width 0.1397)
		(layer "F.Cu")
		(net "LED_DR_LED0_BLUE")
	)
	(segment
		(start 5.947918 -433.671472)
		(end 5.947918 -432.456082)
		(width 0.1397)
		(layer "F.Cu")
		(net "LED_DR_LED0_BLUE")
	)
	(segment
		(start 9.017 -434.848508)
		(end 9.017 -440.292998)
		(width 0.1397)
		(layer "F.Cu")
		(net "LED_DR_LED0_BLUE")
	)
	(via
		(at 8.369046 -434.200554)
		(size 0.7112)
		(drill 0.3556)
		(layers "F.Cu" "B.Cu")
		(net "LED_DR_LED0_BLUE")
	)
	(segment
		(start 38.13556 -251.62256)
		(end 39.116 -252.603)
		(width 0.1397)
		(layer "F.Cu")
		(net "LED_DR_LED6_RESERVE")
	)
	(segment
		(start 38.6334 -253.9365)
		(end 38.6334 -253.0856)
		(width 0.1397)
		(layer "F.Cu")
		(net "LED_DR_LED6_RESERVE")
	)
	(segment
		(start 38.6334 -253.0856)
		(end 39.116 -252.603)
		(width 0.1397)
		(layer "F.Cu")
		(net "LED_DR_LED6_RESERVE")
	)
	(segment
		(start 38.13556 -249.3518)
		(end 38.13556 -251.62256)
		(width 0.1397)
		(layer "F.Cu")
		(net "LED_DR_LED6_RESERVE")
	)
	(segment
		(start 35.5346 -249.3518)
		(end 35.5346 -251.2568)
		(width 0.1397)
		(layer "F.Cu")
		(net "I2C_C_SDA_LEDDRV")
	)
	(segment
		(start 34.29 -253.9365)
		(end 34.0741 -253.9365)
		(width 0.1397)
		(layer "F.Cu")
		(net "I2C_C_SDA_LEDDRV")
	)
	(segment
		(start 35.5346 -251.2568)
		(end 34.66465 -252.12675)
		(width 0.1397)
		(layer "F.Cu")
		(net "I2C_C_SDA_LEDDRV")
	)
	(segment
		(start 34.66465 -252.12675)
		(end 34.66465 -253.56185)
		(width 0.1397)
		(layer "F.Cu")
		(net "I2C_C_SDA_LEDDRV")
	)
	(segment
		(start 34.0741 -253.9365)
		(end 33.2486 -254.762)
		(width 0.1397)
		(layer "F.Cu")
		(net "I2C_C_SDA_LEDDRV")
	)
	(segment
		(start 34.66465 -253.56185)
		(end 34.29 -253.9365)
		(width 0.1397)
		(layer "F.Cu")
		(net "I2C_C_SDA_LEDDRV")
	)
	(segment
		(start 33.2486 -254.762)
		(end 33.2486 -254.8636)
		(width 0.1397)
		(layer "F.Cu")
		(net "I2C_C_SDA_LEDDRV")
	)
	(via
		(at 33.2486 -254.8636)
		(size 0.7112)
		(drill 0.3556)
		(layers "F.Cu" "B.Cu")
		(net "I2C_C_SDA_LEDDRV")
	)
	(segment
		(start 42.9641 -178.0794)
		(end 42.5958 -177.7111)
		(width 0.1397)
		(layer "F.Cu")
		(net "D_LATCH_Q")
	)
	(segment
		(start 42.17924 -180.366416)
		(end 42.17924 -179.02936)
		(width 0.1397)
		(layer "F.Cu")
		(net "D_LATCH_Q")
	)
	(segment
		(start 42.5958 -177.7111)
		(end 42.5958 -178.6128)
		(width 0.1397)
		(layer "F.Cu")
		(net "D_LATCH_Q")
	)
	(segment
		(start 42.17924 -179.02936)
		(end 42.5704 -178.6382)
		(width 0.1397)
		(layer "F.Cu")
		(net "D_LATCH_Q")
	)
	(segment
		(start 43.6245 -178.0794)
		(end 42.9641 -178.0794)
		(width 0.1397)
		(layer "F.Cu")
		(net "D_LATCH_Q")
	)
	(segment
		(start 42.5958 -178.6128)
		(end 42.5704 -178.6382)
		(width 0.1397)
		(layer "F.Cu")
		(net "D_LATCH_Q")
	)
	(via
		(at 42.5704 -178.6382)
		(size 0.7112)
		(drill 0.3556)
		(layers "F.Cu" "B.Cu")
		(net "D_LATCH_Q")
	)
	(segment
		(start 38.735 -171.323)
		(end 38.862 -171.45)
		(width 0.1397)
		(layer "F.Cu")
		(net "TEMP_ALM#_IN")
	)
	(segment
		(start 37.084 -171.323)
		(end 38.735 -171.323)
		(width 0.1397)
		(layer "F.Cu")
		(net "TEMP_ALM#_IN")
	)
	(segment
		(start 38.862 -171.45)
		(end 38.862 -173.2915)
		(width 0.1397)
		(layer "F.Cu")
		(net "TEMP_ALM#_IN")
	)
	(segment
		(start 36.703 -171.45)
		(end 36.957 -171.45)
		(width 0.1397)
		(layer "F.Cu")
		(net "TEMP_ALM#_IN")
	)
	(segment
		(start 35.97275 -173.2915)
		(end 35.97275 -172.18025)
		(width 0.1397)
		(layer "F.Cu")
		(net "TEMP_ALM#_IN")
	)
	(segment
		(start 36.957 -171.45)
		(end 37.084 -171.323)
		(width 0.1397)
		(layer "F.Cu")
		(net "TEMP_ALM#_IN")
	)
	(segment
		(start 35.97275 -172.18025)
		(end 36.703 -171.45)
		(width 0.1397)
		(layer "F.Cu")
		(net "TEMP_ALM#_IN")
	)
	(segment
		(start 38.862 -173.2915)
		(end 39.243 -173.6725)
		(width 0.1397)
		(layer "F.Cu")
		(net "TEMP_ALM#_IN")
	)
	(via
		(at 36.957 -171.45)
		(size 0.7112)
		(drill 0.3556)
		(layers "F.Cu" "B.Cu")
		(net "TEMP_ALM#_IN")
	)
	(segment
		(start 40.87876 -179.43576)
		(end 40.87876 -180.366416)
		(width 0.1397)
		(layer "F.Cu")
		(net "TEMP_ALM#_IN_D")
	)
	(segment
		(start 37.720016 -175.489616)
		(end 37.4269 -175.1965)
		(width 0.1397)
		(layer "F.Cu")
		(net "TEMP_ALM#_IN_D")
	)
	(segment
		(start 36.6395 -176.657)
		(end 36.6395 -175.514)
		(width 0.1397)
		(layer "F.Cu")
		(net "TEMP_ALM#_IN_D")
	)
	(segment
		(start 38.910768 -179.148232)
		(end 39.243 -178.816)
		(width 0.1397)
		(layer "F.Cu")
		(net "TEMP_ALM#_IN_D")
	)
	(segment
		(start 37.4269 -175.1965)
		(end 36.957 -175.1965)
		(width 0.1397)
		(layer "F.Cu")
		(net "TEMP_ALM#_IN_D")
	)
	(segment
		(start 39.243 -178.816)
		(end 39.243 -178.4985)
		(width 0.1397)
		(layer "F.Cu")
		(net "TEMP_ALM#_IN_D")
	)
	(segment
		(start 40.64 -179.197)
		(end 40.87876 -179.43576)
		(width 0.1397)
		(layer "F.Cu")
		(net "TEMP_ALM#_IN_D")
	)
	(segment
		(start 36.6395 -175.514)
		(end 36.957 -175.1965)
		(width 0.1397)
		(layer "F.Cu")
		(net "TEMP_ALM#_IN_D")
	)
	(segment
		(start 38.2778 -175.6918)
		(end 38.075616 -175.489616)
		(width 0.1397)
		(layer "F.Cu")
		(net "TEMP_ALM#_IN_D")
	)
	(segment
		(start 38.075616 -175.489616)
		(end 37.720016 -175.489616)
		(width 0.1397)
		(layer "F.Cu")
		(net "TEMP_ALM#_IN_D")
	)
	(segment
		(start 38.910768 -179.29606)
		(end 38.910768 -179.148232)
		(width 0.1397)
		(layer "F.Cu")
		(net "TEMP_ALM#_IN_D")
	)
	(segment
		(start 39.9415 -179.197)
		(end 40.64 -179.197)
		(width 0.1397)
		(layer "F.Cu")
		(net "TEMP_ALM#_IN_D")
	)
	(segment
		(start 39.243 -178.4985)
		(end 39.9415 -179.197)
		(width 0.1397)
		(layer "F.Cu")
		(net "TEMP_ALM#_IN_D")
	)
	(via
		(at 38.608 -176.704752)
		(size 0.7112)
		(drill 0.3556)
		(layers "F.Cu" "B.Cu")
		(net "TEMP_ALM#_IN_D")
	)
	(via
		(at 38.910768 -179.29606)
		(size 0.5588)
		(drill 0.3048)
		(layers "F.Cu" "B.Cu")
		(net "TEMP_ALM#_IN_D")
	)
	(via
		(at 38.2778 -175.6918)
		(size 0.5588)
		(drill 0.3048)
		(layers "F.Cu" "B.Cu")
		(net "TEMP_ALM#_IN_D")
	)
	(segment
		(start 38.910768 -177.00752)
		(end 38.608 -176.704752)
		(width 0.1397)
		(layer "B.Cu")
		(net "TEMP_ALM#_IN_D")
	)
	(segment
		(start 38.2778 -175.6918)
		(end 38.2778 -176.3268)
		(width 0.1397)
		(layer "B.Cu")
		(net "TEMP_ALM#_IN_D")
	)
	(segment
		(start 38.910768 -179.29606)
		(end 38.910768 -177.00752)
		(width 0.1397)
		(layer "B.Cu")
		(net "TEMP_ALM#_IN_D")
	)
	(segment
		(start 38.2778 -176.3268)
		(end 38.608 -176.657)
		(width 0.1397)
		(layer "B.Cu")
		(net "TEMP_ALM#_IN_D")
	)
	(segment
		(start 38.608 -176.657)
		(end 38.608 -176.704752)
		(width 0.1397)
		(layer "B.Cu")
		(net "TEMP_ALM#_IN_D")
	)
	(segment
		(start 26.289 -245.491)
		(end 26.289 -244.856)
		(width 0.254)
		(layer "F.Cu")
		(net "P3V3_LX_COPPER")
	)
	(segment
		(start 24.003 -243.205)
		(end 23.876 -243.078)
		(width 0.254)
		(layer "F.Cu")
		(net "P3V3_LX_COPPER")
	)
	(segment
		(start 26.289 -247.396)
		(end 26.289 -245.491)
		(width 0.254)
		(layer "F.Cu")
		(net "P3V3_LX_COPPER")
	)
	(segment
		(start 26.289 -244.856)
		(end 24.638 -243.205)
		(width 0.254)
		(layer "F.Cu")
		(net "P3V3_LX_COPPER")
	)
	(segment
		(start 24.638 -243.205)
		(end 24.003 -243.205)
		(width 0.254)
		(layer "F.Cu")
		(net "P3V3_LX_COPPER")
	)
	(via
		(at 24.003 -241.427)
		(size 0.7112)
		(drill 0.3556)
		(layers "F.Cu" "B.Cu")
		(net "P3V3_LX_COPPER")
	)
	(via
		(at 26.289 -245.491)
		(size 0.7112)
		(drill 0.3556)
		(layers "F.Cu" "B.Cu")
		(net "P3V3_LX_COPPER")
	)
	(segment
		(start 18.161 -247.9802)
		(end 19.6596 -247.9802)
		(width 0.508)
		(layer "F.Cu")
		(net "P3V3_IN")
	)
	(segment
		(start 17.9832 -247.8024)
		(end 16.2052 -247.8024)
		(width 0.508)
		(layer "F.Cu")
		(net "P3V3_IN")
	)
	(segment
		(start 14.5034 -247.4214)
		(end 13.081 -247.4214)
		(width 1.016)
		(layer "F.Cu")
		(net "P3V3_IN")
	)
	(segment
		(start 17.9832 -247.8024)
		(end 18.161 -247.9802)
		(width 0.508)
		(layer "F.Cu")
		(net "P3V3_IN")
	)
	(via
		(at 13.081 -247.4214)
		(size 0.7112)
		(drill 0.3556)
		(layers "F.Cu" "B.Cu")
		(net "P3V3_IN")
	)
	(segment
		(start 34.60877 -383.09423)
		(end 34.798 -382.905)
		(width 0.254)
		(layer "F.Cu")
		(net "SENSE-_R4")
	)
	(segment
		(start 41.974008 -409.968446)
		(end 41.974008 -409.777438)
		(width 0.254)
		(layer "F.Cu")
		(net "SENSE-_R4")
	)
	(segment
		(start 44.01058 -413.135318)
		(end 43.97629 -413.135318)
		(width 0.254)
		(layer "F.Cu")
		(net "SENSE-_R4")
	)
	(segment
		(start 34.292032 -383.09423)
		(end 34.60877 -383.09423)
		(width 0.254)
		(layer "F.Cu")
		(net "SENSE-_R4")
	)
	(segment
		(start 43.97629 -413.135318)
		(end 43.942 -413.101028)
		(width 0.254)
		(layer "F.Cu")
		(net "SENSE-_R4")
	)
	(segment
		(start 43.942 -411.936438)
		(end 41.974008 -409.968446)
		(width 0.254)
		(layer "F.Cu")
		(net "SENSE-_R4")
	)
	(segment
		(start 43.942 -413.101028)
		(end 43.942 -411.936438)
		(width 0.254)
		(layer "F.Cu")
		(net "SENSE-_R4")
	)
	(segment
		(start 34.798 -382.905)
		(end 34.798 -381.4445)
		(width 0.254)
		(layer "F.Cu")
		(net "SENSE-_R4")
	)
	(via
		(at 44.01058 -413.135318)
		(size 0.5588)
		(drill 0.3048)
		(layers "F.Cu" "B.Cu")
		(net "SENSE-_R4")
	)
	(via
		(at 35.179 -382.143)
		(size 0.7112)
		(drill 0.3556)
		(layers "F.Cu" "B.Cu")
		(net "SENSE-_R4")
	)
	(via
		(at 34.292032 -383.09423)
		(size 0.5588)
		(drill 0.3048)
		(layers "F.Cu" "B.Cu")
		(net "SENSE-_R4")
	)
	(segment
		(start 34.292032 -383.029968)
		(end 34.292032 -383.09423)
		(width 0.254)
		(layer "B.Cu")
		(net "SENSE-_R4")
	)
	(segment
		(start 34.292032 -383.09423)
		(end 32.500062 -384.8862)
		(width 0.254)
		(layer "B.Cu")
		(net "SENSE-_R4")
	)
	(segment
		(start 22.86 -393.7)
		(end 22.86 -409.800552)
		(width 0.254)
		(layer "B.Cu")
		(net "SENSE-_R4")
	)
	(segment
		(start 43.371262 -412.496)
		(end 44.01058 -413.135318)
		(width 0.254)
		(layer "B.Cu")
		(net "SENSE-_R4")
	)
	(segment
		(start 22.86 -409.800552)
		(end 23.218648 -410.1592)
		(width 0.254)
		(layer "B.Cu")
		(net "SENSE-_R4")
	)
	(segment
		(start 29.280358 -410.1592)
		(end 30.397958 -411.2768)
		(width 0.254)
		(layer "B.Cu")
		(net "SENSE-_R4")
	)
	(segment
		(start 32.500062 -384.8862)
		(end 31.6738 -384.8862)
		(width 0.254)
		(layer "B.Cu")
		(net "SENSE-_R4")
	)
	(segment
		(start 30.397958 -411.2768)
		(end 36.195 -411.2768)
		(width 0.254)
		(layer "B.Cu")
		(net "SENSE-_R4")
	)
	(segment
		(start 23.218648 -410.1592)
		(end 29.280358 -410.1592)
		(width 0.254)
		(layer "B.Cu")
		(net "SENSE-_R4")
	)
	(segment
		(start 31.6738 -384.8862)
		(end 22.86 -393.7)
		(width 0.254)
		(layer "B.Cu")
		(net "SENSE-_R4")
	)
	(segment
		(start 36.195 -411.2768)
		(end 37.4142 -412.496)
		(width 0.254)
		(layer "B.Cu")
		(net "SENSE-_R4")
	)
	(segment
		(start 37.4142 -412.496)
		(end 43.371262 -412.496)
		(width 0.254)
		(layer "B.Cu")
		(net "SENSE-_R4")
	)
	(segment
		(start 35.179 -382.143)
		(end 34.292032 -383.029968)
		(width 0.254)
		(layer "B.Cu")
		(net "SENSE-_R4")
	)
	(segment
		(start 20.701 -410.464)
		(end 20.014438 -409.777438)
		(width 0.254)
		(layer "F.Cu")
		(net "SENSE-_R1")
	)
	(segment
		(start 31.75 -381.4445)
		(end 31.75 -382.651)
		(width 0.254)
		(layer "F.Cu")
		(net "SENSE-_R1")
	)
	(segment
		(start 20.014438 -409.777438)
		(end 20.003008 -409.777438)
		(width 0.254)
		(layer "F.Cu")
		(net "SENSE-_R1")
	)
	(segment
		(start 21.0947 -410.464)
		(end 20.701 -410.464)
		(width 0.254)
		(layer "F.Cu")
		(net "SENSE-_R1")
	)
	(via
		(at 31.75 -382.651)
		(size 0.5588)
		(drill 0.3048)
		(layers "F.Cu" "B.Cu")
		(net "SENSE-_R1")
	)
	(via
		(at 31.75 -381.127)
		(size 0.7112)
		(drill 0.3556)
		(layers "F.Cu" "B.Cu")
		(net "SENSE-_R1")
	)
	(via
		(at 21.0947 -410.464)
		(size 0.5588)
		(drill 0.3048)
		(layers "F.Cu" "B.Cu")
		(net "SENSE-_R1")
	)
	(segment
		(start 21.0947 -392.966956)
		(end 30.851856 -383.2098)
		(width 0.254)
		(layer "B.Cu")
		(net "SENSE-_R1")
	)
	(segment
		(start 31.1912 -383.2098)
		(end 31.75 -382.651)
		(width 0.254)
		(layer "B.Cu")
		(net "SENSE-_R1")
	)
	(segment
		(start 21.0947 -410.464)
		(end 21.0947 -392.966956)
		(width 0.254)
		(layer "B.Cu")
		(net "SENSE-_R1")
	)
	(segment
		(start 31.75 -382.651)
		(end 31.75 -381.127)
		(width 0.254)
		(layer "B.Cu")
		(net "SENSE-_R1")
	)
	(segment
		(start 30.851856 -383.2098)
		(end 31.1912 -383.2098)
		(width 0.254)
		(layer "B.Cu")
		(net "SENSE-_R1")
	)
	(segment
		(start 28.7528 -411.3022)
		(end 28.7528 -410.9212)
		(width 0.254)
		(layer "F.Cu")
		(net "SENSE-_R2")
	)
	(segment
		(start 27.750008 -409.918408)
		(end 27.750008 -409.777438)
		(width 0.254)
		(layer "F.Cu")
		(net "SENSE-_R2")
	)
	(segment
		(start 28.7528 -410.9212)
		(end 27.750008 -409.918408)
		(width 0.254)
		(layer "F.Cu")
		(net "SENSE-_R2")
	)
	(segment
		(start 32.766 -381.4445)
		(end 32.766 -382.650492)
		(width 0.254)
		(layer "F.Cu")
		(net "SENSE-_R2")
	)
	(segment
		(start 32.766 -382.650492)
		(end 32.765746 -382.650746)
		(width 0.254)
		(layer "F.Cu")
		(net "SENSE-_R2")
	)
	(via
		(at 33.02 -381.254)
		(size 0.7112)
		(drill 0.3556)
		(layers "F.Cu" "B.Cu")
		(net "SENSE-_R2")
	)
	(via
		(at 28.7528 -411.3022)
		(size 0.5588)
		(drill 0.3048)
		(layers "F.Cu" "B.Cu")
		(net "SENSE-_R2")
	)
	(via
		(at 32.765746 -382.650746)
		(size 0.5588)
		(drill 0.3048)
		(layers "F.Cu" "B.Cu")
		(net "SENSE-_R2")
	)
	(segment
		(start 33.02 -381.254)
		(end 33.02 -381.508)
		(width 0.254)
		(layer "B.Cu")
		(net "SENSE-_R2")
	)
	(segment
		(start 28.702 -411.353)
		(end 22.733 -411.353)
		(width 0.254)
		(layer "B.Cu")
		(net "SENSE-_R2")
	)
	(segment
		(start 31.647892 -383.7686)
		(end 32.765746 -382.650746)
		(width 0.254)
		(layer "B.Cu")
		(net "SENSE-_R2")
	)
	(segment
		(start 21.653754 -410.273754)
		(end 21.653754 -393.19835)
		(width 0.254)
		(layer "B.Cu")
		(net "SENSE-_R2")
	)
	(segment
		(start 32.765746 -381.762254)
		(end 32.765746 -382.650746)
		(width 0.254)
		(layer "B.Cu")
		(net "SENSE-_R2")
	)
	(segment
		(start 31.083504 -383.7686)
		(end 31.647892 -383.7686)
		(width 0.254)
		(layer "B.Cu")
		(net "SENSE-_R2")
	)
	(segment
		(start 21.653754 -393.19835)
		(end 31.083504 -383.7686)
		(width 0.254)
		(layer "B.Cu")
		(net "SENSE-_R2")
	)
	(segment
		(start 28.7528 -411.3022)
		(end 28.702 -411.353)
		(width 0.254)
		(layer "B.Cu")
		(net "SENSE-_R2")
	)
	(segment
		(start 22.733 -411.353)
		(end 21.653754 -410.273754)
		(width 0.254)
		(layer "B.Cu")
		(net "SENSE-_R2")
	)
	(segment
		(start 33.02 -381.508)
		(end 32.765746 -381.762254)
		(width 0.254)
		(layer "B.Cu")
		(net "SENSE-_R2")
	)
	(segment
		(start 33.782 -381.4445)
		(end 33.782 -382.397)
		(width 0.254)
		(layer "F.Cu")
		(net "SENSE-_R3")
	)
	(segment
		(start 34.989008 -409.893008)
		(end 34.989008 -409.777438)
		(width 0.254)
		(layer "F.Cu")
		(net "SENSE-_R3")
	)
	(segment
		(start 35.8902 -410.7942)
		(end 34.989008 -409.893008)
		(width 0.254)
		(layer "F.Cu")
		(net "SENSE-_R3")
	)
	(segment
		(start 35.8902 -411.8356)
		(end 35.8902 -410.7942)
		(width 0.254)
		(layer "F.Cu")
		(net "SENSE-_R3")
	)
	(segment
		(start 35.941 -411.8864)
		(end 35.8902 -411.8356)
		(width 0.254)
		(layer "F.Cu")
		(net "SENSE-_R3")
	)
	(via
		(at 35.941 -411.8864)
		(size 0.5588)
		(drill 0.3048)
		(layers "F.Cu" "B.Cu")
		(net "SENSE-_R3")
	)
	(via
		(at 34.29 -381.127)
		(size 0.7112)
		(drill 0.3556)
		(layers "F.Cu" "B.Cu")
		(net "SENSE-_R3")
	)
	(via
		(at 33.782 -382.397)
		(size 0.5588)
		(drill 0.3048)
		(layers "F.Cu" "B.Cu")
		(net "SENSE-_R3")
	)
	(segment
		(start 31.315152 -384.3274)
		(end 31.9786 -384.3274)
		(width 0.254)
		(layer "B.Cu")
		(net "SENSE-_R3")
	)
	(segment
		(start 33.782 -382.524)
		(end 33.782 -382.397)
		(width 0.254)
		(layer "B.Cu")
		(net "SENSE-_R3")
	)
	(segment
		(start 29.0068 -410.718)
		(end 22.987 -410.718)
		(width 0.254)
		(layer "B.Cu")
		(net "SENSE-_R3")
	)
	(segment
		(start 22.987 -410.718)
		(end 22.212554 -409.943554)
		(width 0.254)
		(layer "B.Cu")
		(net "SENSE-_R3")
	)
	(segment
		(start 34.29 -381.127)
		(end 34.29 -381.635)
		(width 0.254)
		(layer "B.Cu")
		(net "SENSE-_R3")
	)
	(segment
		(start 34.29 -381.635)
		(end 33.782 -382.143)
		(width 0.254)
		(layer "B.Cu")
		(net "SENSE-_R3")
	)
	(segment
		(start 31.9786 -384.3274)
		(end 33.782 -382.524)
		(width 0.254)
		(layer "B.Cu")
		(net "SENSE-_R3")
	)
	(segment
		(start 22.212554 -393.429998)
		(end 31.315152 -384.3274)
		(width 0.254)
		(layer "B.Cu")
		(net "SENSE-_R3")
	)
	(segment
		(start 33.782 -382.143)
		(end 33.782 -382.397)
		(width 0.254)
		(layer "B.Cu")
		(net "SENSE-_R3")
	)
	(segment
		(start 22.212554 -409.943554)
		(end 22.212554 -393.429998)
		(width 0.254)
		(layer "B.Cu")
		(net "SENSE-_R3")
	)
	(segment
		(start 30.1752 -411.8864)
		(end 29.0068 -410.718)
		(width 0.254)
		(layer "B.Cu")
		(net "SENSE-_R3")
	)
	(segment
		(start 35.941 -411.8864)
		(end 30.1752 -411.8864)
		(width 0.254)
		(layer "B.Cu")
		(net "SENSE-_R3")
	)
	(segment
		(start 43.148504 -412.210504)
		(end 43.148504 -413.080962)
		(width 0.254)
		(layer "F.Cu")
		(net "SENSE+_R4")
	)
	(segment
		(start 41.974008 -411.404562)
		(end 42.342562 -411.404562)
		(width 0.254)
		(layer "F.Cu")
		(net "SENSE+_R4")
	)
	(segment
		(start 27.686 -381.4445)
		(end 27.686 -382.651)
		(width 0.254)
		(layer "F.Cu")
		(net "SENSE+_R4")
	)
	(segment
		(start 42.342562 -411.404562)
		(end 43.148504 -412.210504)
		(width 0.254)
		(layer "F.Cu")
		(net "SENSE+_R4")
	)
	(via
		(at 26.543 -382.524)
		(size 0.7112)
		(drill 0.3556)
		(layers "F.Cu" "B.Cu")
		(net "SENSE+_R4")
	)
	(via
		(at 27.686 -382.651)
		(size 0.5588)
		(drill 0.3048)
		(layers "F.Cu" "B.Cu")
		(net "SENSE+_R4")
	)
	(via
		(at 43.148504 -413.080962)
		(size 0.5588)
		(drill 0.3048)
		(layers "F.Cu" "B.Cu")
		(net "SENSE+_R4")
	)
	(segment
		(start 43.148504 -413.080962)
		(end 42.844466 -413.385)
		(width 0.254)
		(layer "B.Cu")
		(net "SENSE+_R4")
	)
	(segment
		(start 18.8214 -409.926536)
		(end 18.821146 -409.926282)
		(width 0.254)
		(layer "B.Cu")
		(net "SENSE+_R4")
	)
	(segment
		(start 27.686 -382.651)
		(end 27.559 -382.524)
		(width 0.254)
		(layer "B.Cu")
		(net "SENSE+_R4")
	)
	(segment
		(start 18.8214 -392.0236)
		(end 27.686 -383.159)
		(width 0.254)
		(layer "B.Cu")
		(net "SENSE+_R4")
	)
	(segment
		(start 18.8214 -411.515306)
		(end 18.8214 -409.926536)
		(width 0.254)
		(layer "B.Cu")
		(net "SENSE+_R4")
	)
	(segment
		(start 20.691094 -413.385)
		(end 18.8214 -411.515306)
		(width 0.254)
		(layer "B.Cu")
		(net "SENSE+_R4")
	)
	(segment
		(start 27.686 -383.159)
		(end 27.686 -382.651)
		(width 0.254)
		(layer "B.Cu")
		(net "SENSE+_R4")
	)
	(segment
		(start 18.821146 -406.683718)
		(end 18.8214 -406.683464)
		(width 0.254)
		(layer "B.Cu")
		(net "SENSE+_R4")
	)
	(segment
		(start 18.821146 -409.926282)
		(end 18.821146 -406.683718)
		(width 0.254)
		(layer "B.Cu")
		(net "SENSE+_R4")
	)
	(segment
		(start 42.844466 -413.385)
		(end 20.691094 -413.385)
		(width 0.254)
		(layer "B.Cu")
		(net "SENSE+_R4")
	)
	(segment
		(start 18.8214 -406.683464)
		(end 18.8214 -392.0236)
		(width 0.254)
		(layer "B.Cu")
		(net "SENSE+_R4")
	)
	(segment
		(start 27.559 -382.524)
		(end 26.543 -382.524)
		(width 0.254)
		(layer "B.Cu")
		(net "SENSE+_R4")
	)
	(segment
		(start 28.3972 -412.1912)
		(end 27.750008 -411.544008)
		(width 0.254)
		(layer "F.Cu")
		(net "SENSE+_R2")
	)
	(segment
		(start 28.7528 -412.1912)
		(end 28.3972 -412.1912)
		(width 0.254)
		(layer "F.Cu")
		(net "SENSE+_R2")
	)
	(segment
		(start 27.750008 -411.544008)
		(end 27.750008 -411.404562)
		(width 0.254)
		(layer "F.Cu")
		(net "SENSE+_R2")
	)
	(segment
		(start 29.718 -381.4445)
		(end 29.718 -382.651)
		(width 0.254)
		(layer "F.Cu")
		(net "SENSE+_R2")
	)
	(via
		(at 28.7528 -412.1912)
		(size 0.5588)
		(drill 0.3048)
		(layers "F.Cu" "B.Cu")
		(net "SENSE+_R2")
	)
	(via
		(at 29.718 -382.651)
		(size 0.5588)
		(drill 0.3048)
		(layers "F.Cu" "B.Cu")
		(net "SENSE+_R2")
	)
	(via
		(at 29.083 -381.4572)
		(size 0.7112)
		(drill 0.3556)
		(layers "F.Cu" "B.Cu")
		(net "SENSE+_R2")
	)
	(segment
		(start 19.938746 -407.147014)
		(end 19.939 -407.14676)
		(width 0.254)
		(layer "B.Cu")
		(net "SENSE+_R2")
	)
	(segment
		(start 29.718 -382.651)
		(end 29.718 -382.0922)
		(width 0.254)
		(layer "B.Cu")
		(net "SENSE+_R2")
	)
	(segment
		(start 29.718 -382.707896)
		(end 29.718 -382.651)
		(width 0.254)
		(layer "B.Cu")
		(net "SENSE+_R2")
	)
	(segment
		(start 28.7528 -412.1912)
		(end 21.082 -412.1912)
		(width 0.254)
		(layer "B.Cu")
		(net "SENSE+_R2")
	)
	(segment
		(start 19.939 -411.05201)
		(end 19.939 -409.46324)
		(width 0.254)
		(layer "B.Cu")
		(net "SENSE+_R2")
	)
	(segment
		(start 19.938746 -409.462986)
		(end 19.938746 -407.147014)
		(width 0.254)
		(layer "B.Cu")
		(net "SENSE+_R2")
	)
	(segment
		(start 19.939 -392.486896)
		(end 29.718 -382.707896)
		(width 0.254)
		(layer "B.Cu")
		(net "SENSE+_R2")
	)
	(segment
		(start 21.082 -412.1912)
		(end 20.854416 -411.963616)
		(width 0.254)
		(layer "B.Cu")
		(net "SENSE+_R2")
	)
	(segment
		(start 19.939 -407.14676)
		(end 19.939 -392.486896)
		(width 0.254)
		(layer "B.Cu")
		(net "SENSE+_R2")
	)
	(segment
		(start 29.718 -382.0922)
		(end 29.083 -381.4572)
		(width 0.254)
		(layer "B.Cu")
		(net "SENSE+_R2")
	)
	(segment
		(start 20.850606 -411.963616)
		(end 19.939 -411.05201)
		(width 0.254)
		(layer "B.Cu")
		(net "SENSE+_R2")
	)
	(segment
		(start 19.939 -409.46324)
		(end 19.938746 -409.462986)
		(width 0.254)
		(layer "B.Cu")
		(net "SENSE+_R2")
	)
	(segment
		(start 20.854416 -411.963616)
		(end 20.850606 -411.963616)
		(width 0.254)
		(layer "B.Cu")
		(net "SENSE+_R2")
	)
	(segment
		(start 28.702 -381.4445)
		(end 28.702 -382.651)
		(width 0.254)
		(layer "F.Cu")
		(net "SENSE+_R3")
	)
	(segment
		(start 34.989008 -411.899608)
		(end 34.989008 -411.404562)
		(width 0.254)
		(layer "F.Cu")
		(net "SENSE+_R3")
	)
	(segment
		(start 35.8902 -412.75)
		(end 35.8394 -412.75)
		(width 0.254)
		(layer "F.Cu")
		(net "SENSE+_R3")
	)
	(segment
		(start 35.8394 -412.75)
		(end 34.989008 -411.899608)
		(width 0.254)
		(layer "F.Cu")
		(net "SENSE+_R3")
	)
	(via
		(at 28.702 -382.651)
		(size 0.5588)
		(drill 0.3048)
		(layers "F.Cu" "B.Cu")
		(net "SENSE+_R3")
	)
	(via
		(at 27.559 -381.381)
		(size 0.7112)
		(drill 0.3556)
		(layers "F.Cu" "B.Cu")
		(net "SENSE+_R3")
	)
	(via
		(at 35.8902 -412.75)
		(size 0.5588)
		(drill 0.3048)
		(layers "F.Cu" "B.Cu")
		(net "SENSE+_R3")
	)
	(segment
		(start 19.3802 -411.283658)
		(end 19.3802 -409.694888)
		(width 0.254)
		(layer "B.Cu")
		(net "SENSE+_R3")
	)
	(segment
		(start 19.3802 -406.915112)
		(end 19.3802 -392.255248)
		(width 0.254)
		(layer "B.Cu")
		(net "SENSE+_R3")
	)
	(segment
		(start 19.379946 -406.915366)
		(end 19.3802 -406.915112)
		(width 0.254)
		(layer "B.Cu")
		(net "SENSE+_R3")
	)
	(segment
		(start 19.3802 -392.255248)
		(end 28.702 -382.933448)
		(width 0.254)
		(layer "B.Cu")
		(net "SENSE+_R3")
	)
	(segment
		(start 28.702 -382.524)
		(end 28.702 -382.651)
		(width 0.254)
		(layer "B.Cu")
		(net "SENSE+_R3")
	)
	(segment
		(start 35.8902 -412.75)
		(end 20.846542 -412.75)
		(width 0.254)
		(layer "B.Cu")
		(net "SENSE+_R3")
	)
	(segment
		(start 19.379946 -409.694634)
		(end 19.379946 -406.915366)
		(width 0.254)
		(layer "B.Cu")
		(net "SENSE+_R3")
	)
	(segment
		(start 19.3802 -409.694888)
		(end 19.379946 -409.694634)
		(width 0.254)
		(layer "B.Cu")
		(net "SENSE+_R3")
	)
	(segment
		(start 27.559 -381.381)
		(end 28.702 -382.524)
		(width 0.254)
		(layer "B.Cu")
		(net "SENSE+_R3")
	)
	(segment
		(start 28.702 -382.933448)
		(end 28.702 -382.651)
		(width 0.254)
		(layer "B.Cu")
		(net "SENSE+_R3")
	)
	(segment
		(start 20.846542 -412.75)
		(end 19.3802 -411.283658)
		(width 0.254)
		(layer "B.Cu")
		(net "SENSE+_R3")
	)
	(segment
		(start 20.003008 -411.404562)
		(end 21.082 -411.404562)
		(width 0.254)
		(layer "F.Cu")
		(net "SENSE+_R1")
	)
	(segment
		(start 30.734 -381.4445)
		(end 30.734 -382.651)
		(width 0.254)
		(layer "F.Cu")
		(net "SENSE+_R1")
	)
	(via
		(at 30.353 -381.254)
		(size 0.7112)
		(drill 0.3556)
		(layers "F.Cu" "B.Cu")
		(net "SENSE+_R1")
	)
	(via
		(at 21.082 -411.404562)
		(size 0.5588)
		(drill 0.3048)
		(layers "F.Cu" "B.Cu")
		(net "SENSE+_R1")
	)
	(via
		(at 30.734 -382.651)
		(size 0.5588)
		(drill 0.3048)
		(layers "F.Cu" "B.Cu")
		(net "SENSE+_R1")
	)
	(segment
		(start 20.4978 -410.820362)
		(end 20.4978 -392.7602)
		(width 0.254)
		(layer "B.Cu")
		(net "SENSE+_R1")
	)
	(segment
		(start 30.734 -381.889)
		(end 30.353 -381.508)
		(width 0.254)
		(layer "B.Cu")
		(net "SENSE+_R1")
	)
	(segment
		(start 20.4978 -392.7602)
		(end 30.607 -382.651)
		(width 0.254)
		(layer "B.Cu")
		(net "SENSE+_R1")
	)
	(segment
		(start 30.353 -381.508)
		(end 30.353 -381.254)
		(width 0.254)
		(layer "B.Cu")
		(net "SENSE+_R1")
	)
	(segment
		(start 30.607 -382.651)
		(end 30.734 -382.651)
		(width 0.254)
		(layer "B.Cu")
		(net "SENSE+_R1")
	)
	(segment
		(start 30.734 -382.651)
		(end 30.734 -381.889)
		(width 0.254)
		(layer "B.Cu")
		(net "SENSE+_R1")
	)
	(segment
		(start 21.082 -411.404562)
		(end 20.4978 -410.820362)
		(width 0.254)
		(layer "B.Cu")
		(net "SENSE+_R1")
	)
	(segment
		(start 25.146 -247.9675)
		(end 25.146 -245.872)
		(width 0.254)
		(layer "F.Cu")
		(net "P3V3_LX_REV")
	)
	(segment
		(start 25.146 -245.872)
		(end 24.881332 -245.607332)
		(width 0.254)
		(layer "F.Cu")
		(net "P3V3_LX_REV")
	)
	(segment
		(start 24.881332 -245.607332)
		(end 23.876 -244.602)
		(width 0.254)
		(layer "F.Cu")
		(net "P3V3_LX_REV")
	)
	(via
		(at 24.881332 -245.607332)
		(size 0.7112)
		(drill 0.3556)
		(layers "F.Cu" "B.Cu")
		(net "P3V3_LX_REV")
	)
	(segment
		(start 41.529 -180.366416)
		(end 41.529 -178.435)
		(width 0.1397)
		(layer "F.Cu")
		(net "D_LATCH_PRE#")
	)
	(segment
		(start 40.259 -176.4538)
		(end 40.259 -176.53)
		(width 0.1397)
		(layer "F.Cu")
		(net "D_LATCH_PRE#")
	)
	(segment
		(start 41.3639 -178.4985)
		(end 41.4782 -178.3842)
		(width 0.1397)
		(layer "F.Cu")
		(net "D_LATCH_PRE#")
	)
	(segment
		(start 13.6271 -48.6537)
		(end 13.5636 -48.5902)
		(width 0.1397)
		(layer "F.Cu")
		(net "D_LATCH_PRE#")
	)
	(segment
		(start 40.767 -177.008028)
		(end 40.767 -177.546)
		(width 0.1397)
		(layer "F.Cu")
		(net "D_LATCH_PRE#")
	)
	(segment
		(start 41.529 -178.435)
		(end 41.4782 -178.3842)
		(width 0.1397)
		(layer "F.Cu")
		(net "D_LATCH_PRE#")
	)
	(segment
		(start 14.4399 -47.5742)
		(end 14.4399 -48.5902)
		(width 0.1397)
		(layer "F.Cu")
		(net "D_LATCH_PRE#")
	)
	(segment
		(start 41.4782 -178.2572)
		(end 41.4782 -178.3842)
		(width 0.1397)
		(layer "F.Cu")
		(net "D_LATCH_PRE#")
	)
	(segment
		(start 41.021 -175.6918)
		(end 40.259 -176.4538)
		(width 0.1397)
		(layer "F.Cu")
		(net "D_LATCH_PRE#")
	)
	(segment
		(start 14.4399 -48.5902)
		(end 14.3764 -48.6537)
		(width 0.1397)
		(layer "F.Cu")
		(net "D_LATCH_PRE#")
	)
	(segment
		(start 40.767 -177.546)
		(end 41.4782 -178.2572)
		(width 0.1397)
		(layer "F.Cu")
		(net "D_LATCH_PRE#")
	)
	(segment
		(start 40.259 -178.4985)
		(end 41.3639 -178.4985)
		(width 0.1397)
		(layer "F.Cu")
		(net "D_LATCH_PRE#")
	)
	(segment
		(start 14.3764 -48.6537)
		(end 13.6271 -48.6537)
		(width 0.1397)
		(layer "F.Cu")
		(net "D_LATCH_PRE#")
	)
	(segment
		(start 40.51681 -176.78781)
		(end 40.546782 -176.78781)
		(width 0.1397)
		(layer "F.Cu")
		(net "D_LATCH_PRE#")
	)
	(segment
		(start 40.546782 -176.78781)
		(end 40.767 -177.008028)
		(width 0.1397)
		(layer "F.Cu")
		(net "D_LATCH_PRE#")
	)
	(segment
		(start 40.259 -176.53)
		(end 40.51681 -176.78781)
		(width 0.1397)
		(layer "F.Cu")
		(net "D_LATCH_PRE#")
	)
	(via
		(at 41.021 -175.6918)
		(size 0.5588)
		(drill 0.3048)
		(layers "F.Cu" "B.Cu")
		(net "D_LATCH_PRE#")
	)
	(via
		(at 40.259 -176.53)
		(size 0.7112)
		(drill 0.3556)
		(layers "F.Cu" "B.Cu")
		(net "D_LATCH_PRE#")
	)
	(via
		(at 13.5636 -48.5902)
		(size 0.5588)
		(drill 0.3048)
		(layers "F.Cu" "B.Cu")
		(net "D_LATCH_PRE#")
	)
	(segment
		(start 48.2092 -107.061)
		(end 49.3776 -108.2294)
		(width 0.1397)
		(layer "B.Cu")
		(net "D_LATCH_PRE#")
	)
	(segment
		(start 43.1292 -159.4612)
		(end 43.1292 -173.355)
		(width 0.1397)
		(layer "B.Cu")
		(net "D_LATCH_PRE#")
	)
	(segment
		(start 48.8442 -98.7044)
		(end 48.2092 -99.3394)
		(width 0.1397)
		(layer "B.Cu")
		(net "D_LATCH_PRE#")
	)
	(segment
		(start 19.910044 -47.374556)
		(end 21.085556 -47.374556)
		(width 0.1397)
		(layer "B.Cu")
		(net "D_LATCH_PRE#")
	)
	(segment
		(start 41.6052 -65.3288)
		(end 42.901616 -66.625216)
		(width 0.1397)
		(layer "B.Cu")
		(net "D_LATCH_PRE#")
	)
	(segment
		(start 41.18102 -58.3438)
		(end 41.6052 -58.76798)
		(width 0.1397)
		(layer "B.Cu")
		(net "D_LATCH_PRE#")
	)
	(segment
		(start 46.3042 -114.8334)
		(end 46.3042 -134.874)
		(width 0.1397)
		(layer "B.Cu")
		(net "D_LATCH_PRE#")
	)
	(segment
		(start 45.20565 -156.27985)
		(end 45.20565 -157.38475)
		(width 0.1397)
		(layer "B.Cu")
		(net "D_LATCH_PRE#")
	)
	(segment
		(start 48.8442 -69.5198)
		(end 48.8442 -98.7044)
		(width 0.1397)
		(layer "B.Cu")
		(net "D_LATCH_PRE#")
	)
	(segment
		(start 37.4142 -58.3438)
		(end 41.18102 -58.3438)
		(width 0.1397)
		(layer "B.Cu")
		(net "D_LATCH_PRE#")
	)
	(segment
		(start 21.530056 -47.819056)
		(end 29.023056 -47.819056)
		(width 0.1397)
		(layer "B.Cu")
		(net "D_LATCH_PRE#")
	)
	(segment
		(start 42.901616 -66.625216)
		(end 45.949616 -66.625216)
		(width 0.1397)
		(layer "B.Cu")
		(net "D_LATCH_PRE#")
	)
	(segment
		(start 36.3982 -55.1942)
		(end 36.3982 -57.3278)
		(width 0.1397)
		(layer "B.Cu")
		(net "D_LATCH_PRE#")
	)
	(segment
		(start 42.926 -138.2522)
		(end 42.925746 -138.2522)
		(width 0.1397)
		(layer "B.Cu")
		(net "D_LATCH_PRE#")
	)
	(segment
		(start 41.6052 -58.76798)
		(end 41.6052 -65.3288)
		(width 0.1397)
		(layer "B.Cu")
		(net "D_LATCH_PRE#")
	)
	(segment
		(start 46.3042 -134.874)
		(end 42.926 -138.2522)
		(width 0.1397)
		(layer "B.Cu")
		(net "D_LATCH_PRE#")
	)
	(segment
		(start 48.2092 -99.3394)
		(end 48.2092 -107.061)
		(width 0.1397)
		(layer "B.Cu")
		(net "D_LATCH_PRE#")
	)
	(segment
		(start 36.3982 -57.3278)
		(end 37.4142 -58.3438)
		(width 0.1397)
		(layer "B.Cu")
		(net "D_LATCH_PRE#")
	)
	(segment
		(start 45.20565 -157.38475)
		(end 43.1292 -159.4612)
		(width 0.1397)
		(layer "B.Cu")
		(net "D_LATCH_PRE#")
	)
	(segment
		(start 18.49755 -48.78705)
		(end 19.910044 -47.374556)
		(width 0.1397)
		(layer "B.Cu")
		(net "D_LATCH_PRE#")
	)
	(segment
		(start 37.973 -143.204946)
		(end 37.973 -149.0472)
		(width 0.1397)
		(layer "B.Cu")
		(net "D_LATCH_PRE#")
	)
	(segment
		(start 13.5636 -48.5902)
		(end 13.76045 -48.78705)
		(width 0.1397)
		(layer "B.Cu")
		(net "D_LATCH_PRE#")
	)
	(segment
		(start 41.021 -175.4632)
		(end 41.021 -175.6918)
		(width 0.1397)
		(layer "B.Cu")
		(net "D_LATCH_PRE#")
	)
	(segment
		(start 43.1292 -173.355)
		(end 41.021 -175.4632)
		(width 0.1397)
		(layer "B.Cu")
		(net "D_LATCH_PRE#")
	)
	(segment
		(start 47.0408 -114.0968)
		(end 46.3042 -114.8334)
		(width 0.1397)
		(layer "B.Cu")
		(net "D_LATCH_PRE#")
	)
	(segment
		(start 13.76045 -48.78705)
		(end 18.49755 -48.78705)
		(width 0.1397)
		(layer "B.Cu")
		(net "D_LATCH_PRE#")
	)
	(segment
		(start 29.023056 -47.819056)
		(end 36.3982 -55.1942)
		(width 0.1397)
		(layer "B.Cu")
		(net "D_LATCH_PRE#")
	)
	(segment
		(start 37.973 -149.0472)
		(end 45.20565 -156.27985)
		(width 0.1397)
		(layer "B.Cu")
		(net "D_LATCH_PRE#")
	)
	(segment
		(start 21.085556 -47.374556)
		(end 21.530056 -47.819056)
		(width 0.1397)
		(layer "B.Cu")
		(net "D_LATCH_PRE#")
	)
	(segment
		(start 49.3776 -108.2294)
		(end 49.3776 -111.7346)
		(width 0.1397)
		(layer "B.Cu")
		(net "D_LATCH_PRE#")
	)
	(segment
		(start 45.949616 -66.625216)
		(end 48.8442 -69.5198)
		(width 0.1397)
		(layer "B.Cu")
		(net "D_LATCH_PRE#")
	)
	(segment
		(start 42.925746 -138.2522)
		(end 37.973 -143.204946)
		(width 0.1397)
		(layer "B.Cu")
		(net "D_LATCH_PRE#")
	)
	(segment
		(start 47.0408 -114.0714)
		(end 47.0408 -114.0968)
		(width 0.1397)
		(layer "B.Cu")
		(net "D_LATCH_PRE#")
	)
	(segment
		(start 49.3776 -111.7346)
		(end 47.0408 -114.0714)
		(width 0.1397)
		(layer "B.Cu")
		(net "D_LATCH_PRE#")
	)
	(via
		(at 29.845 -184.023)
		(size 0.7112)
		(drill 0.3556)
		(layers "F.Cu" "B.Cu")
		(net "P3V3_AUX_BJT_B")
	)
	(via
		(at 43.942 -175.514)
		(size 0.7112)
		(drill 0.3556)
		(layers "F.Cu" "B.Cu")
		(net "P3V3_AUX")
	)
	(via
		(at 36.068 -178.054)
		(size 0.7112)
		(drill 0.3556)
		(layers "F.Cu" "B.Cu")
		(net "P3V3_AUX")
	)
	(segment
		(start 38.391084 -180.366416)
		(end 37.973 -180.7845)
		(width 0.1397)
		(layer "F.Cu")
		(net "D_LATCH_CLR")
	)
	(segment
		(start 37.973 -180.7845)
		(end 36.83 -180.7845)
		(width 0.1397)
		(layer "F.Cu")
		(net "D_LATCH_CLR")
	)
	(segment
		(start 39.57955 -180.366416)
		(end 38.391084 -180.366416)
		(width 0.1397)
		(layer "F.Cu")
		(net "D_LATCH_CLR")
	)
	(via
		(at 36.83 -180.7845)
		(size 0.7112)
		(drill 0.3556)
		(layers "F.Cu" "B.Cu")
		(net "D_LATCH_CLR")
	)
	(segment
		(start 43.2308 -159.2961)
		(end 43.5356 -159.2961)
		(width 0.1397)
		(layer "F.Cu")
		(net "NCT7904_VSEN_P12V_AUX")
	)
	(segment
		(start 43.2308 -159.2961)
		(end 42.3164 -159.2961)
		(width 0.1397)
		(layer "F.Cu")
		(net "NCT7904_VSEN_P12V_AUX")
	)
	(segment
		(start 44.2595 -158.3055)
		(end 44.2595 -158.5722)
		(width 0.1397)
		(layer "F.Cu")
		(net "NCT7904_VSEN_P12V_AUX")
	)
	(segment
		(start 42.2021 -159.1818)
		(end 42.2021 -158.1658)
		(width 0.1397)
		(layer "F.Cu")
		(net "NCT7904_VSEN_P12V_AUX")
	)
	(segment
		(start 45.470318 -157.483302)
		(end 45.081698 -157.483302)
		(width 0.1397)
		(layer "F.Cu")
		(net "NCT7904_VSEN_P12V_AUX")
	)
	(segment
		(start 42.3164 -159.2961)
		(end 42.2021 -159.1818)
		(width 0.1397)
		(layer "F.Cu")
		(net "NCT7904_VSEN_P12V_AUX")
	)
	(segment
		(start 43.5356 -159.2961)
		(end 44.2595 -158.5722)
		(width 0.1397)
		(layer "F.Cu")
		(net "NCT7904_VSEN_P12V_AUX")
	)
	(segment
		(start 45.081698 -157.483302)
		(end 44.2595 -158.3055)
		(width 0.1397)
		(layer "F.Cu")
		(net "NCT7904_VSEN_P12V_AUX")
	)
	(via
		(at 45.470318 -157.483302)
		(size 0.7112)
		(drill 0.3556)
		(layers "F.Cu" "B.Cu")
		(net "NCT7904_VSEN_P12V_AUX")
	)
	(segment
		(start 25.0952 -210.4009)
		(end 25.096216 -210.399884)
		(width 0.254)
		(layer "F.Cu")
		(net "PWM_OUT_FAN6_NET")
	)
	(segment
		(start 15.546578 -210.4009)
		(end 25.0952 -210.4009)
		(width 0.254)
		(layer "F.Cu")
		(net "PWM_OUT_FAN6_NET")
	)
	(segment
		(start 25.096216 -210.399884)
		(end 26.1366 -210.399884)
		(width 0.254)
		(layer "F.Cu")
		(net "PWM_OUT_FAN6_NET")
	)
	(segment
		(start 17.0815 -16.129)
		(end 16.129 -16.129)
		(width 0.254)
		(layer "F.Cu")
		(net "PWM_OUT_FAN6_NET")
	)
	(segment
		(start 17.0815 -15.75943)
		(end 16.08201 -14.75994)
		(width 0.254)
		(layer "F.Cu")
		(net "PWM_OUT_FAN6_NET")
	)
	(segment
		(start 17.0815 -16.129)
		(end 17.0815 -15.75943)
		(width 0.254)
		(layer "F.Cu")
		(net "PWM_OUT_FAN6_NET")
	)
	(segment
		(start 16.08201 -14.75994)
		(end 4.040124 -14.75994)
		(width 0.254)
		(layer "F.Cu")
		(net "PWM_OUT_FAN6_NET")
	)
	(via
		(at 16.129 -16.129)
		(size 0.5588)
		(drill 0.3048)
		(layers "F.Cu" "B.Cu")
		(net "PWM_OUT_FAN6_NET")
	)
	(via
		(at 17.6784 -168.3258)
		(size 0.7112)
		(drill 0.3556)
		(layers "F.Cu" "B.Cu")
		(net "PWM_OUT_FAN6_NET")
	)
	(via
		(at 15.546578 -210.4009)
		(size 0.5588)
		(drill 0.3048)
		(layers "F.Cu" "B.Cu")
		(net "PWM_OUT_FAN6_NET")
	)
	(segment
		(start 6.6294 -92.68333)
		(end 5.364734 -93.947996)
		(width 0.254)
		(layer "B.Cu")
		(net "PWM_OUT_FAN6_NET")
	)
	(segment
		(start 11.6332 -46.482)
		(end 10.5156 -47.5996)
		(width 0.254)
		(layer "B.Cu")
		(net "PWM_OUT_FAN6_NET")
	)
	(segment
		(start 7.6454 -84.605876)
		(end 6.6294 -85.621876)
		(width 0.254)
		(layer "B.Cu")
		(net "PWM_OUT_FAN6_NET")
	)
	(segment
		(start 10.5156 -47.5996)
		(end 10.5156 -51.9938)
		(width 0.254)
		(layer "B.Cu")
		(net "PWM_OUT_FAN6_NET")
	)
	(segment
		(start 10.922 -136.9314)
		(end 10.922 -146.685)
		(width 0.254)
		(layer "B.Cu")
		(net "PWM_OUT_FAN6_NET")
	)
	(segment
		(start 12.147296 -41.954704)
		(end 11.6332 -42.4688)
		(width 0.254)
		(layer "B.Cu")
		(net "PWM_OUT_FAN6_NET")
	)
	(segment
		(start 8.7884 -62.59068)
		(end 8.7884 -65.1002)
		(width 0.254)
		(layer "B.Cu")
		(net "PWM_OUT_FAN6_NET")
	)
	(segment
		(start 17.15135 -172.01642)
		(end 17.15135 -168.85285)
		(width 0.254)
		(layer "B.Cu")
		(net "PWM_OUT_FAN6_NET")
	)
	(segment
		(start 11.53668 -53.01488)
		(end 11.53668 -59.8424)
		(width 0.254)
		(layer "B.Cu")
		(net "PWM_OUT_FAN6_NET")
	)
	(segment
		(start 7.6454 -66.2432)
		(end 7.6454 -84.605876)
		(width 0.254)
		(layer "B.Cu")
		(net "PWM_OUT_FAN6_NET")
	)
	(segment
		(start 4.890516 -114.535458)
		(end 4.890516 -117.996716)
		(width 0.254)
		(layer "B.Cu")
		(net "PWM_OUT_FAN6_NET")
	)
	(segment
		(start 16.256 -152.019)
		(end 16.256 -155.6766)
		(width 0.254)
		(layer "B.Cu")
		(net "PWM_OUT_FAN6_NET")
	)
	(segment
		(start 15.9385 -210.008978)
		(end 15.9385 -173.22927)
		(width 0.254)
		(layer "B.Cu")
		(net "PWM_OUT_FAN6_NET")
	)
	(segment
		(start 8.7884 -65.1002)
		(end 7.6454 -66.2432)
		(width 0.254)
		(layer "B.Cu")
		(net "PWM_OUT_FAN6_NET")
	)
	(segment
		(start 5.364734 -93.947996)
		(end 5.364734 -114.06124)
		(width 0.254)
		(layer "B.Cu")
		(net "PWM_OUT_FAN6_NET")
	)
	(segment
		(start 7.8232 -133.8326)
		(end 10.922 -136.9314)
		(width 0.254)
		(layer "B.Cu")
		(net "PWM_OUT_FAN6_NET")
	)
	(segment
		(start 10.5156 -51.9938)
		(end 11.53668 -53.01488)
		(width 0.254)
		(layer "B.Cu")
		(net "PWM_OUT_FAN6_NET")
	)
	(segment
		(start 16.256 -155.6766)
		(end 17.6784 -157.099)
		(width 0.254)
		(layer "B.Cu")
		(net "PWM_OUT_FAN6_NET")
	)
	(segment
		(start 10.922 -146.685)
		(end 16.256 -152.019)
		(width 0.254)
		(layer "B.Cu")
		(net "PWM_OUT_FAN6_NET")
	)
	(segment
		(start 17.6784 -157.099)
		(end 17.6784 -168.3258)
		(width 0.254)
		(layer "B.Cu")
		(net "PWM_OUT_FAN6_NET")
	)
	(segment
		(start 6.6294 -85.621876)
		(end 6.6294 -92.68333)
		(width 0.254)
		(layer "B.Cu")
		(net "PWM_OUT_FAN6_NET")
	)
	(segment
		(start 11.6332 -42.4688)
		(end 11.6332 -46.482)
		(width 0.254)
		(layer "B.Cu")
		(net "PWM_OUT_FAN6_NET")
	)
	(segment
		(start 16.129 -16.129)
		(end 16.129 -16.51)
		(width 0.254)
		(layer "B.Cu")
		(net "PWM_OUT_FAN6_NET")
	)
	(segment
		(start 5.364734 -114.06124)
		(end 4.890516 -114.535458)
		(width 0.254)
		(layer "B.Cu")
		(net "PWM_OUT_FAN6_NET")
	)
	(segment
		(start 16.129 -16.51)
		(end 12.147296 -20.491704)
		(width 0.254)
		(layer "B.Cu")
		(net "PWM_OUT_FAN6_NET")
	)
	(segment
		(start 4.890516 -117.996716)
		(end 7.8232 -120.9294)
		(width 0.254)
		(layer "B.Cu")
		(net "PWM_OUT_FAN6_NET")
	)
	(segment
		(start 12.147296 -20.491704)
		(end 12.147296 -41.954704)
		(width 0.254)
		(layer "B.Cu")
		(net "PWM_OUT_FAN6_NET")
	)
	(segment
		(start 17.15135 -168.85285)
		(end 17.6784 -168.3258)
		(width 0.254)
		(layer "B.Cu")
		(net "PWM_OUT_FAN6_NET")
	)
	(segment
		(start 11.53668 -59.8424)
		(end 8.7884 -62.59068)
		(width 0.254)
		(layer "B.Cu")
		(net "PWM_OUT_FAN6_NET")
	)
	(segment
		(start 15.546578 -210.4009)
		(end 15.9385 -210.008978)
		(width 0.254)
		(layer "B.Cu")
		(net "PWM_OUT_FAN6_NET")
	)
	(segment
		(start 7.8232 -120.9294)
		(end 7.8232 -133.8326)
		(width 0.254)
		(layer "B.Cu")
		(net "PWM_OUT_FAN6_NET")
	)
	(segment
		(start 15.9385 -173.22927)
		(end 17.15135 -172.01642)
		(width 0.254)
		(layer "B.Cu")
		(net "PWM_OUT_FAN6_NET")
	)
	(segment
		(start 7.366 -145.7706)
		(end 7.62 -145.5166)
		(width 0.254)
		(layer "F.Cu")
		(net "PWM_OUT_FAN5_NET")
	)
	(segment
		(start 7.6073 -145.066004)
		(end 7.6073 -144.9832)
		(width 0.254)
		(layer "F.Cu")
		(net "PWM_OUT_FAN5_NET")
	)
	(segment
		(start 13.462 -209.6008)
		(end 27.4447 -209.6008)
		(width 0.254)
		(layer "F.Cu")
		(net "PWM_OUT_FAN5_NET")
	)
	(segment
		(start 7.62 -145.5166)
		(end 7.62 -145.078704)
		(width 0.254)
		(layer "F.Cu")
		(net "PWM_OUT_FAN5_NET")
	)
	(segment
		(start 6.858 -145.7452)
		(end 6.8834 -145.7706)
		(width 0.254)
		(layer "F.Cu")
		(net "PWM_OUT_FAN5_NET")
	)
	(segment
		(start 6.8834 -145.7706)
		(end 7.366 -145.7706)
		(width 0.254)
		(layer "F.Cu")
		(net "PWM_OUT_FAN5_NET")
	)
	(segment
		(start 7.62 -145.078704)
		(end 7.6073 -145.066004)
		(width 0.254)
		(layer "F.Cu")
		(net "PWM_OUT_FAN5_NET")
	)
	(segment
		(start 27.4447 -209.6008)
		(end 28.2448 -210.4009)
		(width 0.254)
		(layer "F.Cu")
		(net "PWM_OUT_FAN5_NET")
	)
	(segment
		(start 13.0048 -210.058)
		(end 13.462 -209.6008)
		(width 0.254)
		(layer "F.Cu")
		(net "PWM_OUT_FAN5_NET")
	)
	(via
		(at 9.652 -149.733)
		(size 0.7112)
		(drill 0.3556)
		(layers "F.Cu" "B.Cu")
		(net "PWM_OUT_FAN5_NET")
	)
	(via
		(at 13.0048 -210.058)
		(size 0.5588)
		(drill 0.3048)
		(layers "F.Cu" "B.Cu")
		(net "PWM_OUT_FAN5_NET")
	)
	(via
		(at 6.858 -145.7452)
		(size 0.5588)
		(drill 0.3048)
		(layers "F.Cu" "B.Cu")
		(net "PWM_OUT_FAN5_NET")
	)
	(segment
		(start 6.951726 -145.651474)
		(end 6.858 -145.7452)
		(width 0.254)
		(layer "B.Cu")
		(net "PWM_OUT_FAN5_NET")
	)
	(segment
		(start 6.951726 -144.746726)
		(end 6.951726 -145.651474)
		(width 0.254)
		(layer "B.Cu")
		(net "PWM_OUT_FAN5_NET")
	)
	(segment
		(start 6.858 -146.685)
		(end 6.858 -145.7452)
		(width 0.254)
		(layer "B.Cu")
		(net "PWM_OUT_FAN5_NET")
	)
	(segment
		(start 5.449824 -133.742176)
		(end 4.475734 -134.716266)
		(width 0.254)
		(layer "B.Cu")
		(net "PWM_OUT_FAN5_NET")
	)
	(segment
		(start 9.779 -149.733)
		(end 9.652 -149.733)
		(width 0.254)
		(layer "B.Cu")
		(net "PWM_OUT_FAN5_NET")
	)
	(segment
		(start 4.475734 -142.270734)
		(end 6.951726 -144.746726)
		(width 0.254)
		(layer "B.Cu")
		(net "PWM_OUT_FAN5_NET")
	)
	(segment
		(start 10.107676 -191.568324)
		(end 10.7696 -190.9064)
		(width 0.254)
		(layer "B.Cu")
		(net "PWM_OUT_FAN5_NET")
	)
	(segment
		(start 13.0048 -210.058)
		(end 13.0048 -198.2978)
		(width 0.254)
		(layer "B.Cu")
		(net "PWM_OUT_FAN5_NET")
	)
	(segment
		(start 4.475734 -134.716266)
		(end 4.475734 -142.270734)
		(width 0.254)
		(layer "B.Cu")
		(net "PWM_OUT_FAN5_NET")
	)
	(segment
		(start 10.7696 -178.5874)
		(end 11.8364 -177.5206)
		(width 0.254)
		(layer "B.Cu")
		(net "PWM_OUT_FAN5_NET")
	)
	(segment
		(start 10.107676 -195.400676)
		(end 10.107676 -191.568324)
		(width 0.254)
		(layer "B.Cu")
		(net "PWM_OUT_FAN5_NET")
	)
	(segment
		(start 9.652 -149.479)
		(end 6.858 -146.685)
		(width 0.254)
		(layer "B.Cu")
		(net "PWM_OUT_FAN5_NET")
	)
	(segment
		(start 11.8364 -151.7904)
		(end 9.779 -149.733)
		(width 0.254)
		(layer "B.Cu")
		(net "PWM_OUT_FAN5_NET")
	)
	(segment
		(start 11.8364 -177.5206)
		(end 11.8364 -151.7904)
		(width 0.254)
		(layer "B.Cu")
		(net "PWM_OUT_FAN5_NET")
	)
	(segment
		(start 9.652 -149.733)
		(end 9.652 -149.479)
		(width 0.254)
		(layer "B.Cu")
		(net "PWM_OUT_FAN5_NET")
	)
	(segment
		(start 10.7696 -190.9064)
		(end 10.7696 -178.5874)
		(width 0.254)
		(layer "B.Cu")
		(net "PWM_OUT_FAN5_NET")
	)
	(segment
		(start 5.449824 -126.209806)
		(end 5.449824 -133.742176)
		(width 0.254)
		(layer "B.Cu")
		(net "PWM_OUT_FAN5_NET")
	)
	(segment
		(start 4.040124 -124.800106)
		(end 5.449824 -126.209806)
		(width 0.254)
		(layer "B.Cu")
		(net "PWM_OUT_FAN5_NET")
	)
	(segment
		(start 13.0048 -198.2978)
		(end 10.107676 -195.400676)
		(width 0.254)
		(layer "B.Cu")
		(net "PWM_OUT_FAN5_NET")
	)
	(segment
		(start 4.826 -188.849)
		(end 5.969 -187.706)
		(width 0.254)
		(layer "F.Cu")
		(net "PWM_OUT_FAN4_NET")
	)
	(segment
		(start 13.335 -187.706)
		(end 15.621 -185.42)
		(width 0.254)
		(layer "F.Cu")
		(net "PWM_OUT_FAN4_NET")
	)
	(segment
		(start 4.040124 -190.799974)
		(end 4.826 -190.014098)
		(width 0.254)
		(layer "F.Cu")
		(net "PWM_OUT_FAN4_NET")
	)
	(segment
		(start 17.267174 -183.896)
		(end 21.844 -183.896)
		(width 0.254)
		(layer "F.Cu")
		(net "PWM_OUT_FAN4_NET")
	)
	(segment
		(start 4.826 -190.014098)
		(end 4.826 -188.849)
		(width 0.254)
		(layer "F.Cu")
		(net "PWM_OUT_FAN4_NET")
	)
	(segment
		(start 30.3784 -210.4009)
		(end 30.2641 -210.4009)
		(width 0.254)
		(layer "F.Cu")
		(net "PWM_OUT_FAN4_NET")
	)
	(segment
		(start 16.5735 -185.42)
		(end 16.637 -185.3565)
		(width 0.254)
		(layer "F.Cu")
		(net "PWM_OUT_FAN4_NET")
	)
	(segment
		(start 5.969 -187.706)
		(end 13.335 -187.706)
		(width 0.254)
		(layer "F.Cu")
		(net "PWM_OUT_FAN4_NET")
	)
	(segment
		(start 21.844 -183.896)
		(end 21.971 -183.769)
		(width 0.254)
		(layer "F.Cu")
		(net "PWM_OUT_FAN4_NET")
	)
	(segment
		(start 16.637 -184.526174)
		(end 17.267174 -183.896)
		(width 0.254)
		(layer "F.Cu")
		(net "PWM_OUT_FAN4_NET")
	)
	(segment
		(start 16.637 -185.3565)
		(end 16.637 -184.526174)
		(width 0.254)
		(layer "F.Cu")
		(net "PWM_OUT_FAN4_NET")
	)
	(segment
		(start 30.2641 -210.4009)
		(end 29.1846 -209.3214)
		(width 0.254)
		(layer "F.Cu")
		(net "PWM_OUT_FAN4_NET")
	)
	(segment
		(start 15.621 -185.42)
		(end 16.5735 -185.42)
		(width 0.254)
		(layer "F.Cu")
		(net "PWM_OUT_FAN4_NET")
	)
	(via
		(at 26.863802 -206.822802)
		(size 0.7112)
		(drill 0.3556)
		(layers "F.Cu" "B.Cu")
		(net "PWM_OUT_FAN4_NET")
	)
	(via
		(at 21.971 -183.769)
		(size 0.5588)
		(drill 0.3048)
		(layers "F.Cu" "B.Cu")
		(net "PWM_OUT_FAN4_NET")
	)
	(via
		(at 29.1846 -209.3214)
		(size 0.5588)
		(drill 0.3048)
		(layers "F.Cu" "B.Cu")
		(net "PWM_OUT_FAN4_NET")
	)
	(segment
		(start 29.1846 -209.1436)
		(end 26.863802 -206.822802)
		(width 0.254)
		(layer "B.Cu")
		(net "PWM_OUT_FAN4_NET")
	)
	(segment
		(start 29.1846 -209.3214)
		(end 29.1846 -209.1436)
		(width 0.254)
		(layer "B.Cu")
		(net "PWM_OUT_FAN4_NET")
	)
	(segment
		(start 21.971 -183.769)
		(end 21.971 -201.93)
		(width 0.254)
		(layer "B.Cu")
		(net "PWM_OUT_FAN4_NET")
	)
	(segment
		(start 21.971 -201.93)
		(end 26.863802 -206.822802)
		(width 0.254)
		(layer "B.Cu")
		(net "PWM_OUT_FAN4_NET")
	)
	(segment
		(start 4.040124 -304.120042)
		(end 4.796282 -304.120042)
		(width 0.254)
		(layer "F.Cu")
		(net "PWM_OUT_FAN3_NET")
	)
	(segment
		(start 29.2354 -224.7519)
		(end 29.2354 -224.79)
		(width 0.254)
		(layer "F.Cu")
		(net "PWM_OUT_FAN3_NET")
	)
	(segment
		(start 17.5133 -258.445)
		(end 18.3769 -259.3086)
		(width 0.254)
		(layer "F.Cu")
		(net "PWM_OUT_FAN3_NET")
	)
	(segment
		(start 11.80465 -259.72135)
		(end 12.954 -258.572)
		(width 0.254)
		(layer "F.Cu")
		(net "PWM_OUT_FAN3_NET")
	)
	(segment
		(start 12.954 -258.572)
		(end 13.081 -258.445)
		(width 0.254)
		(layer "F.Cu")
		(net "PWM_OUT_FAN3_NET")
	)
	(segment
		(start 13.081 -258.445)
		(end 17.5133 -258.445)
		(width 0.254)
		(layer "F.Cu")
		(net "PWM_OUT_FAN3_NET")
	)
	(segment
		(start 11.80465 -297.111674)
		(end 11.80465 -259.72135)
		(width 0.254)
		(layer "F.Cu")
		(net "PWM_OUT_FAN3_NET")
	)
	(segment
		(start 17.2212 -225.9076)
		(end 17.0688 -225.7552)
		(width 0.254)
		(layer "F.Cu")
		(net "PWM_OUT_FAN3_NET")
	)
	(segment
		(start 30.3022 -224.7519)
		(end 29.2354 -224.7519)
		(width 0.254)
		(layer "F.Cu")
		(net "PWM_OUT_FAN3_NET")
	)
	(segment
		(start 4.796282 -304.120042)
		(end 11.80465 -297.111674)
		(width 0.254)
		(layer "F.Cu")
		(net "PWM_OUT_FAN3_NET")
	)
	(segment
		(start 29.2354 -224.79)
		(end 28.1178 -225.9076)
		(width 0.254)
		(layer "F.Cu")
		(net "PWM_OUT_FAN3_NET")
	)
	(segment
		(start 28.1178 -225.9076)
		(end 17.2212 -225.9076)
		(width 0.254)
		(layer "F.Cu")
		(net "PWM_OUT_FAN3_NET")
	)
	(via
		(at 17.0688 -225.7552)
		(size 0.5588)
		(drill 0.3048)
		(layers "F.Cu" "B.Cu")
		(net "PWM_OUT_FAN3_NET")
	)
	(via
		(at 12.954 -258.572)
		(size 0.5588)
		(drill 0.3048)
		(layers "F.Cu" "B.Cu")
		(net "PWM_OUT_FAN3_NET")
	)
	(via
		(at 14.859 -231.775)
		(size 0.7112)
		(drill 0.3556)
		(layers "F.Cu" "B.Cu")
		(net "PWM_OUT_FAN3_NET")
	)
	(segment
		(start 12.954 -258.572)
		(end 12.96035 -258.56565)
		(width 0.254)
		(layer "B.Cu")
		(net "PWM_OUT_FAN3_NET")
	)
	(segment
		(start 12.96035 -258.56565)
		(end 12.96035 -234.68965)
		(width 0.254)
		(layer "B.Cu")
		(net "PWM_OUT_FAN3_NET")
	)
	(segment
		(start 17.0688 -228.1682)
		(end 17.0688 -225.7552)
		(width 0.254)
		(layer "B.Cu")
		(net "PWM_OUT_FAN3_NET")
	)
	(segment
		(start 12.96035 -234.68965)
		(end 14.859 -232.791)
		(width 0.254)
		(layer "B.Cu")
		(net "PWM_OUT_FAN3_NET")
	)
	(segment
		(start 14.859 -230.378)
		(end 17.0688 -228.1682)
		(width 0.254)
		(layer "B.Cu")
		(net "PWM_OUT_FAN3_NET")
	)
	(segment
		(start 14.859 -231.775)
		(end 14.859 -230.378)
		(width 0.254)
		(layer "B.Cu")
		(net "PWM_OUT_FAN3_NET")
	)
	(segment
		(start 14.859 -232.791)
		(end 14.859 -231.775)
		(width 0.254)
		(layer "B.Cu")
		(net "PWM_OUT_FAN3_NET")
	)
	(segment
		(start 27.1272 -224.7519)
		(end 26.5684 -225.3107)
		(width 0.254)
		(layer "F.Cu")
		(net "PWM_OUT_FAN2_NET")
	)
	(segment
		(start 17.484852 -225.3107)
		(end 17.014952 -224.8408)
		(width 0.254)
		(layer "F.Cu")
		(net "PWM_OUT_FAN2_NET")
	)
	(segment
		(start 26.5684 -225.3107)
		(end 17.484852 -225.3107)
		(width 0.254)
		(layer "F.Cu")
		(net "PWM_OUT_FAN2_NET")
	)
	(segment
		(start 17.014952 -224.8408)
		(end 15.6464 -224.8408)
		(width 0.254)
		(layer "F.Cu")
		(net "PWM_OUT_FAN2_NET")
	)
	(segment
		(start 17.4625 -299.4025)
		(end 17.4752 -299.4152)
		(width 0.254)
		(layer "F.Cu")
		(net "PWM_OUT_FAN2_NET")
	)
	(segment
		(start 17.4625 -298.4754)
		(end 17.4625 -299.4025)
		(width 0.254)
		(layer "F.Cu")
		(net "PWM_OUT_FAN2_NET")
	)
	(segment
		(start 28.1686 -224.7519)
		(end 27.1272 -224.7519)
		(width 0.254)
		(layer "F.Cu")
		(net "PWM_OUT_FAN2_NET")
	)
	(via
		(at 15.4686 -226.822)
		(size 0.7112)
		(drill 0.3556)
		(layers "F.Cu" "B.Cu")
		(net "PWM_OUT_FAN2_NET")
	)
	(via
		(at 15.6464 -224.8408)
		(size 0.5588)
		(drill 0.3048)
		(layers "F.Cu" "B.Cu")
		(net "PWM_OUT_FAN2_NET")
	)
	(via
		(at 17.4752 -299.4152)
		(size 0.5588)
		(drill 0.3048)
		(layers "F.Cu" "B.Cu")
		(net "PWM_OUT_FAN2_NET")
	)
	(segment
		(start 17.3736 -290.8046)
		(end 17.3736 -296.7228)
		(width 0.254)
		(layer "B.Cu")
		(net "PWM_OUT_FAN2_NET")
	)
	(segment
		(start 17.4752 -336.75447)
		(end 17.4752 -299.4152)
		(width 0.254)
		(layer "B.Cu")
		(net "PWM_OUT_FAN2_NET")
	)
	(segment
		(start 15.6464 -226.6442)
		(end 15.6464 -224.8408)
		(width 0.254)
		(layer "B.Cu")
		(net "PWM_OUT_FAN2_NET")
	)
	(segment
		(start 15.4686 -226.822)
		(end 15.6464 -226.6442)
		(width 0.254)
		(layer "B.Cu")
		(net "PWM_OUT_FAN2_NET")
	)
	(segment
		(start 15.4686 -227.965)
		(end 11.8364 -231.5972)
		(width 0.254)
		(layer "B.Cu")
		(net "PWM_OUT_FAN2_NET")
	)
	(segment
		(start 11.8364 -285.2674)
		(end 17.3736 -290.8046)
		(width 0.254)
		(layer "B.Cu")
		(net "PWM_OUT_FAN2_NET")
	)
	(segment
		(start 3.027934 -351.201736)
		(end 17.4752 -336.75447)
		(width 0.254)
		(layer "B.Cu")
		(net "PWM_OUT_FAN2_NET")
	)
	(segment
		(start 4.040124 -370.11991)
		(end 3.027934 -369.10772)
		(width 0.254)
		(layer "B.Cu")
		(net "PWM_OUT_FAN2_NET")
	)
	(segment
		(start 17.3736 -296.7228)
		(end 17.0815 -297.0149)
		(width 0.254)
		(layer "B.Cu")
		(net "PWM_OUT_FAN2_NET")
	)
	(segment
		(start 17.0815 -297.0149)
		(end 17.0815 -299.0215)
		(width 0.254)
		(layer "B.Cu")
		(net "PWM_OUT_FAN2_NET")
	)
	(segment
		(start 15.4686 -226.822)
		(end 15.4686 -227.965)
		(width 0.254)
		(layer "B.Cu")
		(net "PWM_OUT_FAN2_NET")
	)
	(segment
		(start 3.027934 -369.10772)
		(end 3.027934 -351.201736)
		(width 0.254)
		(layer "B.Cu")
		(net "PWM_OUT_FAN2_NET")
	)
	(segment
		(start 17.0815 -299.0215)
		(end 17.4752 -299.4152)
		(width 0.254)
		(layer "B.Cu")
		(net "PWM_OUT_FAN2_NET")
	)
	(segment
		(start 11.8364 -231.5972)
		(end 11.8364 -285.2674)
		(width 0.254)
		(layer "B.Cu")
		(net "PWM_OUT_FAN2_NET")
	)
	(segment
		(start 14.23035 -459.51775)
		(end 9.958324 -455.245724)
		(width 0.254)
		(layer "F.Cu")
		(net "PWM_OUT_FAN1_NET")
	)
	(segment
		(start 9.951466 -455.245724)
		(end 9.805924 -455.245724)
		(width 0.254)
		(layer "F.Cu")
		(net "PWM_OUT_FAN1_NET")
	)
	(segment
		(start 26.0604 -224.7519)
		(end 17.7165 -224.7519)
		(width 0.254)
		(layer "F.Cu")
		(net "PWM_OUT_FAN1_NET")
	)
	(segment
		(start 17.1704 -224.2058)
		(end 16.4084 -224.2058)
		(width 0.254)
		(layer "F.Cu")
		(net "PWM_OUT_FAN1_NET")
	)
	(segment
		(start 17.7165 -224.7519)
		(end 17.1704 -224.2058)
		(width 0.254)
		(layer "F.Cu")
		(net "PWM_OUT_FAN1_NET")
	)
	(segment
		(start 9.958324 -455.245724)
		(end 9.951466 -455.245724)
		(width 0.254)
		(layer "F.Cu")
		(net "PWM_OUT_FAN1_NET")
	)
	(segment
		(start 8.8773 -454.3171)
		(end 8.8773 -454.2028)
		(width 0.254)
		(layer "F.Cu")
		(net "PWM_OUT_FAN1_NET")
	)
	(segment
		(start 9.805924 -455.245724)
		(end 8.8773 -454.3171)
		(width 0.254)
		(layer "F.Cu")
		(net "PWM_OUT_FAN1_NET")
	)
	(segment
		(start 7.646924 -480.160076)
		(end 14.23035 -473.57665)
		(width 0.254)
		(layer "F.Cu")
		(net "PWM_OUT_FAN1_NET")
	)
	(segment
		(start 14.23035 -473.57665)
		(end 14.23035 -459.51775)
		(width 0.254)
		(layer "F.Cu")
		(net "PWM_OUT_FAN1_NET")
	)
	(segment
		(start 4.040124 -480.160076)
		(end 7.646924 -480.160076)
		(width 0.254)
		(layer "F.Cu")
		(net "PWM_OUT_FAN1_NET")
	)
	(via
		(at 9.951466 -455.245724)
		(size 0.7112)
		(drill 0.4064)
		(layers "F.Cu" "B.Cu")
		(net "PWM_OUT_FAN1_NET")
	)
	(via
		(at 14.459458 -287.026858)
		(size 0.7112)
		(drill 0.3556)
		(layers "F.Cu" "B.Cu")
		(net "PWM_OUT_FAN1_NET")
	)
	(via
		(at 16.4084 -224.2058)
		(size 0.5588)
		(drill 0.3048)
		(layers "F.Cu" "B.Cu")
		(net "PWM_OUT_FAN1_NET")
	)
	(segment
		(start 4.216654 -417.24453)
		(end 4.216654 -449.510912)
		(width 0.254)
		(layer "B.Cu")
		(net "PWM_OUT_FAN1_NET")
	)
	(segment
		(start 19.116802 -337.803998)
		(end 4.475734 -352.445066)
		(width 0.254)
		(layer "B.Cu")
		(net "PWM_OUT_FAN1_NET")
	)
	(segment
		(start 12.3952 -231.9528)
		(end 16.4084 -227.9396)
		(width 0.254)
		(layer "B.Cu")
		(net "PWM_OUT_FAN1_NET")
	)
	(segment
		(start 16.4084 -227.9396)
		(end 16.4084 -224.2058)
		(width 0.254)
		(layer "B.Cu")
		(net "PWM_OUT_FAN1_NET")
	)
	(segment
		(start 14.459458 -287.026858)
		(end 12.3952 -284.9626)
		(width 0.254)
		(layer "B.Cu")
		(net "PWM_OUT_FAN1_NET")
	)
	(segment
		(start 5.449824 -377.69546)
		(end 3.586734 -379.55855)
		(width 0.254)
		(layer "B.Cu")
		(net "PWM_OUT_FAN1_NET")
	)
	(segment
		(start 18.3642 -290.9316)
		(end 18.3642 -293.3446)
		(width 0.254)
		(layer "B.Cu")
		(net "PWM_OUT_FAN1_NET")
	)
	(segment
		(start 5.449824 -364.732824)
		(end 5.449824 -377.69546)
		(width 0.254)
		(layer "B.Cu")
		(net "PWM_OUT_FAN1_NET")
	)
	(segment
		(start 14.459458 -287.026858)
		(end 18.3642 -290.9316)
		(width 0.254)
		(layer "B.Cu")
		(net "PWM_OUT_FAN1_NET")
	)
	(segment
		(start 3.586734 -379.55855)
		(end 3.586734 -416.61461)
		(width 0.254)
		(layer "B.Cu")
		(net "PWM_OUT_FAN1_NET")
	)
	(segment
		(start 12.3952 -284.9626)
		(end 12.3952 -231.9528)
		(width 0.254)
		(layer "B.Cu")
		(net "PWM_OUT_FAN1_NET")
	)
	(segment
		(start 3.586734 -416.61461)
		(end 4.216654 -417.24453)
		(width 0.254)
		(layer "B.Cu")
		(net "PWM_OUT_FAN1_NET")
	)
	(segment
		(start 4.216654 -449.510912)
		(end 9.951466 -455.245724)
		(width 0.254)
		(layer "B.Cu")
		(net "PWM_OUT_FAN1_NET")
	)
	(segment
		(start 18.3642 -293.3446)
		(end 19.116802 -294.097202)
		(width 0.254)
		(layer "B.Cu")
		(net "PWM_OUT_FAN1_NET")
	)
	(segment
		(start 4.475734 -352.445066)
		(end 4.475734 -363.758734)
		(width 0.254)
		(layer "B.Cu")
		(net "PWM_OUT_FAN1_NET")
	)
	(segment
		(start 4.475734 -363.758734)
		(end 5.449824 -364.732824)
		(width 0.254)
		(layer "B.Cu")
		(net "PWM_OUT_FAN1_NET")
	)
	(segment
		(start 19.116802 -294.097202)
		(end 19.116802 -337.803998)
		(width 0.254)
		(layer "B.Cu")
		(net "PWM_OUT_FAN1_NET")
	)
	(segment
		(start 26.25852 -215.75268)
		(end 26.025348 -215.985852)
		(width 0.254)
		(layer "F.Cu")
		(net "PWM_OUT_FAN6")
	)
	(segment
		(start 26.25852 -214.961216)
		(end 26.25852 -215.75268)
		(width 0.254)
		(layer "F.Cu")
		(net "PWM_OUT_FAN6")
	)
	(segment
		(start 26.25852 -212.93328)
		(end 26.25852 -214.961216)
		(width 0.254)
		(layer "F.Cu")
		(net "PWM_OUT_FAN6")
	)
	(segment
		(start 26.2636 -212.9282)
		(end 26.25852 -212.93328)
		(width 0.254)
		(layer "F.Cu")
		(net "PWM_OUT_FAN6")
	)
	(segment
		(start 26.2636 -211.415884)
		(end 26.2636 -212.9282)
		(width 0.254)
		(layer "F.Cu")
		(net "PWM_OUT_FAN6")
	)
	(segment
		(start 24.901652 -215.985852)
		(end 23.3172 -214.4014)
		(width 0.254)
		(layer "F.Cu")
		(net "PWM_OUT_FAN6")
	)
	(segment
		(start 26.1366 -211.288884)
		(end 26.2636 -211.415884)
		(width 0.254)
		(layer "F.Cu")
		(net "PWM_OUT_FAN6")
	)
	(segment
		(start 26.025348 -215.985852)
		(end 24.901652 -215.985852)
		(width 0.254)
		(layer "F.Cu")
		(net "PWM_OUT_FAN6")
	)
	(segment
		(start 23.3172 -214.4014)
		(end 22.211284 -214.4014)
		(width 0.254)
		(layer "F.Cu")
		(net "PWM_OUT_FAN6")
	)
	(via
		(at 26.2636 -212.9282)
		(size 0.7112)
		(drill 0.3556)
		(layers "F.Cu" "B.Cu")
		(net "PWM_OUT_FAN6")
	)
	(segment
		(start 27.559 -214.961216)
		(end 27.559 -213.80958)
		(width 0.254)
		(layer "F.Cu")
		(net "PWM_OUT_FAN5")
	)
	(segment
		(start 24.393652 -216.544652)
		(end 26.990548 -216.544652)
		(width 0.254)
		(layer "F.Cu")
		(net "PWM_OUT_FAN5")
	)
	(segment
		(start 27.559508 -213.266528)
		(end 27.559508 -211.967572)
		(width 0.254)
		(layer "F.Cu")
		(net "PWM_OUT_FAN5")
	)
	(segment
		(start 23.4696 -215.6206)
		(end 24.393652 -216.544652)
		(width 0.254)
		(layer "F.Cu")
		(net "PWM_OUT_FAN5")
	)
	(segment
		(start 28.09748 -211.4296)
		(end 28.1051 -211.4296)
		(width 0.254)
		(layer "F.Cu")
		(net "PWM_OUT_FAN5")
	)
	(segment
		(start 27.559 -213.80958)
		(end 27.560016 -213.808564)
		(width 0.254)
		(layer "F.Cu")
		(net "PWM_OUT_FAN5")
	)
	(segment
		(start 27.559508 -211.967572)
		(end 28.09748 -211.4296)
		(width 0.254)
		(layer "F.Cu")
		(net "PWM_OUT_FAN5")
	)
	(segment
		(start 23.368 -215.519)
		(end 23.4696 -215.6206)
		(width 0.254)
		(layer "F.Cu")
		(net "PWM_OUT_FAN5")
	)
	(segment
		(start 27.559 -215.9762)
		(end 27.559 -214.961216)
		(width 0.254)
		(layer "F.Cu")
		(net "PWM_OUT_FAN5")
	)
	(segment
		(start 27.560016 -213.808564)
		(end 27.560016 -213.267036)
		(width 0.254)
		(layer "F.Cu")
		(net "PWM_OUT_FAN5")
	)
	(segment
		(start 26.990548 -216.544652)
		(end 27.559 -215.9762)
		(width 0.254)
		(layer "F.Cu")
		(net "PWM_OUT_FAN5")
	)
	(segment
		(start 28.1051 -211.4296)
		(end 28.2448 -211.2899)
		(width 0.254)
		(layer "F.Cu")
		(net "PWM_OUT_FAN5")
	)
	(segment
		(start 27.560016 -213.267036)
		(end 27.559508 -213.266528)
		(width 0.254)
		(layer "F.Cu")
		(net "PWM_OUT_FAN5")
	)
	(segment
		(start 22.211284 -215.519)
		(end 23.368 -215.519)
		(width 0.254)
		(layer "F.Cu")
		(net "PWM_OUT_FAN5")
	)
	(via
		(at 23.4696 -215.6206)
		(size 0.7112)
		(drill 0.3556)
		(layers "F.Cu" "B.Cu")
		(net "PWM_OUT_FAN5")
	)
	(segment
		(start 22.2123 -217.7288)
		(end 23.3172 -217.7288)
		(width 0.254)
		(layer "F.Cu")
		(net "PWM_OUT_FAN3")
	)
	(segment
		(start 23.840948 -217.662252)
		(end 23.5458 -217.9574)
		(width 0.254)
		(layer "F.Cu")
		(net "PWM_OUT_FAN3")
	)
	(segment
		(start 28.381452 -217.662252)
		(end 23.840948 -217.662252)
		(width 0.254)
		(layer "F.Cu")
		(net "PWM_OUT_FAN3")
	)
	(segment
		(start 29.50845 -218.78925)
		(end 28.381452 -217.662252)
		(width 0.254)
		(layer "F.Cu")
		(net "PWM_OUT_FAN3")
	)
	(segment
		(start 29.50845 -220.600016)
		(end 29.50845 -218.78925)
		(width 0.254)
		(layer "F.Cu")
		(net "PWM_OUT_FAN3")
	)
	(segment
		(start 23.3172 -217.7288)
		(end 23.5458 -217.9574)
		(width 0.254)
		(layer "F.Cu")
		(net "PWM_OUT_FAN3")
	)
	(segment
		(start 30.3022 -223.8629)
		(end 29.50845 -223.06915)
		(width 0.254)
		(layer "F.Cu")
		(net "PWM_OUT_FAN3")
	)
	(segment
		(start 29.50845 -223.06915)
		(end 29.50845 -220.600016)
		(width 0.254)
		(layer "F.Cu")
		(net "PWM_OUT_FAN3")
	)
	(via
		(at 23.5458 -217.9574)
		(size 0.7112)
		(drill 0.3556)
		(layers "F.Cu" "B.Cu")
		(net "PWM_OUT_FAN3")
	)
	(segment
		(start 23.911052 -217.103452)
		(end 28.285948 -217.103452)
		(width 0.254)
		(layer "F.Cu")
		(net "PWM_OUT_FAN4")
	)
	(segment
		(start 28.8544 -216.535)
		(end 28.8544 -216.4842)
		(width 0.254)
		(layer "F.Cu")
		(net "PWM_OUT_FAN4")
	)
	(segment
		(start 29.6672 -212.598)
		(end 30.3022 -212.598)
		(width 0.254)
		(layer "F.Cu")
		(net "PWM_OUT_FAN4")
	)
	(segment
		(start 30.3784 -212.5218)
		(end 30.3784 -211.2899)
		(width 0.254)
		(layer "F.Cu")
		(net "PWM_OUT_FAN4")
	)
	(segment
		(start 28.285948 -217.103452)
		(end 28.8544 -216.535)
		(width 0.254)
		(layer "F.Cu")
		(net "PWM_OUT_FAN4")
	)
	(segment
		(start 28.85948 -216.47912)
		(end 28.85948 -214.961216)
		(width 0.254)
		(layer "F.Cu")
		(net "PWM_OUT_FAN4")
	)
	(segment
		(start 22.211284 -216.6366)
		(end 23.4442 -216.6366)
		(width 0.254)
		(layer "F.Cu")
		(net "PWM_OUT_FAN4")
	)
	(segment
		(start 23.4442 -216.6366)
		(end 23.911052 -217.103452)
		(width 0.254)
		(layer "F.Cu")
		(net "PWM_OUT_FAN4")
	)
	(segment
		(start 28.8544 -216.4842)
		(end 28.85948 -216.47912)
		(width 0.254)
		(layer "F.Cu")
		(net "PWM_OUT_FAN4")
	)
	(segment
		(start 30.3022 -212.598)
		(end 30.3784 -212.5218)
		(width 0.254)
		(layer "F.Cu")
		(net "PWM_OUT_FAN4")
	)
	(segment
		(start 28.85948 -213.40572)
		(end 29.6672 -212.598)
		(width 0.254)
		(layer "F.Cu")
		(net "PWM_OUT_FAN4")
	)
	(segment
		(start 28.85948 -214.961216)
		(end 28.85948 -213.40572)
		(width 0.254)
		(layer "F.Cu")
		(net "PWM_OUT_FAN4")
	)
	(via
		(at 30.3022 -212.598)
		(size 0.7112)
		(drill 0.3556)
		(layers "F.Cu" "B.Cu")
		(net "PWM_OUT_FAN4")
	)
	(segment
		(start 24.323548 -218.221052)
		(end 23.8506 -218.694)
		(width 0.254)
		(layer "F.Cu")
		(net "PWM_OUT_FAN2")
	)
	(segment
		(start 22.3393 -218.694)
		(end 22.2123 -218.821)
		(width 0.254)
		(layer "F.Cu")
		(net "PWM_OUT_FAN2")
	)
	(segment
		(start 28.20924 -222.69196)
		(end 28.2194 -222.6818)
		(width 0.254)
		(layer "F.Cu")
		(net "PWM_OUT_FAN2")
	)
	(segment
		(start 28.20924 -219.255594)
		(end 27.174698 -218.221052)
		(width 0.254)
		(layer "F.Cu")
		(net "PWM_OUT_FAN2")
	)
	(segment
		(start 28.20924 -223.82226)
		(end 28.20924 -222.69196)
		(width 0.254)
		(layer "F.Cu")
		(net "PWM_OUT_FAN2")
	)
	(segment
		(start 23.8506 -218.694)
		(end 22.3393 -218.694)
		(width 0.254)
		(layer "F.Cu")
		(net "PWM_OUT_FAN2")
	)
	(segment
		(start 28.2194 -222.6818)
		(end 28.20924 -222.67164)
		(width 0.254)
		(layer "F.Cu")
		(net "PWM_OUT_FAN2")
	)
	(segment
		(start 28.20924 -220.600016)
		(end 28.20924 -219.255594)
		(width 0.254)
		(layer "F.Cu")
		(net "PWM_OUT_FAN2")
	)
	(segment
		(start 27.174698 -218.221052)
		(end 24.323548 -218.221052)
		(width 0.254)
		(layer "F.Cu")
		(net "PWM_OUT_FAN2")
	)
	(segment
		(start 28.20924 -222.67164)
		(end 28.20924 -220.600016)
		(width 0.254)
		(layer "F.Cu")
		(net "PWM_OUT_FAN2")
	)
	(segment
		(start 28.1686 -223.8629)
		(end 28.20924 -223.82226)
		(width 0.254)
		(layer "F.Cu")
		(net "PWM_OUT_FAN2")
	)
	(via
		(at 28.2194 -222.6818)
		(size 0.7112)
		(drill 0.3556)
		(layers "F.Cu" "B.Cu")
		(net "PWM_OUT_FAN2")
	)
	(segment
		(start 26.30551 -223.61779)
		(end 26.30551 -222.62211)
		(width 0.254)
		(layer "F.Cu")
		(net "PWM_OUT_FAN1")
	)
	(segment
		(start 26.20518 -218.779852)
		(end 24.577548 -218.779852)
		(width 0.254)
		(layer "F.Cu")
		(net "PWM_OUT_FAN1")
	)
	(segment
		(start 26.90876 -220.600016)
		(end 26.90876 -219.483432)
		(width 0.254)
		(layer "F.Cu")
		(net "PWM_OUT_FAN1")
	)
	(segment
		(start 26.90876 -222.01886)
		(end 26.90876 -220.600016)
		(width 0.254)
		(layer "F.Cu")
		(net "PWM_OUT_FAN1")
	)
	(segment
		(start 26.30551 -222.62211)
		(end 26.90876 -222.01886)
		(width 0.254)
		(layer "F.Cu")
		(net "PWM_OUT_FAN1")
	)
	(segment
		(start 23.4696 -219.8878)
		(end 23.5712 -219.7862)
		(width 0.254)
		(layer "F.Cu")
		(net "PWM_OUT_FAN1")
	)
	(segment
		(start 26.0604 -223.8629)
		(end 26.30551 -223.61779)
		(width 0.254)
		(layer "F.Cu")
		(net "PWM_OUT_FAN1")
	)
	(segment
		(start 26.90876 -219.483432)
		(end 26.20518 -218.779852)
		(width 0.254)
		(layer "F.Cu")
		(net "PWM_OUT_FAN1")
	)
	(segment
		(start 24.577548 -218.779852)
		(end 23.5712 -219.7862)
		(width 0.254)
		(layer "F.Cu")
		(net "PWM_OUT_FAN1")
	)
	(segment
		(start 22.2123 -219.8878)
		(end 23.4696 -219.8878)
		(width 0.254)
		(layer "F.Cu")
		(net "PWM_OUT_FAN1")
	)
	(via
		(at 23.5712 -219.7862)
		(size 0.7112)
		(drill 0.3556)
		(layers "F.Cu" "B.Cu")
		(net "PWM_OUT_FAN1")
	)
	(segment
		(start 36.5252 -253.9365)
		(end 36.5252 -253.0602)
		(width 0.1397)
		(layer "F.Cu")
		(net "LED_DRV_RST")
	)
	(segment
		(start 36.83508 -249.3518)
		(end 36.83508 -251.83592)
		(width 0.1397)
		(layer "F.Cu")
		(net "LED_DRV_RST")
	)
	(segment
		(start 36.83508 -251.83592)
		(end 36.068 -252.603)
		(width 0.1397)
		(layer "F.Cu")
		(net "LED_DRV_RST")
	)
	(segment
		(start 36.5252 -253.0602)
		(end 36.068 -252.603)
		(width 0.1397)
		(layer "F.Cu")
		(net "LED_DRV_RST")
	)
	(segment
		(start 40.767 -371.475)
		(end 40.767 -371.1575)
		(width 0.254)
		(layer "F.Cu")
		(net "ADM1276_LATCH_B")
	)
	(segment
		(start 36.212526 -363.161326)
		(end 36.822126 -363.161326)
		(width 0.254)
		(layer "F.Cu")
		(net "ADM1276_LATCH_B")
	)
	(segment
		(start 38.481 -364.8202)
		(end 38.481 -365.379)
		(width 0.254)
		(layer "F.Cu")
		(net "ADM1276_LATCH_B")
	)
	(segment
		(start 38.481 -366.93475)
		(end 38.481 -365.379)
		(width 0.254)
		(layer "F.Cu")
		(net "ADM1276_LATCH_B")
	)
	(segment
		(start 40.005 -370.2685)
		(end 39.9415 -370.332)
		(width 0.254)
		(layer "F.Cu")
		(net "ADM1276_LATCH_B")
	)
	(segment
		(start 40.767 -371.1575)
		(end 39.9415 -370.332)
		(width 0.254)
		(layer "F.Cu")
		(net "ADM1276_LATCH_B")
	)
	(segment
		(start 40.005 -369.5192)
		(end 40.005 -370.2685)
		(width 0.254)
		(layer "F.Cu")
		(net "ADM1276_LATCH_B")
	)
	(segment
		(start 38.44925 -366.9665)
		(end 38.481 -366.93475)
		(width 0.254)
		(layer "F.Cu")
		(net "ADM1276_LATCH_B")
	)
	(segment
		(start 36.822126 -363.161326)
		(end 38.481 -364.8202)
		(width 0.254)
		(layer "F.Cu")
		(net "ADM1276_LATCH_B")
	)
	(via
		(at 40.005 -369.5192)
		(size 0.5588)
		(drill 0.3048)
		(layers "F.Cu" "B.Cu")
		(net "ADM1276_LATCH_B")
	)
	(via
		(at 38.481 -365.379)
		(size 0.5588)
		(drill 0.3048)
		(layers "F.Cu" "B.Cu")
		(net "ADM1276_LATCH_B")
	)
	(via
		(at 39.624 -367.665)
		(size 0.7112)
		(drill 0.3556)
		(layers "F.Cu" "B.Cu")
		(net "ADM1276_LATCH_B")
	)
	(segment
		(start 40.005 -368.046)
		(end 39.624 -367.665)
		(width 0.254)
		(layer "B.Cu")
		(net "ADM1276_LATCH_B")
	)
	(segment
		(start 38.481 -365.379)
		(end 39.624 -366.522)
		(width 0.254)
		(layer "B.Cu")
		(net "ADM1276_LATCH_B")
	)
	(segment
		(start 39.624 -366.522)
		(end 39.624 -367.665)
		(width 0.254)
		(layer "B.Cu")
		(net "ADM1276_LATCH_B")
	)
	(segment
		(start 40.005 -369.5192)
		(end 40.005 -368.046)
		(width 0.254)
		(layer "B.Cu")
		(net "ADM1276_LATCH_B")
	)
	(segment
		(start 38.800024 -368.681)
		(end 38.977824 -368.8588)
		(width 0.254)
		(layer "F.Cu")
		(net "ADM1276_EN_NET")
	)
	(segment
		(start 40.8305 -369.824)
		(end 40.8305 -370.332)
		(width 0.254)
		(layer "F.Cu")
		(net "ADM1276_EN_NET")
	)
	(segment
		(start 36.48075 -366.9665)
		(end 36.0045 -366.9665)
		(width 0.254)
		(layer "F.Cu")
		(net "ADM1276_EN_NET")
	)
	(segment
		(start 40.64 -369.363752)
		(end 40.64 -369.6335)
		(width 0.254)
		(layer "F.Cu")
		(net "ADM1276_EN_NET")
	)
	(segment
		(start 34.925 -367.792)
		(end 35.052 -367.919)
		(width 0.254)
		(layer "F.Cu")
		(net "ADM1276_EN_NET")
	)
	(segment
		(start 40.64 -369.6335)
		(end 40.8305 -369.824)
		(width 0.254)
		(layer "F.Cu")
		(net "ADM1276_EN_NET")
	)
	(segment
		(start 37.904674 -368.681)
		(end 38.800024 -368.681)
		(width 0.254)
		(layer "F.Cu")
		(net "ADM1276_EN_NET")
	)
	(segment
		(start 40.8305 -370.332)
		(end 42.3418 -370.332)
		(width 0.254)
		(layer "F.Cu")
		(net "ADM1276_EN_NET")
	)
	(segment
		(start 34.925 -366.7125)
		(end 34.925 -367.792)
		(width 0.254)
		(layer "F.Cu")
		(net "ADM1276_EN_NET")
	)
	(segment
		(start 42.3418 -370.332)
		(end 42.418 -370.2558)
		(width 0.254)
		(layer "F.Cu")
		(net "ADM1276_EN_NET")
	)
	(segment
		(start 36.0045 -366.9665)
		(end 35.052 -367.919)
		(width 0.254)
		(layer "F.Cu")
		(net "ADM1276_EN_NET")
	)
	(segment
		(start 38.977824 -368.8588)
		(end 40.135048 -368.8588)
		(width 0.254)
		(layer "F.Cu")
		(net "ADM1276_EN_NET")
	)
	(segment
		(start 36.703 -367.479326)
		(end 37.904674 -368.681)
		(width 0.254)
		(layer "F.Cu")
		(net "ADM1276_EN_NET")
	)
	(segment
		(start 36.703 -367.18875)
		(end 36.703 -367.479326)
		(width 0.254)
		(layer "F.Cu")
		(net "ADM1276_EN_NET")
	)
	(segment
		(start 36.48075 -366.9665)
		(end 36.703 -367.18875)
		(width 0.254)
		(layer "F.Cu")
		(net "ADM1276_EN_NET")
	)
	(segment
		(start 40.135048 -368.8588)
		(end 40.64 -369.363752)
		(width 0.254)
		(layer "F.Cu")
		(net "ADM1276_EN_NET")
	)
	(via
		(at 35.052 -367.919)
		(size 0.7112)
		(drill 0.3556)
		(layers "F.Cu" "B.Cu")
		(net "ADM1276_EN_NET")
	)
	(segment
		(start 40.562784 -367.665)
		(end 40.767 -367.665)
		(width 0.1397)
		(layer "F.Cu")
		(net "TEMP_ALM#_REVERSE")
	)
	(segment
		(start 43.019726 -368.1984)
		(end 43.019726 -367.022126)
		(width 0.1397)
		(layer "F.Cu")
		(net "TEMP_ALM#_REVERSE")
	)
	(segment
		(start 41.5544 -368.4524)
		(end 42.037 -368.4524)
		(width 0.1397)
		(layer "F.Cu")
		(net "TEMP_ALM#_REVERSE")
	)
	(segment
		(start 42.037 -368.4524)
		(end 42.765726 -368.4524)
		(width 0.1397)
		(layer "F.Cu")
		(net "TEMP_ALM#_REVERSE")
	)
	(segment
		(start 38.692074 -363.507274)
		(end 39.784274 -363.507274)
		(width 0.1397)
		(layer "F.Cu")
		(net "TEMP_ALM#_REVERSE")
	)
	(segment
		(start 40.866314 -366.804702)
		(end 40.2844 -367.386616)
		(width 0.1397)
		(layer "F.Cu")
		(net "TEMP_ALM#_REVERSE")
	)
	(segment
		(start 39.784274 -363.507274)
		(end 40.866314 -364.589314)
		(width 0.1397)
		(layer "F.Cu")
		(net "TEMP_ALM#_REVERSE")
	)
	(segment
		(start 42.765726 -368.4524)
		(end 43.019726 -368.1984)
		(width 0.1397)
		(layer "F.Cu")
		(net "TEMP_ALM#_REVERSE")
	)
	(segment
		(start 40.2844 -367.386616)
		(end 40.562784 -367.665)
		(width 0.1397)
		(layer "F.Cu")
		(net "TEMP_ALM#_REVERSE")
	)
	(segment
		(start 40.767 -367.665)
		(end 41.5544 -368.4524)
		(width 0.1397)
		(layer "F.Cu")
		(net "TEMP_ALM#_REVERSE")
	)
	(segment
		(start 40.866314 -364.589314)
		(end 40.866314 -366.804702)
		(width 0.1397)
		(layer "F.Cu")
		(net "TEMP_ALM#_REVERSE")
	)
	(via
		(at 42.037 -368.4524)
		(size 0.7112)
		(drill 0.3556)
		(layers "F.Cu" "B.Cu")
		(net "TEMP_ALM#_REVERSE")
	)
	(segment
		(start 6.977634 -68.336668)
		(end 7.0866 -68.445634)
		(width 0.1397)
		(layer "F.Cu")
		(net "LED_DR_LED5_B")
	)
	(segment
		(start 6.977634 -66.688462)
		(end 6.977634 -68.336668)
		(width 0.1397)
		(layer "F.Cu")
		(net "LED_DR_LED5_B")
	)
	(segment
		(start 8.288528 -67.111118)
		(end 8.288528 -67.243706)
		(width 0.1397)
		(layer "F.Cu")
		(net "LED_DR_LED5_B")
	)
	(segment
		(start 8.288528 -67.243706)
		(end 7.0866 -68.445634)
		(width 0.1397)
		(layer "F.Cu")
		(net "LED_DR_LED5_B")
	)
	(via
		(at 7.0866 -68.445634)
		(size 0.7112)
		(drill 0.3556)
		(layers "F.Cu" "B.Cu")
		(net "LED_DR_LED5_B")
	)
	(segment
		(start 4.897882 -78.036928)
		(end 4.897882 -77.142086)
		(width 0.1397)
		(layer "F.Cu")
		(net "LED_DR_LED4_B")
	)
	(segment
		(start 5.08254 -76.957428)
		(end 5.087112 -76.962)
		(width 0.1397)
		(layer "F.Cu")
		(net "LED_DR_LED4_B")
	)
	(segment
		(start 5.087112 -76.962)
		(end 5.73405 -76.962)
		(width 0.1397)
		(layer "F.Cu")
		(net "LED_DR_LED4_B")
	)
	(segment
		(start 5.73405 -76.962)
		(end 6.33095 -77.5589)
		(width 0.1397)
		(layer "F.Cu")
		(net "LED_DR_LED4_B")
	)
	(segment
		(start 4.897882 -77.142086)
		(end 5.08254 -76.957428)
		(width 0.1397)
		(layer "F.Cu")
		(net "LED_DR_LED4_B")
	)
	(via
		(at 5.08254 -76.957428)
		(size 0.7112)
		(drill 0.3556)
		(layers "F.Cu" "B.Cu")
		(net "LED_DR_LED4_B")
	)
	(segment
		(start 14.907768 -231.106472)
		(end 15.03934 -230.9749)
		(width 0.1397)
		(layer "F.Cu")
		(net "LED_DR_LED3_B")
	)
	(segment
		(start 15.03934 -230.9749)
		(end 16.2814 -230.9749)
		(width 0.1397)
		(layer "F.Cu")
		(net "LED_DR_LED3_B")
	)
	(segment
		(start 16.2814 -230.9749)
		(end 16.2814 -229.8192)
		(width 0.1397)
		(layer "F.Cu")
		(net "LED_DR_LED3_B")
	)
	(via
		(at 16.2814 -229.8192)
		(size 0.7112)
		(drill 0.3556)
		(layers "F.Cu" "B.Cu")
		(net "LED_DR_LED3_B")
	)
	(segment
		(start 9.6393 -278.384)
		(end 9.6393 -277.4823)
		(width 0.1397)
		(layer "F.Cu")
		(net "LED_DR_LED2_B")
	)
	(segment
		(start 9.6393 -277.4823)
		(end 9.4488 -277.2918)
		(width 0.1397)
		(layer "F.Cu")
		(net "LED_DR_LED2_B")
	)
	(segment
		(start 8.094472 -276.658832)
		(end 8.815832 -276.658832)
		(width 0.1397)
		(layer "F.Cu")
		(net "LED_DR_LED2_B")
	)
	(segment
		(start 8.815832 -276.658832)
		(end 9.4488 -277.2918)
		(width 0.1397)
		(layer "F.Cu")
		(net "LED_DR_LED2_B")
	)
	(via
		(at 9.4488 -277.2918)
		(size 0.7112)
		(drill 0.3556)
		(layers "F.Cu" "B.Cu")
		(net "LED_DR_LED2_B")
	)
	(segment
		(start 8.98525 -418.8587)
		(end 8.98525 -420.07155)
		(width 0.1397)
		(layer "F.Cu")
		(net "LED_DR_LED1_B")
	)
	(segment
		(start 8.98525 -420.07155)
		(end 8.3566 -420.7002)
		(width 0.1397)
		(layer "F.Cu")
		(net "LED_DR_LED1_B")
	)
	(segment
		(start 8.3566 -420.7002)
		(end 8.3566 -421.8305)
		(width 0.1397)
		(layer "F.Cu")
		(net "LED_DR_LED1_B")
	)
	(via
		(at 8.3566 -420.7002)
		(size 0.7112)
		(drill 0.3556)
		(layers "F.Cu" "B.Cu")
		(net "LED_DR_LED1_B")
	)
	(segment
		(start 5.5499 -436.5625)
		(end 5.5499 -437.0578)
		(width 0.1397)
		(layer "F.Cu")
		(net "LED_DR_LED0_B")
	)
	(segment
		(start 6.535928 -435.576472)
		(end 5.5499 -436.5625)
		(width 0.1397)
		(layer "F.Cu")
		(net "LED_DR_LED0_B")
	)
	(segment
		(start 6.932168 -435.576472)
		(end 6.535928 -435.576472)
		(width 0.1397)
		(layer "F.Cu")
		(net "LED_DR_LED0_B")
	)
	(segment
		(start 7.459472 -435.576472)
		(end 6.932168 -435.576472)
		(width 0.1397)
		(layer "F.Cu")
		(net "LED_DR_LED0_B")
	)
	(segment
		(start 8.382 -436.499)
		(end 7.459472 -435.576472)
		(width 0.1397)
		(layer "F.Cu")
		(net "LED_DR_LED0_B")
	)
	(via
		(at 8.382 -436.499)
		(size 0.7112)
		(drill 0.3556)
		(layers "F.Cu" "B.Cu")
		(net "LED_DR_LED0_B")
	)
	(segment
		(start 9.623298 -88.535002)
		(end 9.9568 -88.2015)
		(width 0.1397)
		(layer "F.Cu")
		(net "LED_DR_LED4_K")
	)
	(segment
		(start 7.949946 -88.535002)
		(end 9.623298 -88.535002)
		(width 0.1397)
		(layer "F.Cu")
		(net "LED_DR_LED4_K")
	)
	(segment
		(start 6.0325 -56.0705)
		(end 6.0325 -59.6265)
		(width 0.1397)
		(layer "F.Cu")
		(net "LED_DR_LED5_BLUE")
	)
	(segment
		(start 7.949946 -53.559964)
		(end 7.949946 -54.153054)
		(width 0.1397)
		(layer "F.Cu")
		(net "LED_DR_LED5_BLUE")
	)
	(segment
		(start 8.3058 -64.3763)
		(end 8.3058 -63.9318)
		(width 0.1397)
		(layer "F.Cu")
		(net "LED_DR_LED5_BLUE")
	)
	(segment
		(start 8.3058 -63.9318)
		(end 7.0866 -62.7126)
		(width 0.1397)
		(layer "F.Cu")
		(net "LED_DR_LED5_BLUE")
	)
	(segment
		(start 6.0325 -59.6265)
		(end 7.0866 -60.6806)
		(width 0.1397)
		(layer "F.Cu")
		(net "LED_DR_LED5_BLUE")
	)
	(segment
		(start 8.3058 -64.3763)
		(end 6.400546 -64.3763)
		(width 0.1397)
		(layer "F.Cu")
		(net "LED_DR_LED5_BLUE")
	)
	(segment
		(start 7.949946 -54.153054)
		(end 6.0325 -56.0705)
		(width 0.1397)
		(layer "F.Cu")
		(net "LED_DR_LED5_BLUE")
	)
	(segment
		(start 6.400546 -64.3763)
		(end 5.993384 -64.783462)
		(width 0.1397)
		(layer "F.Cu")
		(net "LED_DR_LED5_BLUE")
	)
	(segment
		(start 7.0866 -60.6806)
		(end 7.0866 -62.7126)
		(width 0.1397)
		(layer "F.Cu")
		(net "LED_DR_LED5_BLUE")
	)
	(segment
		(start 9.2202 -83.439)
		(end 9.2202 -82.5627)
		(width 0.1397)
		(layer "F.Cu")
		(net "LED_DR_LED4_BLUE")
	)
	(segment
		(start 9.2202 -84.724748)
		(end 7.949946 -85.995002)
		(width 0.1397)
		(layer "F.Cu")
		(net "LED_DR_LED4_BLUE")
	)
	(segment
		(start 8.5344 -81.6102)
		(end 9.1948 -80.9498)
		(width 0.1397)
		(layer "F.Cu")
		(net "LED_DR_LED4_BLUE")
	)
	(segment
		(start 8.2677 -81.6102)
		(end 8.5344 -81.6102)
		(width 0.1397)
		(layer "F.Cu")
		(net "LED_DR_LED4_BLUE")
	)
	(segment
		(start 8.3312 -80.8863)
		(end 7.3152 -79.8703)
		(width 0.1397)
		(layer "F.Cu")
		(net "LED_DR_LED4_BLUE")
	)
	(segment
		(start 9.1948 -80.9498)
		(end 9.1313 -80.8863)
		(width 0.1397)
		(layer "F.Cu")
		(net "LED_DR_LED4_BLUE")
	)
	(segment
		(start 9.2202 -83.439)
		(end 9.2202 -84.724748)
		(width 0.1397)
		(layer "F.Cu")
		(net "LED_DR_LED4_BLUE")
	)
	(segment
		(start 7.3152 -79.8703)
		(end 7.3152 -79.4639)
		(width 0.1397)
		(layer "F.Cu")
		(net "LED_DR_LED4_BLUE")
	)
	(segment
		(start 9.1313 -80.8863)
		(end 8.3312 -80.8863)
		(width 0.1397)
		(layer "F.Cu")
		(net "LED_DR_LED4_BLUE")
	)
	(segment
		(start 9.2202 -82.5627)
		(end 8.2677 -81.6102)
		(width 0.1397)
		(layer "F.Cu")
		(net "LED_DR_LED4_BLUE")
	)
	(via
		(at 9.1948 -80.9498)
		(size 0.7112)
		(drill 0.3556)
		(layers "F.Cu" "B.Cu")
		(net "LED_DR_LED4_BLUE")
	)
	(segment
		(start 11.0236 -227.6221)
		(end 12.3317 -227.6221)
		(width 0.1397)
		(layer "F.Cu")
		(net "LED_DR_LED3_BLUE")
	)
	(segment
		(start 14.003528 -229.201472)
		(end 13.923518 -229.201472)
		(width 0.1397)
		(layer "F.Cu")
		(net "LED_DR_LED3_BLUE")
	)
	(segment
		(start 11.0236 -227.6221)
		(end 9.922764 -227.6221)
		(width 0.1397)
		(layer "F.Cu")
		(net "LED_DR_LED3_BLUE")
	)
	(segment
		(start 14.605 -228.6)
		(end 14.003528 -229.201472)
		(width 0.1397)
		(layer "F.Cu")
		(net "LED_DR_LED3_BLUE")
	)
	(segment
		(start 16.7386 -228.6)
		(end 14.605 -228.6)
		(width 0.1397)
		(layer "F.Cu")
		(net "LED_DR_LED3_BLUE")
	)
	(segment
		(start 13.923518 -228.528118)
		(end 12.6746 -227.2792)
		(width 0.1397)
		(layer "F.Cu")
		(net "LED_DR_LED3_BLUE")
	)
	(segment
		(start 9.922764 -227.6221)
		(end 7.949946 -229.594918)
		(width 0.1397)
		(layer "F.Cu")
		(net "LED_DR_LED3_BLUE")
	)
	(segment
		(start 13.923518 -229.201472)
		(end 13.923518 -228.528118)
		(width 0.1397)
		(layer "F.Cu")
		(net "LED_DR_LED3_BLUE")
	)
	(segment
		(start 12.3317 -227.6221)
		(end 12.6746 -227.2792)
		(width 0.1397)
		(layer "F.Cu")
		(net "LED_DR_LED3_BLUE")
	)
	(via
		(at 16.7386 -228.6)
		(size 0.7112)
		(drill 0.3556)
		(layers "F.Cu" "B.Cu")
		(net "LED_DR_LED3_BLUE")
	)
	(segment
		(start 6.223 -279.908)
		(end 6.189472 -279.874472)
		(width 0.1397)
		(layer "F.Cu")
		(net "LED_DR_LED2_BLUE")
	)
	(segment
		(start 7.949946 -265.325098)
		(end 7.949946 -266.427204)
		(width 0.1397)
		(layer "F.Cu")
		(net "LED_DR_LED2_BLUE")
	)
	(segment
		(start 9.906 -263.369044)
		(end 7.949946 -265.325098)
		(width 0.1397)
		(layer "F.Cu")
		(net "LED_DR_LED2_BLUE")
	)
	(segment
		(start 6.189472 -279.874472)
		(end 6.189472 -277.643082)
		(width 0.1397)
		(layer "F.Cu")
		(net "LED_DR_LED2_BLUE")
	)
	(segment
		(start 6.1595 -279.9715)
		(end 6.223 -279.908)
		(width 0.1397)
		(layer "F.Cu")
		(net "LED_DR_LED2_BLUE")
	)
	(segment
		(start 5.7531 -277.20671)
		(end 6.189472 -277.643082)
		(width 0.1397)
		(layer "F.Cu")
		(net "LED_DR_LED2_BLUE")
	)
	(segment
		(start 9.906 -262.509)
		(end 9.906 -263.369044)
		(width 0.1397)
		(layer "F.Cu")
		(net "LED_DR_LED2_BLUE")
	)
	(segment
		(start 5.7531 -268.62405)
		(end 5.7531 -277.20671)
		(width 0.1397)
		(layer "F.Cu")
		(net "LED_DR_LED2_BLUE")
	)
	(segment
		(start 7.949946 -266.427204)
		(end 5.7531 -268.62405)
		(width 0.1397)
		(layer "F.Cu")
		(net "LED_DR_LED2_BLUE")
	)
	(segment
		(start 6.1595 -280.924)
		(end 6.1595 -279.9715)
		(width 0.1397)
		(layer "F.Cu")
		(net "LED_DR_LED2_BLUE")
	)
	(via
		(at 6.223 -279.908)
		(size 0.7112)
		(drill 0.3556)
		(layers "F.Cu" "B.Cu")
		(net "LED_DR_LED2_BLUE")
	)
	(segment
		(start 8.001 -416.9537)
		(end 6.7183 -416.9537)
		(width 0.1397)
		(layer "F.Cu")
		(net "LED_DR_LED1_BLUE")
	)
	(segment
		(start 8.001 -416.179)
		(end 8.001 -416.9537)
		(width 0.1397)
		(layer "F.Cu")
		(net "LED_DR_LED1_BLUE")
	)
	(segment
		(start 7.118096 -415.296096)
		(end 8.001 -416.179)
		(width 0.1397)
		(layer "F.Cu")
		(net "LED_DR_LED1_BLUE")
	)
	(segment
		(start 6.9088 -420.9034)
		(end 5.6007 -419.5953)
		(width 0.1397)
		(layer "F.Cu")
		(net "LED_DR_LED1_BLUE")
	)
	(segment
		(start 6.0198 -417.6522)
		(end 5.6007 -417.6522)
		(width 0.1397)
		(layer "F.Cu")
		(net "LED_DR_LED1_BLUE")
	)
	(segment
		(start 6.7183 -416.9537)
		(end 6.0198 -417.6522)
		(width 0.1397)
		(layer "F.Cu")
		(net "LED_DR_LED1_BLUE")
	)
	(segment
		(start 8.781796 -411.809692)
		(end 7.118096 -413.473392)
		(width 0.1397)
		(layer "F.Cu")
		(net "LED_DR_LED1_BLUE")
	)
	(segment
		(start 8.781796 -409.756864)
		(end 8.781796 -411.809692)
		(width 0.1397)
		(layer "F.Cu")
		(net "LED_DR_LED1_BLUE")
	)
	(segment
		(start 7.118096 -413.473392)
		(end 7.118096 -415.296096)
		(width 0.1397)
		(layer "F.Cu")
		(net "LED_DR_LED1_BLUE")
	)
	(segment
		(start 5.6007 -419.5953)
		(end 5.6007 -417.6522)
		(width 0.1397)
		(layer "F.Cu")
		(net "LED_DR_LED1_BLUE")
	)
	(segment
		(start 7.949946 -408.925014)
		(end 8.781796 -409.756864)
		(width 0.1397)
		(layer "F.Cu")
		(net "LED_DR_LED1_BLUE")
	)
	(segment
		(start 45.0088 -174.77613)
		(end 45.0088 -176.0347)
		(width 0.254)
		(layer "F.Cu")
		(net "ADM1276_EN")
	)
	(segment
		(start 39.4208 -172.593)
		(end 40.6146 -173.7868)
		(width 0.254)
		(layer "F.Cu")
		(net "ADM1276_EN")
	)
	(segment
		(start 32.574484 -358.8258)
		(end 31.75 -358.001316)
		(width 0.254)
		(layer "F.Cu")
		(net "ADM1276_EN")
	)
	(segment
		(start 33.318196 -358.8258)
		(end 32.574484 -358.8258)
		(width 0.254)
		(layer "F.Cu")
		(net "ADM1276_EN")
	)
	(segment
		(start 29.718 -364.5408)
		(end 29.718 -366.3696)
		(width 0.254)
		(layer "F.Cu")
		(net "ADM1276_EN")
	)
	(segment
		(start 45.0088 -176.0347)
		(end 44.5135 -176.53)
		(width 0.254)
		(layer "F.Cu")
		(net "ADM1276_EN")
	)
	(segment
		(start 40.6146 -173.7868)
		(end 44.01947 -173.7868)
		(width 0.254)
		(layer "F.Cu")
		(net "ADM1276_EN")
	)
	(segment
		(start 28.7401 -363.5629)
		(end 29.718 -364.5408)
		(width 0.254)
		(layer "F.Cu")
		(net "ADM1276_EN")
	)
	(segment
		(start 44.5135 -176.53)
		(end 44.5135 -178.0794)
		(width 0.254)
		(layer "F.Cu")
		(net "ADM1276_EN")
	)
	(segment
		(start 28.7401 -362.1786)
		(end 28.7401 -363.5629)
		(width 0.254)
		(layer "F.Cu")
		(net "ADM1276_EN")
	)
	(segment
		(start 44.01947 -173.7868)
		(end 45.0088 -174.77613)
		(width 0.254)
		(layer "F.Cu")
		(net "ADM1276_EN")
	)
	(segment
		(start 33.984946 -365.937546)
		(end 34.098992 -365.8235)
		(width 0.254)
		(layer "F.Cu")
		(net "ADM1276_EN")
	)
	(segment
		(start 34.098992 -365.8235)
		(end 34.925 -365.8235)
		(width 0.254)
		(layer "F.Cu")
		(net "ADM1276_EN")
	)
	(segment
		(start 28.7401 -361.0864)
		(end 28.7401 -362.1786)
		(width 0.254)
		(layer "F.Cu")
		(net "ADM1276_EN")
	)
	(via
		(at 29.718 -364.5408)
		(size 0.7112)
		(drill 0.4064)
		(layers "F.Cu" "B.Cu")
		(net "ADM1276_EN")
	)
	(via
		(at 33.318196 -358.8258)
		(size 0.5588)
		(drill 0.3048)
		(layers "F.Cu" "B.Cu")
		(net "ADM1276_EN")
	)
	(via
		(at 31.115 -365.127286)
		(size 0.7112)
		(drill 0.3556)
		(layers "F.Cu" "B.Cu")
		(net "ADM1276_EN")
	)
	(via
		(at 39.4208 -172.593)
		(size 0.5588)
		(drill 0.3048)
		(layers "F.Cu" "B.Cu")
		(net "ADM1276_EN")
	)
	(via
		(at 33.984946 -365.937546)
		(size 0.7112)
		(drill 0.4064)
		(layers "F.Cu" "B.Cu")
		(net "ADM1276_EN")
	)
	(segment
		(start 39.40175 -172.61205)
		(end 39.4208 -172.593)
		(width 0.254)
		(layer "B.Cu")
		(net "ADM1276_EN")
	)
	(segment
		(start 38.25875 -210.885024)
		(end 38.25875 -186.68365)
		(width 0.254)
		(layer "B.Cu")
		(net "ADM1276_EN")
	)
	(segment
		(start 42.007028 -252.1712)
		(end 43.05935 -251.118878)
		(width 0.254)
		(layer "B.Cu")
		(net "ADM1276_EN")
	)
	(segment
		(start 35.87115 -259.6642)
		(end 35.87115 -257.37185)
		(width 0.254)
		(layer "B.Cu")
		(net "ADM1276_EN")
	)
	(segment
		(start 33.319466 -278.465534)
		(end 35.401504 -276.383496)
		(width 0.254)
		(layer "B.Cu")
		(net "ADM1276_EN")
	)
	(segment
		(start 30.528514 -364.5408)
		(end 31.115 -365.127286)
		(width 0.254)
		(layer "B.Cu")
		(net "ADM1276_EN")
	)
	(segment
		(start 33.318196 -358.8258)
		(end 33.319466 -358.82453)
		(width 0.254)
		(layer "B.Cu")
		(net "ADM1276_EN")
	)
	(segment
		(start 35.402012 -273.539204)
		(end 35.402012 -260.133338)
		(width 0.254)
		(layer "B.Cu")
		(net "ADM1276_EN")
	)
	(segment
		(start 39.444168 -176.426368)
		(end 39.40175 -176.38395)
		(width 0.254)
		(layer "B.Cu")
		(net "ADM1276_EN")
	)
	(segment
		(start 33.319466 -358.82453)
		(end 33.319466 -278.465534)
		(width 0.254)
		(layer "B.Cu")
		(net "ADM1276_EN")
	)
	(segment
		(start 38.25875 -186.68365)
		(end 39.444168 -185.498232)
		(width 0.254)
		(layer "B.Cu")
		(net "ADM1276_EN")
	)
	(segment
		(start 43.05935 -215.685624)
		(end 38.25875 -210.885024)
		(width 0.254)
		(layer "B.Cu")
		(net "ADM1276_EN")
	)
	(segment
		(start 43.05935 -251.118878)
		(end 43.05935 -215.685624)
		(width 0.254)
		(layer "B.Cu")
		(net "ADM1276_EN")
	)
	(segment
		(start 31.115 -365.127286)
		(end 31.92526 -365.937546)
		(width 0.254)
		(layer "B.Cu")
		(net "ADM1276_EN")
	)
	(segment
		(start 33.984946 -365.937546)
		(end 34.1884 -365.734092)
		(width 0.254)
		(layer "B.Cu")
		(net "ADM1276_EN")
	)
	(segment
		(start 29.718 -364.5408)
		(end 30.528514 -364.5408)
		(width 0.254)
		(layer "B.Cu")
		(net "ADM1276_EN")
	)
	(segment
		(start 35.402012 -260.133338)
		(end 35.87115 -259.6642)
		(width 0.254)
		(layer "B.Cu")
		(net "ADM1276_EN")
	)
	(segment
		(start 34.1884 -365.734092)
		(end 34.1884 -361.606846)
		(width 0.254)
		(layer "B.Cu")
		(net "ADM1276_EN")
	)
	(segment
		(start 33.318196 -360.736642)
		(end 33.318196 -358.8258)
		(width 0.254)
		(layer "B.Cu")
		(net "ADM1276_EN")
	)
	(segment
		(start 35.87115 -257.37185)
		(end 41.0718 -252.1712)
		(width 0.254)
		(layer "B.Cu")
		(net "ADM1276_EN")
	)
	(segment
		(start 35.40125 -273.539966)
		(end 35.402012 -273.539204)
		(width 0.254)
		(layer "B.Cu")
		(net "ADM1276_EN")
	)
	(segment
		(start 41.0718 -252.1712)
		(end 42.007028 -252.1712)
		(width 0.254)
		(layer "B.Cu")
		(net "ADM1276_EN")
	)
	(segment
		(start 35.40125 -274.018502)
		(end 35.40125 -273.539966)
		(width 0.254)
		(layer "B.Cu")
		(net "ADM1276_EN")
	)
	(segment
		(start 35.401504 -274.018756)
		(end 35.40125 -274.018502)
		(width 0.254)
		(layer "B.Cu")
		(net "ADM1276_EN")
	)
	(segment
		(start 39.40175 -176.38395)
		(end 39.40175 -172.61205)
		(width 0.254)
		(layer "B.Cu")
		(net "ADM1276_EN")
	)
	(segment
		(start 35.401504 -276.383496)
		(end 35.401504 -274.018756)
		(width 0.254)
		(layer "B.Cu")
		(net "ADM1276_EN")
	)
	(segment
		(start 31.92526 -365.937546)
		(end 33.984946 -365.937546)
		(width 0.254)
		(layer "B.Cu")
		(net "ADM1276_EN")
	)
	(segment
		(start 39.444168 -185.498232)
		(end 39.444168 -176.426368)
		(width 0.254)
		(layer "B.Cu")
		(net "ADM1276_EN")
	)
	(segment
		(start 34.1884 -361.606846)
		(end 33.318196 -360.736642)
		(width 0.254)
		(layer "B.Cu")
		(net "ADM1276_EN")
	)
	(segment
		(start 26.2255 -248.8565)
		(end 26.289 -248.92)
		(width 0.254)
		(layer "F.Cu")
		(net "P3V3_FB")
	)
	(segment
		(start 22.352 -250.444)
		(end 22.352 -248.9327)
		(width 0.254)
		(layer "F.Cu")
		(net "P3V3_FB")
	)
	(segment
		(start 24.003 -249.936)
		(end 22.997668 -250.941332)
		(width 0.254)
		(layer "F.Cu")
		(net "P3V3_FB")
	)
	(segment
		(start 22.997668 -250.941332)
		(end 22.849332 -250.941332)
		(width 0.254)
		(layer "F.Cu")
		(net "P3V3_FB")
	)
	(segment
		(start 25.146 -248.8565)
		(end 24.7015 -248.8565)
		(width 0.254)
		(layer "F.Cu")
		(net "P3V3_FB")
	)
	(segment
		(start 24.003 -249.555)
		(end 24.003 -249.936)
		(width 0.254)
		(layer "F.Cu")
		(net "P3V3_FB")
	)
	(segment
		(start 22.849332 -250.941332)
		(end 22.352 -250.444)
		(width 0.254)
		(layer "F.Cu")
		(net "P3V3_FB")
	)
	(segment
		(start 25.146 -248.8565)
		(end 26.2255 -248.8565)
		(width 0.254)
		(layer "F.Cu")
		(net "P3V3_FB")
	)
	(segment
		(start 24.7015 -248.8565)
		(end 24.003 -249.555)
		(width 0.254)
		(layer "F.Cu")
		(net "P3V3_FB")
	)
	(via
		(at 22.997668 -250.941332)
		(size 0.7112)
		(drill 0.3556)
		(layers "F.Cu" "B.Cu")
		(net "P3V3_FB")
	)
	(segment
		(start 20.6756 -250.4186)
		(end 20.701 -250.4186)
		(width 0.254)
		(layer "F.Cu")
		(net "P3V3_EN")
	)
	(segment
		(start 19.6596 -249.4026)
		(end 20.6756 -250.4186)
		(width 0.254)
		(layer "F.Cu")
		(net "P3V3_EN")
	)
	(segment
		(start 19.6596 -248.9327)
		(end 19.6596 -249.4026)
		(width 0.254)
		(layer "F.Cu")
		(net "P3V3_EN")
	)
	(segment
		(start 20.5232 -250.5964)
		(end 20.701 -250.4186)
		(width 0.254)
		(layer "F.Cu")
		(net "P3V3_EN")
	)
	(segment
		(start 18.3769 -248.9327)
		(end 19.6596 -248.9327)
		(width 0.254)
		(layer "F.Cu")
		(net "P3V3_EN")
	)
	(segment
		(start 17.9832 -249.3264)
		(end 18.3769 -248.9327)
		(width 0.254)
		(layer "F.Cu")
		(net "P3V3_EN")
	)
	(segment
		(start 19.5072 -250.5964)
		(end 20.5232 -250.5964)
		(width 0.254)
		(layer "F.Cu")
		(net "P3V3_EN")
	)
	(via
		(at 20.701 -250.4186)
		(size 0.7112)
		(drill 0.3556)
		(layers "F.Cu" "B.Cu")
		(net "P3V3_EN")
	)
	(segment
		(start 22.352 -245.4402)
		(end 22.2504 -245.3386)
		(width 0.254)
		(layer "F.Cu")
		(net "P3V3_BS_NET")
	)
	(segment
		(start 20.8661 -245.3386)
		(end 22.2504 -245.3386)
		(width 0.254)
		(layer "F.Cu")
		(net "P3V3_BS_NET")
	)
	(segment
		(start 22.352 -247.0277)
		(end 22.352 -245.4402)
		(width 0.254)
		(layer "F.Cu")
		(net "P3V3_BS_NET")
	)
	(segment
		(start 20.7899 -245.4148)
		(end 20.8661 -245.3386)
		(width 0.254)
		(layer "F.Cu")
		(net "P3V3_BS_NET")
	)
	(via
		(at 22.2504 -245.3386)
		(size 0.7112)
		(drill 0.3556)
		(layers "F.Cu" "B.Cu")
		(net "P3V3_BS_NET")
	)
	(via
		(at 15.24 -245.5672)
		(size 0.7112)
		(drill 0.3556)
		(layers "F.Cu" "B.Cu")
		(net "P3V3_LX")
	)
	(via
		(at 16.9926 -246.1514)
		(size 0.7112)
		(drill 0.3556)
		(layers "F.Cu" "B.Cu")
		(net "P3V3_LX")
	)
	(via
		(at 18.542 -245.364)
		(size 0.7112)
		(drill 0.3556)
		(layers "F.Cu" "B.Cu")
		(net "P3V3_LX")
	)
	(segment
		(start 37.719 -375.793)
		(end 37.719 -374.4341)
		(width 0.508)
		(layer "F.Cu")
		(net "ADM1276_GATE_RSV")
	)
	(segment
		(start 37.719 -374.4341)
		(end 36.7411 -374.4341)
		(width 0.508)
		(layer "F.Cu")
		(net "ADM1276_GATE_RSV")
	)
	(segment
		(start 36.7411 -374.4341)
		(end 36.1442 -373.8372)
		(width 0.508)
		(layer "F.Cu")
		(net "ADM1276_GATE_RSV")
	)
	(via
		(at 37.719 -375.793)
		(size 0.7112)
		(drill 0.3556)
		(layers "F.Cu" "B.Cu")
		(net "ADM1276_GATE_RSV")
	)
	(segment
		(start 33.5915 -376.428)
		(end 34.52495 -376.428)
		(width 0.508)
		(layer "F.Cu")
		(net "ADM1276_GATE_RC")
	)
	(segment
		(start 34.671 -376.28195)
		(end 34.671 -375.92)
		(width 0.508)
		(layer "F.Cu")
		(net "ADM1276_GATE_RC")
	)
	(segment
		(start 34.671 -375.92)
		(end 33.909 -375.158)
		(width 0.508)
		(layer "F.Cu")
		(net "ADM1276_GATE_RC")
	)
	(segment
		(start 34.52495 -376.428)
		(end 34.671 -376.28195)
		(width 0.508)
		(layer "F.Cu")
		(net "ADM1276_GATE_RC")
	)
	(via
		(at 34.671 -376.28195)
		(size 0.7112)
		(drill 0.3556)
		(layers "F.Cu" "B.Cu")
		(net "ADM1276_GATE_RC")
	)
	(via
		(at 39.624 -401.828)
		(size 0.7112)
		(drill 0.4064)
		(layers "F.Cu" "B.Cu")
		(net "P12V_SENSE_TRACE")
	)
	(via
		(at 38.227 -404.114)
		(size 0.7112)
		(drill 0.4064)
		(layers "F.Cu" "B.Cu")
		(net "P12V_SENSE_TRACE")
	)
	(via
		(at 29.464 -402.336)
		(size 0.7112)
		(drill 0.4064)
		(layers "F.Cu" "B.Cu")
		(net "P12V_SENSE_TRACE")
	)
	(via
		(at 29.464 -406.4)
		(size 0.7112)
		(drill 0.4064)
		(layers "F.Cu" "B.Cu")
		(net "P12V_SENSE_TRACE")
	)
	(via
		(at 29.464 -409.448)
		(size 0.7112)
		(drill 0.4064)
		(layers "F.Cu" "B.Cu")
		(net "P12V_SENSE_TRACE")
	)
	(via
		(at 41.656 -407.924)
		(size 0.7112)
		(drill 0.4064)
		(layers "F.Cu" "B.Cu")
		(net "P12V_SENSE_TRACE")
	)
	(via
		(at 12.8524 -406.7302)
		(size 0.7112)
		(drill 0.4064)
		(layers "F.Cu" "B.Cu")
		(net "P12V_SENSE_TRACE")
	)
	(via
		(at 46.355 -402.463)
		(size 0.7112)
		(drill 0.4064)
		(layers "F.Cu" "B.Cu")
		(net "P12V_SENSE_TRACE")
	)
	(via
		(at 30.988 -402.336)
		(size 0.7112)
		(drill 0.4064)
		(layers "F.Cu" "B.Cu")
		(net "P12V_SENSE_TRACE")
	)
	(via
		(at 29.464 -404.368)
		(size 0.7112)
		(drill 0.4064)
		(layers "F.Cu" "B.Cu")
		(net "P12V_SENSE_TRACE")
	)
	(via
		(at 46.355 -404.368)
		(size 0.7112)
		(drill 0.4064)
		(layers "F.Cu" "B.Cu")
		(net "P12V_SENSE_TRACE")
	)
	(via
		(at 16.3576 -407.8986)
		(size 0.7112)
		(drill 0.3556)
		(layers "F.Cu" "B.Cu")
		(net "P12V_SENSE_TRACE")
	)
	(via
		(at 37.084 -409.448)
		(size 0.7112)
		(drill 0.4064)
		(layers "F.Cu" "B.Cu")
		(net "P12V_SENSE_TRACE")
	)
	(via
		(at 12.8524 -403.6822)
		(size 0.7112)
		(drill 0.4064)
		(layers "F.Cu" "B.Cu")
		(net "P12V_SENSE_TRACE")
	)
	(via
		(at 38.227 -401.828)
		(size 0.7112)
		(drill 0.4064)
		(layers "F.Cu" "B.Cu")
		(net "P12V_SENSE_TRACE")
	)
	(via
		(at 14.0462 -403.6314)
		(size 0.7112)
		(drill 0.4064)
		(layers "F.Cu" "B.Cu")
		(net "P12V_SENSE_TRACE")
	)
	(via
		(at 14.0716 -409.7782)
		(size 0.7112)
		(drill 0.4064)
		(layers "F.Cu" "B.Cu")
		(net "P12V_SENSE_TRACE")
	)
	(via
		(at 24.003 -407.797)
		(size 0.7112)
		(drill 0.4064)
		(layers "F.Cu" "B.Cu")
		(net "P12V_SENSE_TRACE")
	)
	(via
		(at 43.688 -407.924)
		(size 0.7112)
		(drill 0.4064)
		(layers "F.Cu" "B.Cu")
		(net "P12V_SENSE_TRACE")
	)
	(via
		(at 28.829 -407.797)
		(size 0.7112)
		(drill 0.4064)
		(layers "F.Cu" "B.Cu")
		(net "P12V_SENSE_TRACE")
	)
	(via
		(at 12.8524 -402.0312)
		(size 0.7112)
		(drill 0.4064)
		(layers "F.Cu" "B.Cu")
		(net "P12V_SENSE_TRACE")
	)
	(via
		(at 18.1864 -408.3558)
		(size 0.7112)
		(drill 0.4064)
		(layers "F.Cu" "B.Cu")
		(net "P12V_SENSE_TRACE")
	)
	(via
		(at 37.592 -407.924)
		(size 0.7112)
		(drill 0.4064)
		(layers "F.Cu" "B.Cu")
		(net "P12V_SENSE_TRACE")
	)
	(via
		(at 38.227 -406.4)
		(size 0.7112)
		(drill 0.4064)
		(layers "F.Cu" "B.Cu")
		(net "P12V_SENSE_TRACE")
	)
	(via
		(at 14.859 -408.3558)
		(size 0.7112)
		(drill 0.4064)
		(layers "F.Cu" "B.Cu")
		(net "P12V_SENSE_TRACE")
	)
	(via
		(at 39.624 -407.924)
		(size 0.7112)
		(drill 0.4064)
		(layers "F.Cu" "B.Cu")
		(net "P12V_SENSE_TRACE")
	)
	(via
		(at 14.0462 -401.9804)
		(size 0.7112)
		(drill 0.4064)
		(layers "F.Cu" "B.Cu")
		(net "P12V_SENSE_TRACE")
	)
	(via
		(at 35.179 -407.924)
		(size 0.7112)
		(drill 0.4064)
		(layers "F.Cu" "B.Cu")
		(net "P12V_SENSE_TRACE")
	)
	(via
		(at 12.8524 -405.2062)
		(size 0.7112)
		(drill 0.4064)
		(layers "F.Cu" "B.Cu")
		(net "P12V_SENSE_TRACE")
	)
	(via
		(at 32.512 -407.924)
		(size 0.7112)
		(drill 0.4064)
		(layers "F.Cu" "B.Cu")
		(net "P12V_SENSE_TRACE")
	)
	(via
		(at 14.0462 -405.1554)
		(size 0.7112)
		(drill 0.4064)
		(layers "F.Cu" "B.Cu")
		(net "P12V_SENSE_TRACE")
	)
	(via
		(at 46.355 -406.2476)
		(size 0.7112)
		(drill 0.4064)
		(layers "F.Cu" "B.Cu")
		(net "P12V_SENSE_TRACE")
	)
	(via
		(at 30.988 -406.4)
		(size 0.7112)
		(drill 0.4064)
		(layers "F.Cu" "B.Cu")
		(net "P12V_SENSE_TRACE")
	)
	(via
		(at 22.733 -408.94)
		(size 0.7112)
		(drill 0.3556)
		(layers "F.Cu" "B.Cu")
		(net "P12V_SENSE_TRACE")
	)
	(via
		(at 14.0462 -406.6794)
		(size 0.7112)
		(drill 0.4064)
		(layers "F.Cu" "B.Cu")
		(net "P12V_SENSE_TRACE")
	)
	(via
		(at 39.751 -406.4)
		(size 0.7112)
		(drill 0.4064)
		(layers "F.Cu" "B.Cu")
		(net "P12V_SENSE_TRACE")
	)
	(via
		(at 30.607 -407.924)
		(size 0.7112)
		(drill 0.3556)
		(layers "F.Cu" "B.Cu")
		(net "P12V_SENSE_TRACE")
	)
	(via
		(at 30.988 -404.368)
		(size 0.7112)
		(drill 0.4064)
		(layers "F.Cu" "B.Cu")
		(net "P12V_SENSE_TRACE")
	)
	(via
		(at 13.5382 -408.7368)
		(size 0.7112)
		(drill 0.3556)
		(layers "F.Cu" "B.Cu")
		(net "P12V_SENSE_TRACE")
	)
	(via
		(at 39.751 -404.114)
		(size 0.7112)
		(drill 0.4064)
		(layers "F.Cu" "B.Cu")
		(net "P12V_SENSE_TRACE")
	)
	(via
		(at 30.988 -409.448)
		(size 0.7112)
		(drill 0.4064)
		(layers "F.Cu" "B.Cu")
		(net "P12V_SENSE_TRACE")
	)
	(via
		(at 17.4498 -407.3906)
		(size 0.7112)
		(drill 0.4064)
		(layers "F.Cu" "B.Cu")
		(net "P12V_SENSE_TRACE")
	)
	(via
		(at 26.416 -407.797)
		(size 0.7112)
		(drill 0.4064)
		(layers "F.Cu" "B.Cu")
		(net "P12V_SENSE_TRACE")
	)
	(segment
		(start 33.3375 -377.8885)
		(end 33.06572 -377.61672)
		(width 0.508)
		(layer "F.Cu")
		(net "ADM1276_GATE")
	)
	(segment
		(start 37.211 -377.8885)
		(end 36.068 -377.8885)
		(width 0.508)
		(layer "F.Cu")
		(net "ADM1276_GATE")
	)
	(segment
		(start 32.766 -376.3645)
		(end 32.7025 -376.428)
		(width 0.508)
		(layer "F.Cu")
		(net "ADM1276_GATE")
	)
	(segment
		(start 32.7025 -377.2535)
		(end 32.7025 -376.428)
		(width 0.508)
		(layer "F.Cu")
		(net "ADM1276_GATE")
	)
	(segment
		(start 36.068 -377.8885)
		(end 35.0012 -377.8885)
		(width 0.508)
		(layer "F.Cu")
		(net "ADM1276_GATE")
	)
	(segment
		(start 38.354 -377.8885)
		(end 37.211 -377.8885)
		(width 0.508)
		(layer "F.Cu")
		(net "ADM1276_GATE")
	)
	(segment
		(start 35.0012 -377.8885)
		(end 33.3375 -377.8885)
		(width 0.508)
		(layer "F.Cu")
		(net "ADM1276_GATE")
	)
	(segment
		(start 35.0012 -377.8885)
		(end 35.0266 -377.8631)
		(width 0.508)
		(layer "F.Cu")
		(net "ADM1276_GATE")
	)
	(segment
		(start 36.1442 -376.1232)
		(end 36.1442 -377.8123)
		(width 0.508)
		(layer "F.Cu")
		(net "ADM1276_GATE")
	)
	(segment
		(start 32.766 -375.2215)
		(end 32.766 -376.3645)
		(width 0.508)
		(layer "F.Cu")
		(net "ADM1276_GATE")
	)
	(segment
		(start 33.06572 -377.61672)
		(end 32.7025 -377.2535)
		(width 0.508)
		(layer "F.Cu")
		(net "ADM1276_GATE")
	)
	(segment
		(start 36.1442 -377.8123)
		(end 36.068 -377.8885)
		(width 0.508)
		(layer "F.Cu")
		(net "ADM1276_GATE")
	)
	(via
		(at 33.06572 -377.61672)
		(size 0.7112)
		(drill 0.3556)
		(layers "F.Cu" "B.Cu")
		(net "ADM1276_GATE")
	)
	(segment
		(start 32.3342 -373.0752)
		(end 31.5976 -372.3386)
		(width 0.508)
		(layer "F.Cu")
		(net "ADM1276_GATE_DRV")
	)
	(segment
		(start 31.5976 -372.3386)
		(end 31.017972 -371.758972)
		(width 0.381)
		(layer "F.Cu")
		(net "ADM1276_GATE_DRV")
	)
	(segment
		(start 32.766 -373.507)
		(end 32.3342 -373.0752)
		(width 0.508)
		(layer "F.Cu")
		(net "ADM1276_GATE_DRV")
	)
	(segment
		(start 31.017972 -371.758972)
		(end 31.017972 -371.2464)
		(width 0.381)
		(layer "F.Cu")
		(net "ADM1276_GATE_DRV")
	)
	(segment
		(start 32.766 -374.3325)
		(end 32.766 -373.507)
		(width 0.508)
		(layer "F.Cu")
		(net "ADM1276_GATE_DRV")
	)
	(via
		(at 32.3342 -373.0752)
		(size 0.7112)
		(drill 0.3556)
		(layers "F.Cu" "B.Cu")
		(net "ADM1276_GATE_DRV")
	)
	(segment
		(start 31.75 -380.5555)
		(end 31.4325 -380.238)
		(width 0.254)
		(layer "F.Cu")
		(net "ADM1276_SENSE-")
	)
	(segment
		(start 33.782 -380.5555)
		(end 34.798 -380.5555)
		(width 0.254)
		(layer "F.Cu")
		(net "ADM1276_SENSE-")
	)
	(segment
		(start 30.367986 -375.680986)
		(end 30.367986 -371.2464)
		(width 0.254)
		(layer "F.Cu")
		(net "ADM1276_SENSE-")
	)
	(segment
		(start 35.7632 -380.5682)
		(end 34.8107 -380.5682)
		(width 0.254)
		(layer "F.Cu")
		(net "ADM1276_SENSE-")
	)
	(segment
		(start 32.766 -380.5555)
		(end 33.782 -380.5555)
		(width 0.254)
		(layer "F.Cu")
		(net "ADM1276_SENSE-")
	)
	(segment
		(start 31.4325 -376.7455)
		(end 30.367986 -375.680986)
		(width 0.254)
		(layer "F.Cu")
		(net "ADM1276_SENSE-")
	)
	(segment
		(start 31.75 -380.5555)
		(end 32.766 -380.5555)
		(width 0.254)
		(layer "F.Cu")
		(net "ADM1276_SENSE-")
	)
	(segment
		(start 31.4325 -380.238)
		(end 31.4325 -376.7455)
		(width 0.254)
		(layer "F.Cu")
		(net "ADM1276_SENSE-")
	)
	(segment
		(start 36.1696 -380.9746)
		(end 35.7632 -380.5682)
		(width 0.254)
		(layer "F.Cu")
		(net "ADM1276_SENSE-")
	)
	(segment
		(start 34.8107 -380.5682)
		(end 34.798 -380.5555)
		(width 0.254)
		(layer "F.Cu")
		(net "ADM1276_SENSE-")
	)
	(via
		(at 36.1696 -380.9746)
		(size 0.7112)
		(drill 0.3556)
		(layers "F.Cu" "B.Cu")
		(net "ADM1276_SENSE-")
	)
	(segment
		(start 26.500582 -380.534418)
		(end 27.664918 -380.534418)
		(width 0.254)
		(layer "F.Cu")
		(net "ADM1276_SENSE+")
	)
	(segment
		(start 27.686 -380.5555)
		(end 28.702 -380.5555)
		(width 0.254)
		(layer "F.Cu")
		(net "ADM1276_SENSE+")
	)
	(segment
		(start 29.718 -380.5555)
		(end 30.734 -380.5555)
		(width 0.254)
		(layer "F.Cu")
		(net "ADM1276_SENSE+")
	)
	(segment
		(start 28.702 -380.5555)
		(end 29.718 -380.5555)
		(width 0.254)
		(layer "F.Cu")
		(net "ADM1276_SENSE+")
	)
	(segment
		(start 29.718 -375.8692)
		(end 30.8102 -376.9614)
		(width 0.254)
		(layer "F.Cu")
		(net "ADM1276_SENSE+")
	)
	(segment
		(start 30.8102 -376.9614)
		(end 30.8102 -380.4793)
		(width 0.254)
		(layer "F.Cu")
		(net "ADM1276_SENSE+")
	)
	(segment
		(start 29.718 -371.2464)
		(end 29.718 -375.8692)
		(width 0.254)
		(layer "F.Cu")
		(net "ADM1276_SENSE+")
	)
	(segment
		(start 30.8102 -380.4793)
		(end 30.734 -380.5555)
		(width 0.254)
		(layer "F.Cu")
		(net "ADM1276_SENSE+")
	)
	(segment
		(start 27.664918 -380.534418)
		(end 27.686 -380.5555)
		(width 0.254)
		(layer "F.Cu")
		(net "ADM1276_SENSE+")
	)
	(via
		(at 26.500582 -380.534418)
		(size 0.7112)
		(drill 0.3556)
		(layers "F.Cu" "B.Cu")
		(net "ADM1276_SENSE+")
	)
	(segment
		(start 40.6019 -138.5824)
		(end 40.0812 -138.5824)
		(width 0.508)
		(layer "F.Cu")
		(net "P12VL_2490_GATE")
	)
	(segment
		(start 38.372288 -139.194032)
		(end 37.8968 -138.718544)
		(width 0.3048)
		(layer "F.Cu")
		(net "P12VL_2490_GATE")
	)
	(segment
		(start 49.3395 -110.5789)
		(end 49.3395 -111.633)
		(width 0.508)
		(layer "F.Cu")
		(net "P12VL_2490_GATE")
	)
	(segment
		(start 40.0812 -138.5824)
		(end 39.469568 -139.194032)
		(width 0.508)
		(layer "F.Cu")
		(net "P12VL_2490_GATE")
	)
	(segment
		(start 48.6156 -109.855)
		(end 49.3395 -110.5789)
		(width 0.508)
		(layer "F.Cu")
		(net "P12VL_2490_GATE")
	)
	(segment
		(start 38.1127 -109.4232)
		(end 37.73424 -109.4232)
		(width 0.508)
		(layer "F.Cu")
		(net "P12VL_2490_GATE")
	)
	(segment
		(start 48.6156 -109.83087)
		(end 48.6156 -109.855)
		(width 0.508)
		(layer "F.Cu")
		(net "P12VL_2490_GATE")
	)
	(segment
		(start 39.469568 -139.194032)
		(end 38.372288 -139.194032)
		(width 0.508)
		(layer "F.Cu")
		(net "P12VL_2490_GATE")
	)
	(segment
		(start 40.6019 -137.6172)
		(end 40.6019 -138.5824)
		(width 0.508)
		(layer "F.Cu")
		(net "P12VL_2490_GATE")
	)
	(segment
		(start 37.73424 -109.4232)
		(end 37.32784 -109.8296)
		(width 0.508)
		(layer "F.Cu")
		(net "P12VL_2490_GATE")
	)
	(segment
		(start 37.8968 -138.718544)
		(end 37.8968 -137.9093)
		(width 0.3048)
		(layer "F.Cu")
		(net "P12VL_2490_GATE")
	)
	(via
		(at 40.6019 -137.6172)
		(size 0.5588)
		(drill 0.3048)
		(layers "F.Cu" "B.Cu")
		(net "P12VL_2490_GATE")
	)
	(via
		(at 37.32784 -109.8296)
		(size 0.5588)
		(drill 0.3048)
		(layers "F.Cu" "B.Cu")
		(net "P12VL_2490_GATE")
	)
	(via
		(at 45.5422 -134.62)
		(size 0.7112)
		(drill 0.3556)
		(layers "F.Cu" "B.Cu")
		(net "P12VL_2490_GATE")
	)
	(via
		(at 48.6156 -109.83087)
		(size 0.5588)
		(drill 0.3048)
		(layers "F.Cu" "B.Cu")
		(net "P12VL_2490_GATE")
	)
	(segment
		(start 45.5422 -134.62)
		(end 45.57395 -134.58825)
		(width 0.508)
		(layer "B.Cu")
		(net "P12VL_2490_GATE")
	)
	(segment
		(start 42.545 -137.6172)
		(end 45.5422 -134.62)
		(width 0.508)
		(layer "B.Cu")
		(net "P12VL_2490_GATE")
	)
	(segment
		(start 48.6156 -111.3409)
		(end 48.6156 -109.83087)
		(width 0.508)
		(layer "B.Cu")
		(net "P12VL_2490_GATE")
	)
	(segment
		(start 40.6019 -137.6172)
		(end 42.545 -137.6172)
		(width 0.508)
		(layer "B.Cu")
		(net "P12VL_2490_GATE")
	)
	(segment
		(start 37.98824 -110.49)
		(end 37.32784 -109.8296)
		(width 0.508)
		(layer "B.Cu")
		(net "P12VL_2490_GATE")
	)
	(segment
		(start 48.6156 -109.83087)
		(end 48.5394 -109.90707)
		(width 0.508)
		(layer "B.Cu")
		(net "P12VL_2490_GATE")
	)
	(segment
		(start 45.57395 -114.38255)
		(end 48.6156 -111.3409)
		(width 0.508)
		(layer "B.Cu")
		(net "P12VL_2490_GATE")
	)
	(segment
		(start 48.5394 -110.040928)
		(end 48.090328 -110.49)
		(width 0.508)
		(layer "B.Cu")
		(net "P12VL_2490_GATE")
	)
	(segment
		(start 45.57395 -134.58825)
		(end 45.57395 -114.38255)
		(width 0.508)
		(layer "B.Cu")
		(net "P12VL_2490_GATE")
	)
	(segment
		(start 48.090328 -110.49)
		(end 37.98824 -110.49)
		(width 0.508)
		(layer "B.Cu")
		(net "P12VL_2490_GATE")
	)
	(segment
		(start 48.5394 -109.90707)
		(end 48.5394 -110.040928)
		(width 0.508)
		(layer "B.Cu")
		(net "P12VL_2490_GATE")
	)
	(segment
		(start 32.11195 -164.091366)
		(end 32.11195 -165.36035)
		(width 0.1397)
		(layer "F.Cu")
		(net "NCT7904_ADR")
	)
	(segment
		(start 32.11195 -165.36035)
		(end 32.766 -166.0144)
		(width 0.1397)
		(layer "F.Cu")
		(net "NCT7904_ADR")
	)
	(segment
		(start 33.91789 -167.279066)
		(end 34.981642 -167.279066)
		(width 0.1397)
		(layer "F.Cu")
		(net "NCT7904_ADR")
	)
	(segment
		(start 34.981642 -167.279066)
		(end 34.99231 -167.289734)
		(width 0.1397)
		(layer "F.Cu")
		(net "NCT7904_ADR")
	)
	(segment
		(start 32.766 -166.0144)
		(end 33.91789 -167.16629)
		(width 0.1397)
		(layer "F.Cu")
		(net "NCT7904_ADR")
	)
	(segment
		(start 33.91789 -167.16629)
		(end 33.91789 -167.279066)
		(width 0.1397)
		(layer "F.Cu")
		(net "NCT7904_ADR")
	)
	(via
		(at 32.766 -166.0144)
		(size 0.7112)
		(drill 0.3556)
		(layers "F.Cu" "B.Cu")
		(net "NCT7904_ADR")
	)
	(segment
		(start 16.396208 -14.364462)
		(end 14.251686 -12.21994)
		(width 0.1397)
		(layer "F.Cu")
		(net "FAN_TACH11")
	)
	(segment
		(start 18.237708 -14.350238)
		(end 19.293332 -14.350238)
		(width 0.1397)
		(layer "F.Cu")
		(net "FAN_TACH11")
	)
	(segment
		(start 19.293332 -14.350238)
		(end 19.800062 -13.843508)
		(width 0.1397)
		(layer "F.Cu")
		(net "FAN_TACH11")
	)
	(segment
		(start 14.251686 -12.21994)
		(end 4.040124 -12.21994)
		(width 0.1397)
		(layer "F.Cu")
		(net "FAN_TACH11")
	)
	(segment
		(start 17.271492 -14.364462)
		(end 16.396208 -14.364462)
		(width 0.1397)
		(layer "F.Cu")
		(net "FAN_TACH11")
	)
	(segment
		(start 17.271492 -14.364462)
		(end 18.223484 -14.364462)
		(width 0.1397)
		(layer "F.Cu")
		(net "FAN_TACH11")
	)
	(segment
		(start 19.823938 -13.867384)
		(end 19.800062 -13.843508)
		(width 0.1397)
		(layer "F.Cu")
		(net "FAN_TACH11")
	)
	(segment
		(start 18.223484 -14.364462)
		(end 18.237708 -14.350238)
		(width 0.1397)
		(layer "F.Cu")
		(net "FAN_TACH11")
	)
	(segment
		(start 19.823938 -15.595092)
		(end 19.823938 -13.867384)
		(width 0.1397)
		(layer "F.Cu")
		(net "FAN_TACH11")
	)
	(segment
		(start 24.3459 -17.399)
		(end 19.939 -17.399)
		(width 0.1397)
		(layer "F.Cu")
		(net "FAN_TACH12")
	)
	(segment
		(start 8.48614 -17.29994)
		(end 4.040124 -17.29994)
		(width 0.1397)
		(layer "F.Cu")
		(net "FAN_TACH12")
	)
	(segment
		(start 19.939 -17.399)
		(end 19.177 -18.161)
		(width 0.1397)
		(layer "F.Cu")
		(net "FAN_TACH12")
	)
	(segment
		(start 15.735554 -19.431)
		(end 10.6172 -19.431)
		(width 0.1397)
		(layer "F.Cu")
		(net "FAN_TACH12")
	)
	(segment
		(start 19.125184 -18.212816)
		(end 19.177 -18.161)
		(width 0.1397)
		(layer "F.Cu")
		(net "FAN_TACH12")
	)
	(segment
		(start 17.119092 -18.047462)
		(end 15.735554 -19.431)
		(width 0.1397)
		(layer "F.Cu")
		(net "FAN_TACH12")
	)
	(segment
		(start 18.1356 -18.212816)
		(end 17.284446 -18.212816)
		(width 0.1397)
		(layer "F.Cu")
		(net "FAN_TACH12")
	)
	(segment
		(start 17.284446 -18.212816)
		(end 17.119092 -18.047462)
		(width 0.1397)
		(layer "F.Cu")
		(net "FAN_TACH12")
	)
	(segment
		(start 18.1356 -18.212816)
		(end 19.125184 -18.212816)
		(width 0.1397)
		(layer "F.Cu")
		(net "FAN_TACH12")
	)
	(segment
		(start 10.6172 -19.431)
		(end 8.48614 -17.29994)
		(width 0.1397)
		(layer "F.Cu")
		(net "FAN_TACH12")
	)
	(segment
		(start 9.906 -147.6629)
		(end 8.89 -147.6629)
		(width 0.1397)
		(layer "F.Cu")
		(net "FAN_TACH10")
	)
	(segment
		(start 10.0076 -150.3426)
		(end 10.0076 -147.7645)
		(width 0.1397)
		(layer "F.Cu")
		(net "FAN_TACH10")
	)
	(segment
		(start 6.35635 -145.953226)
		(end 6.8834 -146.480276)
		(width 0.1397)
		(layer "F.Cu")
		(net "FAN_TACH10")
	)
	(segment
		(start 6.387592 -144.9832)
		(end 6.361684 -145.009108)
		(width 0.1397)
		(layer "F.Cu")
		(net "FAN_TACH10")
	)
	(segment
		(start 6.8834 -146.480276)
		(end 6.8834 -146.8374)
		(width 0.1397)
		(layer "F.Cu")
		(net "FAN_TACH10")
	)
	(segment
		(start 10.287 -150.622)
		(end 10.0076 -150.3426)
		(width 0.1397)
		(layer "F.Cu")
		(net "FAN_TACH10")
	)
	(segment
		(start 6.361684 -145.53184)
		(end 6.35635 -145.537174)
		(width 0.1397)
		(layer "F.Cu")
		(net "FAN_TACH10")
	)
	(segment
		(start 6.361684 -145.009108)
		(end 6.361684 -145.53184)
		(width 0.1397)
		(layer "F.Cu")
		(net "FAN_TACH10")
	)
	(segment
		(start 6.35635 -145.537174)
		(end 6.35635 -145.953226)
		(width 0.1397)
		(layer "F.Cu")
		(net "FAN_TACH10")
	)
	(segment
		(start 8.3439 -147.6629)
		(end 8.89 -147.6629)
		(width 0.1397)
		(layer "F.Cu")
		(net "FAN_TACH10")
	)
	(segment
		(start 11.4554 -150.6093)
		(end 11.4427 -150.622)
		(width 0.1397)
		(layer "F.Cu")
		(net "FAN_TACH10")
	)
	(segment
		(start 6.8834 -146.8374)
		(end 7.5184 -146.8374)
		(width 0.1397)
		(layer "F.Cu")
		(net "FAN_TACH10")
	)
	(segment
		(start 10.0076 -147.7645)
		(end 9.906 -147.6629)
		(width 0.1397)
		(layer "F.Cu")
		(net "FAN_TACH10")
	)
	(segment
		(start 11.4554 -148.1074)
		(end 11.4554 -150.6093)
		(width 0.1397)
		(layer "F.Cu")
		(net "FAN_TACH10")
	)
	(segment
		(start 7.5184 -146.8374)
		(end 8.3439 -147.6629)
		(width 0.1397)
		(layer "F.Cu")
		(net "FAN_TACH10")
	)
	(segment
		(start 11.4427 -150.622)
		(end 10.287 -150.622)
		(width 0.1397)
		(layer "F.Cu")
		(net "FAN_TACH10")
	)
	(via
		(at 6.8834 -146.8374)
		(size 0.7112)
		(drill 0.3556)
		(layers "F.Cu" "B.Cu")
		(net "FAN_TACH10")
	)
	(via
		(at 6.387592 -144.9832)
		(size 0.5588)
		(drill 0.3048)
		(layers "F.Cu" "B.Cu")
		(net "FAN_TACH10")
	)
	(segment
		(start 6.387592 -144.9832)
		(end 3.974084 -142.569692)
		(width 0.1397)
		(layer "B.Cu")
		(net "FAN_TACH10")
	)
	(segment
		(start 4.948174 -128.248156)
		(end 4.040124 -127.340106)
		(width 0.1397)
		(layer "B.Cu")
		(net "FAN_TACH10")
	)
	(segment
		(start 3.974084 -142.569692)
		(end 3.974084 -134.455916)
		(width 0.1397)
		(layer "B.Cu")
		(net "FAN_TACH10")
	)
	(segment
		(start 3.974084 -134.455916)
		(end 4.948174 -133.481826)
		(width 0.1397)
		(layer "B.Cu")
		(net "FAN_TACH10")
	)
	(segment
		(start 4.948174 -133.481826)
		(end 4.948174 -128.248156)
		(width 0.1397)
		(layer "B.Cu")
		(net "FAN_TACH10")
	)
	(segment
		(start 38.67531 -154.678634)
		(end 40.037258 -154.678634)
		(width 0.1397)
		(layer "F.Cu")
		(net "NCT7904_3VDD")
	)
	(segment
		(start 36.6776 -155.761944)
		(end 37.17671 -155.262834)
		(width 0.1397)
		(layer "F.Cu")
		(net "NCT7904_3VDD")
	)
	(segment
		(start 40.037258 -154.678634)
		(end 40.26789 -154.909266)
		(width 0.1397)
		(layer "F.Cu")
		(net "NCT7904_3VDD")
	)
	(segment
		(start 36.6776 -157.03804)
		(end 36.6776 -155.761944)
		(width 0.1397)
		(layer "F.Cu")
		(net "NCT7904_3VDD")
	)
	(segment
		(start 41.4274 -153.598118)
		(end 41.4274 -153.749756)
		(width 0.1397)
		(layer "F.Cu")
		(net "NCT7904_3VDD")
	)
	(segment
		(start 34.60369 -158.099506)
		(end 35.616134 -158.099506)
		(width 0.1397)
		(layer "F.Cu")
		(net "NCT7904_3VDD")
	)
	(segment
		(start 37.17671 -155.262834)
		(end 37.43706 -155.002484)
		(width 0.1397)
		(layer "F.Cu")
		(net "NCT7904_3VDD")
	)
	(segment
		(start 35.616134 -158.099506)
		(end 36.6776 -157.03804)
		(width 0.1397)
		(layer "F.Cu")
		(net "NCT7904_3VDD")
	)
	(segment
		(start 37.437314 -155.002484)
		(end 37.761164 -154.678634)
		(width 0.1397)
		(layer "F.Cu")
		(net "NCT7904_3VDD")
	)
	(segment
		(start 37.761164 -154.678634)
		(end 38.67531 -154.678634)
		(width 0.1397)
		(layer "F.Cu")
		(net "NCT7904_3VDD")
	)
	(segment
		(start 41.4274 -153.749756)
		(end 40.26789 -154.909266)
		(width 0.1397)
		(layer "F.Cu")
		(net "NCT7904_3VDD")
	)
	(segment
		(start 37.43706 -155.002484)
		(end 37.437314 -155.002484)
		(width 0.1397)
		(layer "F.Cu")
		(net "NCT7904_3VDD")
	)
	(via
		(at 41.4274 -153.598118)
		(size 0.7112)
		(drill 0.3556)
		(layers "F.Cu" "B.Cu")
		(net "NCT7904_3VDD")
	)
	(segment
		(start 5.91185 -144.671542)
		(end 5.911342 -144.67205)
		(width 0.1397)
		(layer "F.Cu")
		(net "FAN_TACH9")
	)
	(segment
		(start 5.9436 -146.169126)
		(end 5.9436 -146.670014)
		(width 0.1397)
		(layer "F.Cu")
		(net "FAN_TACH9")
	)
	(segment
		(start 5.91185 -146.137376)
		(end 5.9436 -146.169126)
		(width 0.1397)
		(layer "F.Cu")
		(net "FAN_TACH9")
	)
	(segment
		(start 16.4719 -146.6088)
		(end 16.3703 -146.6088)
		(width 0.1397)
		(layer "F.Cu")
		(net "FAN_TACH9")
	)
	(segment
		(start 5.911342 -145.29435)
		(end 5.91185 -145.294858)
		(width 0.1397)
		(layer "F.Cu")
		(net "FAN_TACH9")
	)
	(segment
		(start 18.1991 -149.1107)
		(end 18.1991 -148.336)
		(width 0.1397)
		(layer "F.Cu")
		(net "FAN_TACH9")
	)
	(segment
		(start 5.91185 -143.632428)
		(end 5.91185 -144.671542)
		(width 0.1397)
		(layer "F.Cu")
		(net "FAN_TACH9")
	)
	(segment
		(start 16.3703 -146.6088)
		(end 16.3703 -145.542)
		(width 0.1397)
		(layer "F.Cu")
		(net "FAN_TACH9")
	)
	(segment
		(start 16.129 -145.288)
		(end 13.741654 -142.900654)
		(width 0.1397)
		(layer "F.Cu")
		(net "FAN_TACH9")
	)
	(segment
		(start 17.1958 -150.114)
		(end 18.1991 -149.1107)
		(width 0.1397)
		(layer "F.Cu")
		(net "FAN_TACH9")
	)
	(segment
		(start 16.3703 -145.542)
		(end 16.129 -145.3007)
		(width 0.1397)
		(layer "F.Cu")
		(net "FAN_TACH9")
	)
	(segment
		(start 16.129 -145.3007)
		(end 16.129 -145.288)
		(width 0.1397)
		(layer "F.Cu")
		(net "FAN_TACH9")
	)
	(segment
		(start 5.91185 -145.294858)
		(end 5.91185 -146.137376)
		(width 0.1397)
		(layer "F.Cu")
		(net "FAN_TACH9")
	)
	(segment
		(start 18.1991 -148.336)
		(end 16.4719 -146.6088)
		(width 0.1397)
		(layer "F.Cu")
		(net "FAN_TACH9")
	)
	(segment
		(start 5.9436 -146.670014)
		(end 5.9563 -146.682714)
		(width 0.1397)
		(layer "F.Cu")
		(net "FAN_TACH9")
	)
	(segment
		(start 5.911342 -144.67205)
		(end 5.911342 -145.29435)
		(width 0.1397)
		(layer "F.Cu")
		(net "FAN_TACH9")
	)
	(segment
		(start 13.741654 -142.900654)
		(end 6.643624 -142.900654)
		(width 0.1397)
		(layer "F.Cu")
		(net "FAN_TACH9")
	)
	(segment
		(start 6.643624 -142.900654)
		(end 5.91185 -143.632428)
		(width 0.1397)
		(layer "F.Cu")
		(net "FAN_TACH9")
	)
	(via
		(at 5.9563 -146.682714)
		(size 0.5588)
		(drill 0.3048)
		(layers "F.Cu" "B.Cu")
		(net "FAN_TACH9")
	)
	(via
		(at 4.58089 -145.307304)
		(size 0.7112)
		(drill 0.3556)
		(layers "F.Cu" "B.Cu")
		(net "FAN_TACH9")
	)
	(segment
		(start 4.58089 -145.307304)
		(end 3.132074 -143.858488)
		(width 0.1397)
		(layer "B.Cu")
		(net "FAN_TACH9")
	)
	(segment
		(start 5.9563 -146.682714)
		(end 4.58089 -145.307304)
		(width 0.1397)
		(layer "B.Cu")
		(net "FAN_TACH9")
	)
	(segment
		(start 3.132074 -123.168156)
		(end 4.040124 -122.260106)
		(width 0.1397)
		(layer "B.Cu")
		(net "FAN_TACH9")
	)
	(segment
		(start 3.132074 -143.858488)
		(end 3.132074 -123.168156)
		(width 0.1397)
		(layer "B.Cu")
		(net "FAN_TACH9")
	)
	(segment
		(start 13.9827 -256.9972)
		(end 13.6652 -257.3147)
		(width 0.1397)
		(layer "F.Cu")
		(net "FAN_TACH5")
	)
	(segment
		(start 17.4371 -255.0922)
		(end 16.3068 -255.0922)
		(width 0.1397)
		(layer "F.Cu")
		(net "FAN_TACH5")
	)
	(segment
		(start 11.303 -258.191)
		(end 12.1793 -257.3147)
		(width 0.1397)
		(layer "F.Cu")
		(net "FAN_TACH5")
	)
	(segment
		(start 6.394958 -301.580042)
		(end 11.303 -296.672)
		(width 0.1397)
		(layer "F.Cu")
		(net "FAN_TACH5")
	)
	(segment
		(start 11.303 -296.672)
		(end 11.303 -258.191)
		(width 0.1397)
		(layer "F.Cu")
		(net "FAN_TACH5")
	)
	(segment
		(start 4.040124 -301.580042)
		(end 6.394958 -301.580042)
		(width 0.1397)
		(layer "F.Cu")
		(net "FAN_TACH5")
	)
	(segment
		(start 15.2781 -256.9972)
		(end 13.9827 -256.9972)
		(width 0.1397)
		(layer "F.Cu")
		(net "FAN_TACH5")
	)
	(segment
		(start 12.1793 -257.3147)
		(end 13.6652 -257.3147)
		(width 0.1397)
		(layer "F.Cu")
		(net "FAN_TACH5")
	)
	(segment
		(start 16.3068 -255.9685)
		(end 15.2781 -256.9972)
		(width 0.1397)
		(layer "F.Cu")
		(net "FAN_TACH5")
	)
	(segment
		(start 16.3068 -255.0922)
		(end 16.3068 -255.9685)
		(width 0.1397)
		(layer "F.Cu")
		(net "FAN_TACH5")
	)
	(segment
		(start 16.3703 -262.1534)
		(end 15.0749 -262.1534)
		(width 0.1397)
		(layer "F.Cu")
		(net "FAN_TACH6")
	)
	(segment
		(start 14.5415 -261.62)
		(end 14.7574 -261.8359)
		(width 0.1397)
		(layer "F.Cu")
		(net "FAN_TACH6")
	)
	(segment
		(start 16.3703 -262.1534)
		(end 16.3703 -261.2009)
		(width 0.1397)
		(layer "F.Cu")
		(net "FAN_TACH6")
	)
	(segment
		(start 16.3703 -261.2009)
		(end 17.2212 -260.35)
		(width 0.1397)
		(layer "F.Cu")
		(net "FAN_TACH6")
	)
	(segment
		(start 15.0749 -262.1534)
		(end 14.7574 -261.8359)
		(width 0.1397)
		(layer "F.Cu")
		(net "FAN_TACH6")
	)
	(segment
		(start 4.040124 -306.660042)
		(end 6.705854 -303.994312)
		(width 0.1397)
		(layer "F.Cu")
		(net "FAN_TACH6")
	)
	(segment
		(start 6.705854 -302.920654)
		(end 12.319 -297.307508)
		(width 0.1397)
		(layer "F.Cu")
		(net "FAN_TACH6")
	)
	(segment
		(start 13.97 -261.62)
		(end 14.5415 -261.62)
		(width 0.1397)
		(layer "F.Cu")
		(net "FAN_TACH6")
	)
	(segment
		(start 12.319 -263.271)
		(end 13.97 -261.62)
		(width 0.1397)
		(layer "F.Cu")
		(net "FAN_TACH6")
	)
	(segment
		(start 6.705854 -303.994312)
		(end 6.705854 -302.920654)
		(width 0.1397)
		(layer "F.Cu")
		(net "FAN_TACH6")
	)
	(segment
		(start 17.2212 -260.35)
		(end 18.2499 -260.35)
		(width 0.1397)
		(layer "F.Cu")
		(net "FAN_TACH6")
	)
	(segment
		(start 12.319 -297.307508)
		(end 12.319 -263.271)
		(width 0.1397)
		(layer "F.Cu")
		(net "FAN_TACH6")
	)
	(segment
		(start 18.2499 -260.35)
		(end 18.3515 -260.4516)
		(width 0.1397)
		(layer "F.Cu")
		(net "FAN_TACH6")
	)
	(segment
		(start 18.9738 -183.388)
		(end 16.51 -183.388)
		(width 0.1397)
		(layer "F.Cu")
		(net "FAN_TACH7")
	)
	(segment
		(start 19.2278 -183.134)
		(end 18.9738 -183.388)
		(width 0.1397)
		(layer "F.Cu")
		(net "FAN_TACH7")
	)
	(segment
		(start 20.7899 -181.7116)
		(end 20.7899 -179.9717)
		(width 0.1397)
		(layer "F.Cu")
		(net "FAN_TACH7")
	)
	(segment
		(start 20.828 -179.9336)
		(end 22.1615 -179.9336)
		(width 0.1397)
		(layer "F.Cu")
		(net "FAN_TACH7")
	)
	(segment
		(start 20.7899 -179.9717)
		(end 20.828 -179.9336)
		(width 0.1397)
		(layer "F.Cu")
		(net "FAN_TACH7")
	)
	(segment
		(start 12.954 -186.944)
		(end 5.356098 -186.944)
		(width 0.1397)
		(layer "F.Cu")
		(net "FAN_TACH7")
	)
	(segment
		(start 19.2278 -182.6387)
		(end 19.8628 -182.6387)
		(width 0.1397)
		(layer "F.Cu")
		(net "FAN_TACH7")
	)
	(segment
		(start 16.51 -183.388)
		(end 12.954 -186.944)
		(width 0.1397)
		(layer "F.Cu")
		(net "FAN_TACH7")
	)
	(segment
		(start 19.8628 -182.6387)
		(end 20.7899 -181.7116)
		(width 0.1397)
		(layer "F.Cu")
		(net "FAN_TACH7")
	)
	(segment
		(start 22.1615 -179.9336)
		(end 22.2885 -179.8066)
		(width 0.1397)
		(layer "F.Cu")
		(net "FAN_TACH7")
	)
	(segment
		(start 5.356098 -186.944)
		(end 4.040124 -188.259974)
		(width 0.1397)
		(layer "F.Cu")
		(net "FAN_TACH7")
	)
	(segment
		(start 19.2278 -182.6387)
		(end 19.2278 -183.134)
		(width 0.1397)
		(layer "F.Cu")
		(net "FAN_TACH7")
	)
	(segment
		(start 20.6629 -188.0616)
		(end 19.3675 -188.0616)
		(width 0.1397)
		(layer "F.Cu")
		(net "FAN_TACH8")
	)
	(segment
		(start 17.145 -189.23)
		(end 18.1991 -189.23)
		(width 0.1397)
		(layer "F.Cu")
		(net "FAN_TACH8")
	)
	(segment
		(start 5.923026 -193.339974)
		(end 7.758176 -191.504824)
		(width 0.1397)
		(layer "F.Cu")
		(net "FAN_TACH8")
	)
	(segment
		(start 19.3675 -188.0616)
		(end 19.1008 -188.3283)
		(width 0.1397)
		(layer "F.Cu")
		(net "FAN_TACH8")
	)
	(segment
		(start 4.040124 -193.339974)
		(end 5.923026 -193.339974)
		(width 0.1397)
		(layer "F.Cu")
		(net "FAN_TACH8")
	)
	(segment
		(start 7.758176 -191.504824)
		(end 14.870176 -191.504824)
		(width 0.1397)
		(layer "F.Cu")
		(net "FAN_TACH8")
	)
	(segment
		(start 20.6629 -186.3217)
		(end 20.701 -186.2836)
		(width 0.1397)
		(layer "F.Cu")
		(net "FAN_TACH8")
	)
	(segment
		(start 14.870176 -191.504824)
		(end 17.145 -189.23)
		(width 0.1397)
		(layer "F.Cu")
		(net "FAN_TACH8")
	)
	(segment
		(start 20.6629 -188.0616)
		(end 20.6629 -186.3217)
		(width 0.1397)
		(layer "F.Cu")
		(net "FAN_TACH8")
	)
	(segment
		(start 20.701 -186.2836)
		(end 21.9075 -186.2836)
		(width 0.1397)
		(layer "F.Cu")
		(net "FAN_TACH8")
	)
	(segment
		(start 18.1991 -189.23)
		(end 19.1008 -188.3283)
		(width 0.1397)
		(layer "F.Cu")
		(net "FAN_TACH8")
	)
	(segment
		(start 22.0853 -290.828222)
		(end 18.583402 -294.33012)
		(width 0.1397)
		(layer "F.Cu")
		(net "FAN_TACH4")
	)
	(segment
		(start 22.479508 -289.343592)
		(end 22.0853 -289.7378)
		(width 0.1397)
		(layer "F.Cu")
		(net "FAN_TACH4")
	)
	(segment
		(start 22.0853 -289.7378)
		(end 22.0853 -290.322)
		(width 0.1397)
		(layer "F.Cu")
		(net "FAN_TACH4")
	)
	(segment
		(start 22.479508 -288.606738)
		(end 22.479508 -289.343592)
		(width 0.1397)
		(layer "F.Cu")
		(net "FAN_TACH4")
	)
	(segment
		(start 21.388832 -287.516062)
		(end 20.675092 -287.516062)
		(width 0.1397)
		(layer "F.Cu")
		(net "FAN_TACH4")
	)
	(segment
		(start 20.700492 -287.490662)
		(end 20.675092 -287.516062)
		(width 0.1397)
		(layer "F.Cu")
		(net "FAN_TACH4")
	)
	(segment
		(start 22.0853 -290.322)
		(end 22.0853 -290.828222)
		(width 0.1397)
		(layer "F.Cu")
		(net "FAN_TACH4")
	)
	(segment
		(start 20.675092 -286.042862)
		(end 20.700492 -286.068262)
		(width 0.1397)
		(layer "F.Cu")
		(net "FAN_TACH4")
	)
	(segment
		(start 22.479508 -288.606738)
		(end 21.388832 -287.516062)
		(width 0.1397)
		(layer "F.Cu")
		(net "FAN_TACH4")
	)
	(segment
		(start 20.700492 -286.068262)
		(end 20.700492 -287.490662)
		(width 0.1397)
		(layer "F.Cu")
		(net "FAN_TACH4")
	)
	(via
		(at 18.583402 -294.33012)
		(size 0.5588)
		(drill 0.3048)
		(layers "F.Cu" "B.Cu")
		(net "FAN_TACH4")
	)
	(segment
		(start 18.583402 -337.321398)
		(end 18.583402 -294.33012)
		(width 0.1397)
		(layer "B.Cu")
		(net "FAN_TACH4")
	)
	(segment
		(start 4.948174 -371.75186)
		(end 4.948174 -365.297974)
		(width 0.1397)
		(layer "B.Cu")
		(net "FAN_TACH4")
	)
	(segment
		(start 4.040124 -372.65991)
		(end 4.948174 -371.75186)
		(width 0.1397)
		(layer "B.Cu")
		(net "FAN_TACH4")
	)
	(segment
		(start 4.948174 -365.297974)
		(end 3.974084 -364.323884)
		(width 0.1397)
		(layer "B.Cu")
		(net "FAN_TACH4")
	)
	(segment
		(start 3.974084 -351.930716)
		(end 18.583402 -337.321398)
		(width 0.1397)
		(layer "B.Cu")
		(net "FAN_TACH4")
	)
	(segment
		(start 3.974084 -364.323884)
		(end 3.974084 -351.930716)
		(width 0.1397)
		(layer "B.Cu")
		(net "FAN_TACH4")
	)
	(segment
		(start 16.053308 -286.549338)
		(end 16.85798 -287.35401)
		(width 0.1397)
		(layer "F.Cu")
		(net "FAN_TACH3")
	)
	(segment
		(start 17.831308 -290.462208)
		(end 17.831308 -289.140138)
		(width 0.1397)
		(layer "F.Cu")
		(net "FAN_TACH3")
	)
	(segment
		(start 17.907 -295.021)
		(end 17.907 -290.8681)
		(width 0.1397)
		(layer "F.Cu")
		(net "FAN_TACH3")
	)
	(segment
		(start 17.831308 -287.861502)
		(end 17.831308 -289.140138)
		(width 0.1397)
		(layer "F.Cu")
		(net "FAN_TACH3")
	)
	(segment
		(start 17.907 -290.8681)
		(end 18.0721 -290.703)
		(width 0.1397)
		(layer "F.Cu")
		(net "FAN_TACH3")
	)
	(segment
		(start 16.053308 -285.533846)
		(end 16.053308 -286.549338)
		(width 0.1397)
		(layer "F.Cu")
		(net "FAN_TACH3")
	)
	(segment
		(start 17.323816 -287.35401)
		(end 17.831308 -287.861502)
		(width 0.1397)
		(layer "F.Cu")
		(net "FAN_TACH3")
	)
	(segment
		(start 16.85798 -287.35401)
		(end 17.323816 -287.35401)
		(width 0.1397)
		(layer "F.Cu")
		(net "FAN_TACH3")
	)
	(segment
		(start 18.0721 -290.703)
		(end 17.831308 -290.462208)
		(width 0.1397)
		(layer "F.Cu")
		(net "FAN_TACH3")
	)
	(segment
		(start 16.128492 -285.458662)
		(end 16.053308 -285.533846)
		(width 0.1397)
		(layer "F.Cu")
		(net "FAN_TACH3")
	)
	(via
		(at 17.907 -295.021)
		(size 0.5588)
		(drill 0.3048)
		(layers "F.Cu" "B.Cu")
		(net "FAN_TACH3")
	)
	(via
		(at 7.731252 -347.360748)
		(size 0.7112)
		(drill 0.3556)
		(layers "F.Cu" "B.Cu")
		(net "FAN_TACH3")
	)
	(segment
		(start 3.529584 -351.689416)
		(end 7.731252 -347.487748)
		(width 0.1397)
		(layer "B.Cu")
		(net "FAN_TACH3")
	)
	(segment
		(start 17.907 -295.021)
		(end 17.907 -296.912792)
		(width 0.1397)
		(layer "B.Cu")
		(net "FAN_TACH3")
	)
	(segment
		(start 17.97685 -299.207174)
		(end 17.97685 -337.11515)
		(width 0.1397)
		(layer "B.Cu")
		(net "FAN_TACH3")
	)
	(segment
		(start 17.97685 -337.11515)
		(end 7.731252 -347.360748)
		(width 0.1397)
		(layer "B.Cu")
		(net "FAN_TACH3")
	)
	(segment
		(start 7.731252 -347.487748)
		(end 7.731252 -347.360748)
		(width 0.1397)
		(layer "B.Cu")
		(net "FAN_TACH3")
	)
	(segment
		(start 3.529584 -367.06937)
		(end 3.529584 -351.689416)
		(width 0.1397)
		(layer "B.Cu")
		(net "FAN_TACH3")
	)
	(segment
		(start 17.907 -296.912792)
		(end 17.58315 -297.236642)
		(width 0.1397)
		(layer "B.Cu")
		(net "FAN_TACH3")
	)
	(segment
		(start 17.58315 -298.813474)
		(end 17.97685 -299.207174)
		(width 0.1397)
		(layer "B.Cu")
		(net "FAN_TACH3")
	)
	(segment
		(start 17.58315 -297.236642)
		(end 17.58315 -298.813474)
		(width 0.1397)
		(layer "B.Cu")
		(net "FAN_TACH3")
	)
	(segment
		(start 4.040124 -367.57991)
		(end 3.529584 -367.06937)
		(width 0.1397)
		(layer "B.Cu")
		(net "FAN_TACH3")
	)
	(segment
		(start 12.2555 -445.9732)
		(end 12.2682 -445.9605)
		(width 0.1397)
		(layer "F.Cu")
		(net "FAN_TACH2")
	)
	(segment
		(start 12.2555 -447.1162)
		(end 12.2555 -448.1703)
		(width 0.1397)
		(layer "F.Cu")
		(net "FAN_TACH2")
	)
	(segment
		(start 14.732 -458.851)
		(end 14.478 -458.597)
		(width 0.1397)
		(layer "F.Cu")
		(net "FAN_TACH2")
	)
	(segment
		(start 10.9728 -452.2978)
		(end 11.4681 -452.7931)
		(width 0.1397)
		(layer "F.Cu")
		(net "FAN_TACH2")
	)
	(segment
		(start 11.5062 -449.1228)
		(end 11.5062 -450.2404)
		(width 0.1397)
		(layer "F.Cu")
		(net "FAN_TACH2")
	)
	(segment
		(start 5.9182 -480.822)
		(end 7.874 -480.822)
		(width 0.1397)
		(layer "F.Cu")
		(net "FAN_TACH2")
	)
	(segment
		(start 4.040124 -482.700076)
		(end 5.9182 -480.822)
		(width 0.1397)
		(layer "F.Cu")
		(net "FAN_TACH2")
	)
	(segment
		(start 10.5664 -448.9577)
		(end 10.5664 -447.5734)
		(width 0.1397)
		(layer "F.Cu")
		(net "FAN_TACH2")
	)
	(segment
		(start 10.5664 -447.5734)
		(end 11.6078 -446.532)
		(width 0.1397)
		(layer "F.Cu")
		(net "FAN_TACH2")
	)
	(segment
		(start 12.2555 -447.1162)
		(end 12.2555 -445.9732)
		(width 0.1397)
		(layer "F.Cu")
		(net "FAN_TACH2")
	)
	(segment
		(start 7.874 -480.822)
		(end 14.732 -473.964)
		(width 0.1397)
		(layer "F.Cu")
		(net "FAN_TACH2")
	)
	(segment
		(start 12.319 -448.31)
		(end 11.5062 -449.1228)
		(width 0.1397)
		(layer "F.Cu")
		(net "FAN_TACH2")
	)
	(segment
		(start 14.732 -473.964)
		(end 14.732 -458.851)
		(width 0.1397)
		(layer "F.Cu")
		(net "FAN_TACH2")
	)
	(segment
		(start 11.6078 -446.532)
		(end 11.6967 -446.532)
		(width 0.1397)
		(layer "F.Cu")
		(net "FAN_TACH2")
	)
	(segment
		(start 11.4681 -455.5871)
		(end 14.478 -458.597)
		(width 0.1397)
		(layer "F.Cu")
		(net "FAN_TACH2")
	)
	(segment
		(start 11.4681 -452.7931)
		(end 11.4681 -455.5871)
		(width 0.1397)
		(layer "F.Cu")
		(net "FAN_TACH2")
	)
	(segment
		(start 11.6967 -446.532)
		(end 12.2555 -445.9732)
		(width 0.1397)
		(layer "F.Cu")
		(net "FAN_TACH2")
	)
	(segment
		(start 12.319 -448.2338)
		(end 12.319 -448.31)
		(width 0.1397)
		(layer "F.Cu")
		(net "FAN_TACH2")
	)
	(segment
		(start 10.9728 -450.7738)
		(end 10.9728 -452.2978)
		(width 0.1397)
		(layer "F.Cu")
		(net "FAN_TACH2")
	)
	(segment
		(start 11.5062 -450.2404)
		(end 10.9728 -450.7738)
		(width 0.1397)
		(layer "F.Cu")
		(net "FAN_TACH2")
	)
	(segment
		(start 12.2555 -448.1703)
		(end 12.319 -448.2338)
		(width 0.1397)
		(layer "F.Cu")
		(net "FAN_TACH2")
	)
	(via
		(at 14.478 -458.597)
		(size 0.7112)
		(drill 0.3556)
		(layers "F.Cu" "B.Cu")
		(net "FAN_TACH2")
	)
	(segment
		(start 5.094224 -450.644006)
		(end 5.082794 -450.644006)
		(width 0.1397)
		(layer "F.Cu")
		(net "FAN_TACH1")
	)
	(segment
		(start 8.0264 -450.4563)
		(end 7.7851 -450.6976)
		(width 0.1397)
		(layer "F.Cu")
		(net "FAN_TACH1")
	)
	(segment
		(start 7.0866 -452.374)
		(end 5.4229 -452.374)
		(width 0.1397)
		(layer "F.Cu")
		(net "FAN_TACH1")
	)
	(segment
		(start 7.6835 -452.9709)
		(end 7.0866 -452.374)
		(width 0.1397)
		(layer "F.Cu")
		(net "FAN_TACH1")
	)
	(segment
		(start 8.0264 -450.4436)
		(end 8.0264 -450.4563)
		(width 0.1397)
		(layer "F.Cu")
		(net "FAN_TACH1")
	)
	(segment
		(start 9.597898 -455.747374)
		(end 9.621774 -455.747374)
		(width 0.1397)
		(layer "F.Cu")
		(net "FAN_TACH1")
	)
	(segment
		(start 13.7287 -473.368624)
		(end 7.545324 -479.552)
		(width 0.1397)
		(layer "F.Cu")
		(net "FAN_TACH1")
	)
	(segment
		(start 4.826 -450.9008)
		(end 4.826 -451.7771)
		(width 0.1397)
		(layer "F.Cu")
		(net "FAN_TACH1")
	)
	(segment
		(start 5.147818 -450.6976)
		(end 5.094224 -450.644006)
		(width 0.1397)
		(layer "F.Cu")
		(net "FAN_TACH1")
	)
	(segment
		(start 7.951724 -454.1012)
		(end 9.597898 -455.747374)
		(width 0.1397)
		(layer "F.Cu")
		(net "FAN_TACH1")
	)
	(segment
		(start 8.5852 -449.8848)
		(end 8.0264 -450.4436)
		(width 0.1397)
		(layer "F.Cu")
		(net "FAN_TACH1")
	)
	(segment
		(start 7.545324 -479.552)
		(end 5.972048 -479.552)
		(width 0.1397)
		(layer "F.Cu")
		(net "FAN_TACH1")
	)
	(segment
		(start 8.5852 -449.5546)
		(end 8.5852 -449.8848)
		(width 0.1397)
		(layer "F.Cu")
		(net "FAN_TACH1")
	)
	(segment
		(start 7.6835 -454.1012)
		(end 7.951724 -454.1012)
		(width 0.1397)
		(layer "F.Cu")
		(net "FAN_TACH1")
	)
	(segment
		(start 9.621774 -455.747374)
		(end 13.7287 -459.8543)
		(width 0.1397)
		(layer "F.Cu")
		(net "FAN_TACH1")
	)
	(segment
		(start 7.7851 -450.6976)
		(end 5.147818 -450.6976)
		(width 0.1397)
		(layer "F.Cu")
		(net "FAN_TACH1")
	)
	(segment
		(start 13.7287 -459.8543)
		(end 13.7287 -473.368624)
		(width 0.1397)
		(layer "F.Cu")
		(net "FAN_TACH1")
	)
	(segment
		(start 5.972048 -479.552)
		(end 4.040124 -477.620076)
		(width 0.1397)
		(layer "F.Cu")
		(net "FAN_TACH1")
	)
	(segment
		(start 4.826 -451.7771)
		(end 5.4229 -452.374)
		(width 0.1397)
		(layer "F.Cu")
		(net "FAN_TACH1")
	)
	(segment
		(start 5.082794 -450.644006)
		(end 4.826 -450.9008)
		(width 0.1397)
		(layer "F.Cu")
		(net "FAN_TACH1")
	)
	(segment
		(start 7.6835 -454.1012)
		(end 7.6835 -452.9709)
		(width 0.1397)
		(layer "F.Cu")
		(net "FAN_TACH1")
	)
	(via
		(at 5.094224 -450.644006)
		(size 0.7112)
		(drill 0.3556)
		(layers "F.Cu" "B.Cu")
		(net "FAN_TACH1")
	)
	(segment
		(start 32.25165 -361.89285)
		(end 32.25165 -364.5916)
		(width 0.1397)
		(layer "F.Cu")
		(net "I2C_C_SCL_ADM1276")
	)
	(segment
		(start 32.25165 -364.5916)
		(end 32.25165 -367.374678)
		(width 0.1397)
		(layer "F.Cu")
		(net "I2C_C_SCL_ADM1276")
	)
	(segment
		(start 32.385 -361.7595)
		(end 32.25165 -361.89285)
		(width 0.1397)
		(layer "F.Cu")
		(net "I2C_C_SCL_ADM1276")
	)
	(segment
		(start 32.261302 -367.403126)
		(end 32.1564 -367.508028)
		(width 0.1397)
		(layer "F.Cu")
		(net "I2C_C_SCL_ADM1276")
	)
	(segment
		(start 32.261302 -367.38433)
		(end 32.261302 -367.403126)
		(width 0.1397)
		(layer "F.Cu")
		(net "I2C_C_SCL_ADM1276")
	)
	(segment
		(start 32.25165 -367.374678)
		(end 32.261302 -367.38433)
		(width 0.1397)
		(layer "F.Cu")
		(net "I2C_C_SCL_ADM1276")
	)
	(via
		(at 32.25165 -364.5916)
		(size 0.7112)
		(drill 0.3556)
		(layers "F.Cu" "B.Cu")
		(net "I2C_C_SCL_ADM1276")
	)
	(segment
		(start 31.242 -363.5502)
		(end 31.242 -366.145572)
		(width 0.1397)
		(layer "F.Cu")
		(net "I2C_C_SDA_ADM1276")
	)
	(segment
		(start 31.242 -366.145572)
		(end 31.017972 -366.3696)
		(width 0.1397)
		(layer "F.Cu")
		(net "I2C_C_SDA_ADM1276")
	)
	(segment
		(start 31.242 -361.7595)
		(end 31.242 -363.5502)
		(width 0.1397)
		(layer "F.Cu")
		(net "I2C_C_SDA_ADM1276")
	)
	(via
		(at 31.242 -363.5502)
		(size 0.7112)
		(drill 0.3556)
		(layers "F.Cu" "B.Cu")
		(net "I2C_C_SDA_ADM1276")
	)
	(segment
		(start 31.0642 -146.05)
		(end 30.453838 -146.05)
		(width 0.508)
		(layer "F.Cu")
		(net "P12VL")
	)
	(segment
		(start 36.919916 -72.879966)
		(end 37.999924 -72.879966)
		(width 0.635)
		(layer "F.Cu")
		(net "P12VL")
	)
	(segment
		(start 37.09162 -136.6012)
		(end 37.39642 -136.906)
		(width 0.3048)
		(layer "F.Cu")
		(net "P12VL")
	)
	(segment
		(start 41.999916 -70.339966)
		(end 43.079924 -70.339966)
		(width 0.635)
		(layer "F.Cu")
		(net "P12VL")
	)
	(segment
		(start 34.741866 -137.063734)
		(end 35.2044 -136.6012)
		(width 0.3048)
		(layer "F.Cu")
		(net "P12VL")
	)
	(segment
		(start 40.539924 -65.259966)
		(end 40.539924 -66.339974)
		(width 0.635)
		(layer "F.Cu")
		(net "P12VL")
	)
	(segment
		(start 30.453838 -146.05)
		(end 29.6672 -146.836638)
		(width 0.508)
		(layer "F.Cu")
		(net "P12VL")
	)
	(segment
		(start 43.079924 -66.719958)
		(end 43.079924 -67.799966)
		(width 0.635)
		(layer "F.Cu")
		(net "P12VL")
	)
	(segment
		(start 40.539924 -70.339966)
		(end 40.539924 -71.419974)
		(width 0.635)
		(layer "F.Cu")
		(net "P12VL")
	)
	(segment
		(start 40.539924 -72.879966)
		(end 41.619932 -72.879966)
		(width 0.635)
		(layer "F.Cu")
		(net "P12VL")
	)
	(segment
		(start 43.079924 -67.799966)
		(end 43.079924 -68.879974)
		(width 0.635)
		(layer "F.Cu")
		(net "P12VL")
	)
	(segment
		(start 34.741866 -137.063734)
		(end 33.655 -137.063734)
		(width 0.508)
		(layer "F.Cu")
		(net "P12VL")
	)
	(segment
		(start 36.919916 -65.259966)
		(end 37.999924 -65.259966)
		(width 0.635)
		(layer "F.Cu")
		(net "P12VL")
	)
	(segment
		(start 36.919916 -70.339966)
		(end 37.999924 -70.339966)
		(width 0.635)
		(layer "F.Cu")
		(net "P12VL")
	)
	(segment
		(start 37.999924 -65.259966)
		(end 37.999924 -66.339974)
		(width 0.635)
		(layer "F.Cu")
		(net "P12VL")
	)
	(segment
		(start 41.999916 -72.879966)
		(end 43.079924 -72.879966)
		(width 0.635)
		(layer "F.Cu")
		(net "P12VL")
	)
	(segment
		(start 37.999924 -64.179958)
		(end 37.999924 -65.259966)
		(width 0.635)
		(layer "F.Cu")
		(net "P12VL")
	)
	(segment
		(start 44.539916 -72.879966)
		(end 45.619924 -72.879966)
		(width 0.635)
		(layer "F.Cu")
		(net "P12VL")
	)
	(segment
		(start 40.539924 -69.259958)
		(end 40.539924 -70.339966)
		(width 0.635)
		(layer "F.Cu")
		(net "P12VL")
	)
	(segment
		(start 43.079924 -72.879966)
		(end 43.079924 -73.959974)
		(width 0.635)
		(layer "F.Cu")
		(net "P12VL")
	)
	(segment
		(start 35.2044 -136.6012)
		(end 37.09162 -136.6012)
		(width 0.3048)
		(layer "F.Cu")
		(net "P12VL")
	)
	(segment
		(start 39.459916 -65.259966)
		(end 40.539924 -65.259966)
		(width 0.635)
		(layer "F.Cu")
		(net "P12VL")
	)
	(segment
		(start 37.999924 -71.799958)
		(end 37.999924 -72.879966)
		(width 0.635)
		(layer "F.Cu")
		(net "P12VL")
	)
	(segment
		(start 45.619924 -64.179958)
		(end 45.619924 -65.259966)
		(width 0.635)
		(layer "F.Cu")
		(net "P12VL")
	)
	(segment
		(start 37.999924 -70.339966)
		(end 39.079932 -70.339966)
		(width 0.635)
		(layer "F.Cu")
		(net "P12VL")
	)
	(segment
		(start 44.539916 -67.799966)
		(end 45.619924 -67.799966)
		(width 0.635)
		(layer "F.Cu")
		(net "P12VL")
	)
	(segment
		(start 40.539924 -67.799966)
		(end 41.619932 -67.799966)
		(width 0.635)
		(layer "F.Cu")
		(net "P12VL")
	)
	(segment
		(start 39.459916 -67.799966)
		(end 40.539924 -67.799966)
		(width 0.635)
		(layer "F.Cu")
		(net "P12VL")
	)
	(segment
		(start 45.619924 -66.719958)
		(end 45.619924 -67.799966)
		(width 0.635)
		(layer "F.Cu")
		(net "P12VL")
	)
	(segment
		(start 43.079924 -72.879966)
		(end 44.159932 -72.879966)
		(width 0.635)
		(layer "F.Cu")
		(net "P12VL")
	)
	(segment
		(start 45.619924 -72.879966)
		(end 45.619924 -73.959974)
		(width 0.635)
		(layer "F.Cu")
		(net "P12VL")
	)
	(segment
		(start 40.539924 -67.799966)
		(end 40.539924 -68.879974)
		(width 0.635)
		(layer "F.Cu")
		(net "P12VL")
	)
	(segment
		(start 43.079924 -70.339966)
		(end 44.159932 -70.339966)
		(width 0.635)
		(layer "F.Cu")
		(net "P12VL")
	)
	(segment
		(start 40.539924 -71.799958)
		(end 40.539924 -72.879966)
		(width 0.635)
		(layer "F.Cu")
		(net "P12VL")
	)
	(segment
		(start 44.539916 -65.259966)
		(end 45.619924 -65.259966)
		(width 0.635)
		(layer "F.Cu")
		(net "P12VL")
	)
	(segment
		(start 45.619924 -67.799966)
		(end 46.699932 -67.799966)
		(width 0.635)
		(layer "F.Cu")
		(net "P12VL")
	)
	(segment
		(start 40.539924 -66.719958)
		(end 40.539924 -67.799966)
		(width 0.635)
		(layer "F.Cu")
		(net "P12VL")
	)
	(segment
		(start 45.619924 -72.879966)
		(end 46.699932 -72.879966)
		(width 0.635)
		(layer "F.Cu")
		(net "P12VL")
	)
	(segment
		(start 40.539924 -65.259966)
		(end 41.619932 -65.259966)
		(width 0.635)
		(layer "F.Cu")
		(net "P12VL")
	)
	(segment
		(start 29.6672 -146.836638)
		(end 29.6672 -148.627084)
		(width 0.508)
		(layer "F.Cu")
		(net "P12VL")
	)
	(segment
		(start 37.999924 -72.879966)
		(end 39.079932 -72.879966)
		(width 0.635)
		(layer "F.Cu")
		(net "P12VL")
	)
	(segment
		(start 40.539924 -64.179958)
		(end 40.539924 -65.259966)
		(width 0.635)
		(layer "F.Cu")
		(net "P12VL")
	)
	(segment
		(start 37.999924 -67.799966)
		(end 37.999924 -68.879974)
		(width 0.635)
		(layer "F.Cu")
		(net "P12VL")
	)
	(segment
		(start 37.999924 -69.259958)
		(end 37.999924 -70.339966)
		(width 0.635)
		(layer "F.Cu")
		(net "P12VL")
	)
	(segment
		(start 37.999924 -66.719958)
		(end 37.999924 -67.799966)
		(width 0.635)
		(layer "F.Cu")
		(net "P12VL")
	)
	(segment
		(start 41.999916 -65.259966)
		(end 43.079924 -65.259966)
		(width 0.635)
		(layer "F.Cu")
		(net "P12VL")
	)
	(segment
		(start 43.079924 -65.259966)
		(end 43.079924 -66.339974)
		(width 0.635)
		(layer "F.Cu")
		(net "P12VL")
	)
	(segment
		(start 37.999924 -65.259966)
		(end 39.079932 -65.259966)
		(width 0.635)
		(layer "F.Cu")
		(net "P12VL")
	)
	(segment
		(start 44.539916 -70.339966)
		(end 45.619924 -70.339966)
		(width 0.635)
		(layer "F.Cu")
		(net "P12VL")
	)
	(segment
		(start 37.999924 -70.339966)
		(end 37.999924 -71.419974)
		(width 0.635)
		(layer "F.Cu")
		(net "P12VL")
	)
	(segment
		(start 43.079924 -65.259966)
		(end 44.159932 -65.259966)
		(width 0.635)
		(layer "F.Cu")
		(net "P12VL")
	)
	(segment
		(start 45.619924 -71.799958)
		(end 45.619924 -72.879966)
		(width 0.635)
		(layer "F.Cu")
		(net "P12VL")
	)
	(segment
		(start 43.079924 -67.799966)
		(end 44.159932 -67.799966)
		(width 0.635)
		(layer "F.Cu")
		(net "P12VL")
	)
	(segment
		(start 39.459916 -70.339966)
		(end 40.539924 -70.339966)
		(width 0.635)
		(layer "F.Cu")
		(net "P12VL")
	)
	(segment
		(start 43.079924 -69.259958)
		(end 43.079924 -70.339966)
		(width 0.635)
		(layer "F.Cu")
		(net "P12VL")
	)
	(segment
		(start 43.079924 -64.179958)
		(end 43.079924 -65.259966)
		(width 0.635)
		(layer "F.Cu")
		(net "P12VL")
	)
	(segment
		(start 45.619924 -69.259958)
		(end 45.619924 -70.339966)
		(width 0.635)
		(layer "F.Cu")
		(net "P12VL")
	)
	(segment
		(start 45.619924 -67.799966)
		(end 45.619924 -68.879974)
		(width 0.635)
		(layer "F.Cu")
		(net "P12VL")
	)
	(segment
		(start 39.459916 -72.879966)
		(end 40.539924 -72.879966)
		(width 0.635)
		(layer "F.Cu")
		(net "P12VL")
	)
	(segment
		(start 37.999924 -72.879966)
		(end 37.999924 -73.959974)
		(width 0.635)
		(layer "F.Cu")
		(net "P12VL")
	)
	(segment
		(start 40.539924 -70.339966)
		(end 41.619932 -70.339966)
		(width 0.635)
		(layer "F.Cu")
		(net "P12VL")
	)
	(segment
		(start 37.39642 -136.906)
		(end 37.39642 -137.9093)
		(width 0.3048)
		(layer "F.Cu")
		(net "P12VL")
	)
	(segment
		(start 41.999916 -67.799966)
		(end 43.079924 -67.799966)
		(width 0.635)
		(layer "F.Cu")
		(net "P12VL")
	)
	(segment
		(start 45.619924 -70.339966)
		(end 46.699932 -70.339966)
		(width 0.635)
		(layer "F.Cu")
		(net "P12VL")
	)
	(segment
		(start 43.079924 -71.799958)
		(end 43.079924 -72.879966)
		(width 0.635)
		(layer "F.Cu")
		(net "P12VL")
	)
	(segment
		(start 37.999924 -67.799966)
		(end 39.079932 -67.799966)
		(width 0.635)
		(layer "F.Cu")
		(net "P12VL")
	)
	(segment
		(start 43.079924 -70.339966)
		(end 43.079924 -71.419974)
		(width 0.635)
		(layer "F.Cu")
		(net "P12VL")
	)
	(segment
		(start 40.539924 -72.879966)
		(end 40.539924 -73.959974)
		(width 0.635)
		(layer "F.Cu")
		(net "P12VL")
	)
	(segment
		(start 45.619924 -65.259966)
		(end 46.699932 -65.259966)
		(width 0.635)
		(layer "F.Cu")
		(net "P12VL")
	)
	(segment
		(start 36.919916 -67.799966)
		(end 37.999924 -67.799966)
		(width 0.635)
		(layer "F.Cu")
		(net "P12VL")
	)
	(segment
		(start 45.619924 -65.259966)
		(end 45.619924 -66.339974)
		(width 0.635)
		(layer "F.Cu")
		(net "P12VL")
	)
	(segment
		(start 45.619924 -70.339966)
		(end 45.619924 -71.419974)
		(width 0.635)
		(layer "F.Cu")
		(net "P12VL")
	)
	(via
		(at 36.4236 -80.9498)
		(size 0.7112)
		(drill 0.4064)
		(layers "F.Cu" "B.Cu")
		(net "P12VL")
	)
	(via
		(at 31.7754 -103.8606)
		(size 0.7112)
		(drill 0.3556)
		(layers "F.Cu" "B.Cu")
		(net "P12VL")
	)
	(via
		(at 36.068 -109.728)
		(size 0.7112)
		(drill 0.4064)
		(layers "F.Cu" "B.Cu")
		(net "P12VL")
	)
	(via
		(at 41.656 -80.264)
		(size 0.7112)
		(drill 0.4064)
		(layers "F.Cu" "B.Cu")
		(net "P12VL")
	)
	(via
		(at 31.0642 -146.05)
		(size 0.5588)
		(drill 0.3048)
		(layers "F.Cu" "B.Cu")
		(net "P12VL")
	)
	(via
		(at 38.1 -105.156)
		(size 0.7112)
		(drill 0.4064)
		(layers "F.Cu" "B.Cu")
		(net "P12VL")
	)
	(via
		(at 44.704 -76.708)
		(size 0.7112)
		(drill 0.4064)
		(layers "F.Cu" "B.Cu")
		(net "P12VL")
	)
	(via
		(at 31.115 -108.966)
		(size 0.7112)
		(drill 0.3556)
		(layers "F.Cu" "B.Cu")
		(net "P12VL")
	)
	(via
		(at 38.1 -102.616)
		(size 0.7112)
		(drill 0.4064)
		(layers "F.Cu" "B.Cu")
		(net "P12VL")
	)
	(via
		(at 34.036 -100.584)
		(size 0.7112)
		(drill 0.4064)
		(layers "F.Cu" "B.Cu")
		(net "P12VL")
	)
	(via
		(at 43.688 -75.184)
		(size 0.7112)
		(drill 0.4064)
		(layers "F.Cu" "B.Cu")
		(net "P12VL")
	)
	(via
		(at 29.972 -100.584)
		(size 0.7112)
		(drill 0.4064)
		(layers "F.Cu" "B.Cu")
		(net "P12VL")
	)
	(via
		(at 34.036 -98.044)
		(size 0.7112)
		(drill 0.4064)
		(layers "F.Cu" "B.Cu")
		(net "P12VL")
	)
	(via
		(at 36.068 -73.914)
		(size 0.7112)
		(drill 0.4064)
		(layers "F.Cu" "B.Cu")
		(net "P12VL")
	)
	(via
		(at 44.323 -109.728)
		(size 0.7112)
		(drill 0.4064)
		(layers "F.Cu" "B.Cu")
		(net "P12VL")
	)
	(via
		(at 33.655 -137.063734)
		(size 0.5588)
		(drill 0.3048)
		(layers "F.Cu" "B.Cu")
		(net "P12VL")
	)
	(via
		(at 29.972 -98.044)
		(size 0.7112)
		(drill 0.4064)
		(layers "F.Cu" "B.Cu")
		(net "P12VL")
	)
	(via
		(at 46.228 -75.184)
		(size 0.7112)
		(drill 0.4064)
		(layers "F.Cu" "B.Cu")
		(net "P12VL")
	)
	(via
		(at 46.228 -78.74)
		(size 0.7112)
		(drill 0.4064)
		(layers "F.Cu" "B.Cu")
		(net "P12VL")
	)
	(via
		(at 38.1 -98.044)
		(size 0.7112)
		(drill 0.4064)
		(layers "F.Cu" "B.Cu")
		(net "P12VL")
	)
	(via
		(at 36.3982 -87.2236)
		(size 0.7112)
		(drill 0.4064)
		(layers "F.Cu" "B.Cu")
		(net "P12VL")
	)
	(via
		(at 34.417 -112.014)
		(size 0.5588)
		(drill 0.3048)
		(layers "F.Cu" "B.Cu")
		(net "P12VL")
	)
	(via
		(at 41.148 -75.184)
		(size 0.7112)
		(drill 0.4064)
		(layers "F.Cu" "B.Cu")
		(net "P12VL")
	)
	(via
		(at 38.1 -107.696)
		(size 0.7112)
		(drill 0.4064)
		(layers "F.Cu" "B.Cu")
		(net "P12VL")
	)
	(via
		(at 33.02 -109.728)
		(size 0.7112)
		(drill 0.4064)
		(layers "F.Cu" "B.Cu")
		(net "P12VL")
	)
	(via
		(at 41.148 -109.728)
		(size 0.7112)
		(drill 0.4064)
		(layers "F.Cu" "B.Cu")
		(net "P12VL")
	)
	(via
		(at 42.164 -76.708)
		(size 0.7112)
		(drill 0.4064)
		(layers "F.Cu" "B.Cu")
		(net "P12VL")
	)
	(via
		(at 34.036 -107.696)
		(size 0.7112)
		(drill 0.4064)
		(layers "F.Cu" "B.Cu")
		(net "P12VL")
	)
	(via
		(at 29.972 -105.156)
		(size 0.7112)
		(drill 0.4064)
		(layers "F.Cu" "B.Cu")
		(net "P12VL")
	)
	(via
		(at 44.196 -80.264)
		(size 0.7112)
		(drill 0.4064)
		(layers "F.Cu" "B.Cu")
		(net "P12VL")
	)
	(via
		(at 36.4236 -103.6828)
		(size 0.7112)
		(drill 0.3556)
		(layers "F.Cu" "B.Cu")
		(net "P12VL")
	)
	(via
		(at 29.972 -107.696)
		(size 0.7112)
		(drill 0.4064)
		(layers "F.Cu" "B.Cu")
		(net "P12VL")
	)
	(via
		(at 46.736 -76.962)
		(size 0.7112)
		(drill 0.4064)
		(layers "F.Cu" "B.Cu")
		(net "P12VL")
	)
	(via
		(at 38.1 -100.584)
		(size 0.7112)
		(drill 0.4064)
		(layers "F.Cu" "B.Cu")
		(net "P12VL")
	)
	(via
		(at 38.4302 -75.7428)
		(size 0.7112)
		(drill 0.4064)
		(layers "F.Cu" "B.Cu")
		(net "P12VL")
	)
	(via
		(at 34.036 -102.743)
		(size 0.7112)
		(drill 0.4064)
		(layers "F.Cu" "B.Cu")
		(net "P12VL")
	)
	(via
		(at 36.957 -108.458)
		(size 0.7112)
		(drill 0.4064)
		(layers "F.Cu" "B.Cu")
		(net "P12VL")
	)
	(via
		(at 43.688 -78.74)
		(size 0.7112)
		(drill 0.4064)
		(layers "F.Cu" "B.Cu")
		(net "P12VL")
	)
	(via
		(at 34.036 -105.156)
		(size 0.7112)
		(drill 0.4064)
		(layers "F.Cu" "B.Cu")
		(net "P12VL")
	)
	(via
		(at 29.972 -102.616)
		(size 0.7112)
		(drill 0.4064)
		(layers "F.Cu" "B.Cu")
		(net "P12VL")
	)
	(segment
		(start 34.690558 -112.014)
		(end 37.7571 -115.080542)
		(width 0.508)
		(layer "B.Cu")
		(net "P12VL")
	)
	(segment
		(start 34.417 -112.014)
		(end 34.690558 -112.014)
		(width 0.508)
		(layer "B.Cu")
		(net "P12VL")
	)
	(segment
		(start 32.4866 -144.907)
		(end 32.4866 -138.232134)
		(width 0.508)
		(layer "B.Cu")
		(net "P12VL")
	)
	(segment
		(start 31.3436 -146.05)
		(end 32.4866 -144.907)
		(width 0.508)
		(layer "B.Cu")
		(net "P12VL")
	)
	(segment
		(start 37.7571 -115.080542)
		(end 37.7571 -132.961634)
		(width 0.508)
		(layer "B.Cu")
		(net "P12VL")
	)
	(segment
		(start 37.7571 -132.961634)
		(end 33.655 -137.063734)
		(width 0.508)
		(layer "B.Cu")
		(net "P12VL")
	)
	(segment
		(start 32.4866 -138.232134)
		(end 33.655 -137.063734)
		(width 0.508)
		(layer "B.Cu")
		(net "P12VL")
	)
	(segment
		(start 31.0642 -146.05)
		(end 31.3436 -146.05)
		(width 0.508)
		(layer "B.Cu")
		(net "P12VL")
	)
	(segment
		(start 27.040078 -67.799966)
		(end 28.120086 -67.799966)
		(width 0.635)
		(layer "F.Cu")
		(net "P12VU")
	)
	(segment
		(start 19.420078 -70.339966)
		(end 20.500086 -70.339966)
		(width 0.635)
		(layer "F.Cu")
		(net "P12VU")
	)
	(segment
		(start 20.500086 -66.719958)
		(end 20.500086 -67.799966)
		(width 0.635)
		(layer "F.Cu")
		(net "P12VU")
	)
	(segment
		(start 27.040078 -65.259966)
		(end 28.120086 -65.259966)
		(width 0.635)
		(layer "F.Cu")
		(net "P12VU")
	)
	(segment
		(start 25.580086 -67.799966)
		(end 26.660094 -67.799966)
		(width 0.635)
		(layer "F.Cu")
		(net "P12VU")
	)
	(segment
		(start 23.040086 -72.879966)
		(end 23.040086 -73.959974)
		(width 0.635)
		(layer "F.Cu")
		(net "P12VU")
	)
	(segment
		(start 23.040086 -66.719958)
		(end 23.040086 -67.799966)
		(width 0.635)
		(layer "F.Cu")
		(net "P12VU")
	)
	(segment
		(start 28.120086 -66.719958)
		(end 28.120086 -67.799966)
		(width 0.635)
		(layer "F.Cu")
		(net "P12VU")
	)
	(segment
		(start 28.120086 -70.339966)
		(end 29.200094 -70.339966)
		(width 0.635)
		(layer "F.Cu")
		(net "P12VU")
	)
	(segment
		(start 25.580086 -69.259958)
		(end 25.580086 -70.339966)
		(width 0.635)
		(layer "F.Cu")
		(net "P12VU")
	)
	(segment
		(start 28.120086 -67.799966)
		(end 29.200094 -67.799966)
		(width 0.635)
		(layer "F.Cu")
		(net "P12VU")
	)
	(segment
		(start 24.500078 -70.339966)
		(end 25.580086 -70.339966)
		(width 0.635)
		(layer "F.Cu")
		(net "P12VU")
	)
	(segment
		(start 28.120086 -65.259966)
		(end 28.120086 -66.339974)
		(width 0.635)
		(layer "F.Cu")
		(net "P12VU")
	)
	(segment
		(start 23.040086 -70.339966)
		(end 24.120094 -70.339966)
		(width 0.635)
		(layer "F.Cu")
		(net "P12VU")
	)
	(segment
		(start 20.500086 -72.879966)
		(end 21.580094 -72.879966)
		(width 0.635)
		(layer "F.Cu")
		(net "P12VU")
	)
	(segment
		(start 32.7406 -148.627084)
		(end 32.7406 -147.447)
		(width 0.508)
		(layer "F.Cu")
		(net "P12VU")
	)
	(segment
		(start 19.420078 -72.879966)
		(end 20.500086 -72.879966)
		(width 0.635)
		(layer "F.Cu")
		(net "P12VU")
	)
	(segment
		(start 24.500078 -65.259966)
		(end 25.580086 -65.259966)
		(width 0.635)
		(layer "F.Cu")
		(net "P12VU")
	)
	(segment
		(start 21.960078 -67.799966)
		(end 23.040086 -67.799966)
		(width 0.635)
		(layer "F.Cu")
		(net "P12VU")
	)
	(segment
		(start 27.040078 -70.339966)
		(end 28.120086 -70.339966)
		(width 0.635)
		(layer "F.Cu")
		(net "P12VU")
	)
	(segment
		(start 20.9931 -137.2362)
		(end 19.7612 -137.2362)
		(width 0.3048)
		(layer "F.Cu")
		(net "P12VU")
	)
	(segment
		(start 25.580086 -65.259966)
		(end 26.660094 -65.259966)
		(width 0.635)
		(layer "F.Cu")
		(net "P12VU")
	)
	(segment
		(start 23.040086 -70.339966)
		(end 23.040086 -71.419974)
		(width 0.635)
		(layer "F.Cu")
		(net "P12VU")
	)
	(segment
		(start 28.120086 -72.879966)
		(end 29.200094 -72.879966)
		(width 0.635)
		(layer "F.Cu")
		(net "P12VU")
	)
	(segment
		(start 23.040086 -65.259966)
		(end 24.120094 -65.259966)
		(width 0.635)
		(layer "F.Cu")
		(net "P12VU")
	)
	(segment
		(start 21.960078 -65.259966)
		(end 23.040086 -65.259966)
		(width 0.635)
		(layer "F.Cu")
		(net "P12VU")
	)
	(segment
		(start 20.500086 -69.259958)
		(end 20.500086 -70.339966)
		(width 0.635)
		(layer "F.Cu")
		(net "P12VU")
	)
	(segment
		(start 20.500086 -72.879966)
		(end 20.500086 -73.959974)
		(width 0.635)
		(layer "F.Cu")
		(net "P12VU")
	)
	(segment
		(start 25.580086 -70.339966)
		(end 26.660094 -70.339966)
		(width 0.635)
		(layer "F.Cu")
		(net "P12VU")
	)
	(segment
		(start 25.580086 -67.799966)
		(end 25.580086 -68.879974)
		(width 0.635)
		(layer "F.Cu")
		(net "P12VU")
	)
	(segment
		(start 23.040086 -67.799966)
		(end 24.120094 -67.799966)
		(width 0.635)
		(layer "F.Cu")
		(net "P12VU")
	)
	(segment
		(start 28.120086 -72.879966)
		(end 28.120086 -73.959974)
		(width 0.635)
		(layer "F.Cu")
		(net "P12VU")
	)
	(segment
		(start 25.580086 -71.799958)
		(end 25.580086 -72.879966)
		(width 0.635)
		(layer "F.Cu")
		(net "P12VU")
	)
	(segment
		(start 20.500086 -67.799966)
		(end 20.500086 -68.879974)
		(width 0.635)
		(layer "F.Cu")
		(net "P12VU")
	)
	(segment
		(start 20.500086 -71.799958)
		(end 20.500086 -72.879966)
		(width 0.635)
		(layer "F.Cu")
		(net "P12VU")
	)
	(segment
		(start 20.500086 -70.339966)
		(end 20.500086 -71.419974)
		(width 0.635)
		(layer "F.Cu")
		(net "P12VU")
	)
	(segment
		(start 23.040086 -72.879966)
		(end 24.120094 -72.879966)
		(width 0.635)
		(layer "F.Cu")
		(net "P12VU")
	)
	(segment
		(start 28.120086 -71.799958)
		(end 28.120086 -72.879966)
		(width 0.635)
		(layer "F.Cu")
		(net "P12VU")
	)
	(segment
		(start 20.500086 -65.259966)
		(end 20.500086 -66.339974)
		(width 0.635)
		(layer "F.Cu")
		(net "P12VU")
	)
	(segment
		(start 19.420078 -65.259966)
		(end 20.500086 -65.259966)
		(width 0.635)
		(layer "F.Cu")
		(net "P12VU")
	)
	(segment
		(start 25.580086 -72.879966)
		(end 25.580086 -73.959974)
		(width 0.635)
		(layer "F.Cu")
		(net "P12VU")
	)
	(segment
		(start 21.19122 -137.43432)
		(end 20.9931 -137.2362)
		(width 0.3048)
		(layer "F.Cu")
		(net "P12VU")
	)
	(segment
		(start 21.960078 -70.339966)
		(end 23.040086 -70.339966)
		(width 0.635)
		(layer "F.Cu")
		(net "P12VU")
	)
	(segment
		(start 23.040086 -71.799958)
		(end 23.040086 -72.879966)
		(width 0.635)
		(layer "F.Cu")
		(net "P12VU")
	)
	(segment
		(start 19.420078 -67.799966)
		(end 20.500086 -67.799966)
		(width 0.635)
		(layer "F.Cu")
		(net "P12VU")
	)
	(segment
		(start 27.040078 -72.879966)
		(end 28.120086 -72.879966)
		(width 0.635)
		(layer "F.Cu")
		(net "P12VU")
	)
	(segment
		(start 23.040086 -67.799966)
		(end 23.040086 -68.879974)
		(width 0.635)
		(layer "F.Cu")
		(net "P12VU")
	)
	(segment
		(start 18.7198 -137.1219)
		(end 18.8341 -137.2362)
		(width 0.3048)
		(layer "F.Cu")
		(net "P12VU")
	)
	(segment
		(start 24.500078 -67.799966)
		(end 25.580086 -67.799966)
		(width 0.635)
		(layer "F.Cu")
		(net "P12VU")
	)
	(segment
		(start 21.960078 -72.879966)
		(end 23.040086 -72.879966)
		(width 0.635)
		(layer "F.Cu")
		(net "P12VU")
	)
	(segment
		(start 25.580086 -72.879966)
		(end 26.660094 -72.879966)
		(width 0.635)
		(layer "F.Cu")
		(net "P12VU")
	)
	(segment
		(start 21.19122 -138.3665)
		(end 21.19122 -137.43432)
		(width 0.3048)
		(layer "F.Cu")
		(net "P12VU")
	)
	(segment
		(start 25.580086 -65.259966)
		(end 25.580086 -66.339974)
		(width 0.635)
		(layer "F.Cu")
		(net "P12VU")
	)
	(segment
		(start 18.8341 -137.2362)
		(end 19.7612 -137.2362)
		(width 0.3048)
		(layer "F.Cu")
		(net "P12VU")
	)
	(segment
		(start 24.500078 -72.879966)
		(end 25.580086 -72.879966)
		(width 0.635)
		(layer "F.Cu")
		(net "P12VU")
	)
	(segment
		(start 20.500086 -70.339966)
		(end 21.580094 -70.339966)
		(width 0.635)
		(layer "F.Cu")
		(net "P12VU")
	)
	(segment
		(start 23.040086 -69.259958)
		(end 23.040086 -70.339966)
		(width 0.635)
		(layer "F.Cu")
		(net "P12VU")
	)
	(segment
		(start 28.120086 -69.259958)
		(end 28.120086 -70.339966)
		(width 0.635)
		(layer "F.Cu")
		(net "P12VU")
	)
	(segment
		(start 28.120086 -67.799966)
		(end 28.120086 -68.879974)
		(width 0.635)
		(layer "F.Cu")
		(net "P12VU")
	)
	(segment
		(start 20.500086 -67.799966)
		(end 21.580094 -67.799966)
		(width 0.635)
		(layer "F.Cu")
		(net "P12VU")
	)
	(segment
		(start 23.040086 -65.259966)
		(end 23.040086 -66.339974)
		(width 0.635)
		(layer "F.Cu")
		(net "P12VU")
	)
	(segment
		(start 25.580086 -70.339966)
		(end 25.580086 -71.419974)
		(width 0.635)
		(layer "F.Cu")
		(net "P12VU")
	)
	(segment
		(start 20.500086 -65.259966)
		(end 21.580094 -65.259966)
		(width 0.635)
		(layer "F.Cu")
		(net "P12VU")
	)
	(segment
		(start 28.120086 -70.339966)
		(end 28.120086 -71.419974)
		(width 0.635)
		(layer "F.Cu")
		(net "P12VU")
	)
	(segment
		(start 25.580086 -66.719958)
		(end 25.580086 -67.799966)
		(width 0.635)
		(layer "F.Cu")
		(net "P12VU")
	)
	(via
		(at 15.9766 -104.8766)
		(size 0.7112)
		(drill 0.3556)
		(layers "F.Cu" "B.Cu")
		(net "P12VU")
	)
	(via
		(at 32.7406 -147.447)
		(size 0.5588)
		(drill 0.3048)
		(layers "F.Cu" "B.Cu")
		(net "P12VU")
	)
	(via
		(at 17.272 -79.248)
		(size 0.7112)
		(drill 0.4064)
		(layers "F.Cu" "B.Cu")
		(net "P12VU")
	)
	(via
		(at 16.764 -106.172)
		(size 0.7112)
		(drill 0.4064)
		(layers "F.Cu" "B.Cu")
		(net "P12VU")
	)
	(via
		(at 18.796 -99.06)
		(size 0.7112)
		(drill 0.4064)
		(layers "F.Cu" "B.Cu")
		(net "P12VU")
	)
	(via
		(at 19.7612 -137.2362)
		(size 0.5588)
		(drill 0.3048)
		(layers "F.Cu" "B.Cu")
		(net "P12VU")
	)
	(via
		(at 16.764 -108.204)
		(size 0.7112)
		(drill 0.4064)
		(layers "F.Cu" "B.Cu")
		(net "P12VU")
	)
	(via
		(at 17.272 -77.216)
		(size 0.7112)
		(drill 0.4064)
		(layers "F.Cu" "B.Cu")
		(net "P12VU")
	)
	(via
		(at 16.764 -101.6)
		(size 0.7112)
		(drill 0.4064)
		(layers "F.Cu" "B.Cu")
		(net "P12VU")
	)
	(via
		(at 26.924 -75.184)
		(size 0.7112)
		(drill 0.4064)
		(layers "F.Cu" "B.Cu")
		(net "P12VU")
	)
	(via
		(at 23.876 -77.216)
		(size 0.7112)
		(drill 0.4064)
		(layers "F.Cu" "B.Cu")
		(net "P12VU")
	)
	(via
		(at 26.416 -77.216)
		(size 0.7112)
		(drill 0.4064)
		(layers "F.Cu" "B.Cu")
		(net "P12VU")
	)
	(via
		(at 14.732 -99.06)
		(size 0.7112)
		(drill 0.4064)
		(layers "F.Cu" "B.Cu")
		(net "P12VU")
	)
	(via
		(at 18.796 -103.632)
		(size 0.7112)
		(drill 0.4064)
		(layers "F.Cu" "B.Cu")
		(net "P12VU")
	)
	(via
		(at 28.956 -75.184)
		(size 0.7112)
		(drill 0.4064)
		(layers "F.Cu" "B.Cu")
		(net "P12VU")
	)
	(via
		(at 17.272 -72.644)
		(size 0.7112)
		(drill 0.4064)
		(layers "F.Cu" "B.Cu")
		(net "P12VU")
	)
	(via
		(at 15.6718 -107.1626)
		(size 0.7112)
		(drill 0.3556)
		(layers "F.Cu" "B.Cu")
		(net "P12VU")
	)
	(via
		(at 14.732 -103.632)
		(size 0.7112)
		(drill 0.4064)
		(layers "F.Cu" "B.Cu")
		(net "P12VU")
	)
	(via
		(at 18.796 -106.172)
		(size 0.7112)
		(drill 0.4064)
		(layers "F.Cu" "B.Cu")
		(net "P12VU")
	)
	(via
		(at 24.384 -75.184)
		(size 0.7112)
		(drill 0.4064)
		(layers "F.Cu" "B.Cu")
		(net "P12VU")
	)
	(via
		(at 18.796 -101.6)
		(size 0.7112)
		(drill 0.4064)
		(layers "F.Cu" "B.Cu")
		(net "P12VU")
	)
	(via
		(at 16.764 -103.632)
		(size 0.7112)
		(drill 0.4064)
		(layers "F.Cu" "B.Cu")
		(net "P12VU")
	)
	(via
		(at 18.7198 -107.442)
		(size 0.7112)
		(drill 0.4064)
		(layers "F.Cu" "B.Cu")
		(net "P12VU")
	)
	(via
		(at 23.876 -79.248)
		(size 0.7112)
		(drill 0.4064)
		(layers "F.Cu" "B.Cu")
		(net "P12VU")
	)
	(via
		(at 16.764 -99.06)
		(size 0.7112)
		(drill 0.4064)
		(layers "F.Cu" "B.Cu")
		(net "P12VU")
	)
	(via
		(at 17.399 -110.3122)
		(size 0.7112)
		(drill 0.4064)
		(layers "F.Cu" "B.Cu")
		(net "P12VU")
	)
	(via
		(at 23.3426 -104.267)
		(size 0.7112)
		(drill 0.4064)
		(layers "F.Cu" "B.Cu")
		(net "P12VU")
	)
	(via
		(at 20.574 -104.267)
		(size 0.7112)
		(drill 0.4064)
		(layers "F.Cu" "B.Cu")
		(net "P12VU")
	)
	(via
		(at 21.9456 -104.267)
		(size 0.7112)
		(drill 0.4064)
		(layers "F.Cu" "B.Cu")
		(net "P12VU")
	)
	(via
		(at 15.8496 -109.3724)
		(size 0.7112)
		(drill 0.3556)
		(layers "F.Cu" "B.Cu")
		(net "P12VU")
	)
	(via
		(at 17.272 -81.28)
		(size 0.7112)
		(drill 0.4064)
		(layers "F.Cu" "B.Cu")
		(net "P12VU")
	)
	(via
		(at 14.7574 -109.7026)
		(size 0.7112)
		(drill 0.4064)
		(layers "F.Cu" "B.Cu")
		(net "P12VU")
	)
	(via
		(at 25.908 -79.248)
		(size 0.7112)
		(drill 0.4064)
		(layers "F.Cu" "B.Cu")
		(net "P12VU")
	)
	(via
		(at 19.304 -75.184)
		(size 0.7112)
		(drill 0.4064)
		(layers "F.Cu" "B.Cu")
		(net "P12VU")
	)
	(via
		(at 14.732 -108.204)
		(size 0.7112)
		(drill 0.4064)
		(layers "F.Cu" "B.Cu")
		(net "P12VU")
	)
	(via
		(at 17.272 -75.184)
		(size 0.7112)
		(drill 0.4064)
		(layers "F.Cu" "B.Cu")
		(net "P12VU")
	)
	(via
		(at 23.876 -81.28)
		(size 0.7112)
		(drill 0.4064)
		(layers "F.Cu" "B.Cu")
		(net "P12VU")
	)
	(via
		(at 14.732 -101.6)
		(size 0.7112)
		(drill 0.4064)
		(layers "F.Cu" "B.Cu")
		(net "P12VU")
	)
	(via
		(at 16.026384 -110.37316)
		(size 0.7112)
		(drill 0.4064)
		(layers "F.Cu" "B.Cu")
		(net "P12VU")
	)
	(via
		(at 21.844 -75.184)
		(size 0.7112)
		(drill 0.4064)
		(layers "F.Cu" "B.Cu")
		(net "P12VU")
	)
	(via
		(at 21.463 -109.982)
		(size 0.7112)
		(drill 0.4064)
		(layers "F.Cu" "B.Cu")
		(net "P12VU")
	)
	(via
		(at 16.0528 -97.8154)
		(size 0.7112)
		(drill 0.3556)
		(layers "F.Cu" "B.Cu")
		(net "P12VU")
	)
	(via
		(at 22.479 -108.331)
		(size 0.7112)
		(drill 0.4064)
		(layers "F.Cu" "B.Cu")
		(net "P12VU")
	)
	(via
		(at 14.732 -106.045)
		(size 0.7112)
		(drill 0.4064)
		(layers "F.Cu" "B.Cu")
		(net "P12VU")
	)
	(segment
		(start 19.05 -113.396776)
		(end 16.026384 -110.37316)
		(width 0.508)
		(layer "B.Cu")
		(net "P12VU")
	)
	(segment
		(start 19.771868 -134.564374)
		(end 19.05 -133.842506)
		(width 0.508)
		(layer "B.Cu")
		(net "P12VU")
	)
	(segment
		(start 19.7612 -137.2362)
		(end 19.7612 -135.185658)
		(width 0.508)
		(layer "B.Cu")
		(net "P12VU")
	)
	(segment
		(start 32.156654 -146.863054)
		(end 32.7406 -147.447)
		(width 0.508)
		(layer "B.Cu")
		(net "P12VU")
	)
	(segment
		(start 19.771868 -135.17499)
		(end 19.771868 -134.564374)
		(width 0.508)
		(layer "B.Cu")
		(net "P12VU")
	)
	(segment
		(start 19.7612 -135.185658)
		(end 19.771868 -135.17499)
		(width 0.508)
		(layer "B.Cu")
		(net "P12VU")
	)
	(segment
		(start 19.05 -133.842506)
		(end 19.05 -113.396776)
		(width 0.508)
		(layer "B.Cu")
		(net "P12VU")
	)
	(segment
		(start 28.575254 -146.863054)
		(end 32.156654 -146.863054)
		(width 0.508)
		(layer "B.Cu")
		(net "P12VU")
	)
	(segment
		(start 19.7612 -137.2362)
		(end 19.7612 -138.049)
		(width 0.508)
		(layer "B.Cu")
		(net "P12VU")
	)
	(segment
		(start 19.7612 -138.049)
		(end 28.575254 -146.863054)
		(width 0.508)
		(layer "B.Cu")
		(net "P12VU")
	)
	(segment
		(start 37.70249 -165.069266)
		(end 37.70249 -163.50869)
		(width 0.1397)
		(layer "F.Cu")
		(net "I2C_C_SCL_NCT7904")
	)
	(segment
		(start 36.293806 -162.100006)
		(end 34.60369 -162.100006)
		(width 0.1397)
		(layer "F.Cu")
		(net "I2C_C_SCL_NCT7904")
	)
	(segment
		(start 38.069266 -165.069266)
		(end 37.70249 -165.069266)
		(width 0.1397)
		(layer "F.Cu")
		(net "I2C_C_SCL_NCT7904")
	)
	(segment
		(start 38.9128 -165.9128)
		(end 38.069266 -165.069266)
		(width 0.1397)
		(layer "F.Cu")
		(net "I2C_C_SCL_NCT7904")
	)
	(segment
		(start 37.70249 -163.50869)
		(end 36.293806 -162.100006)
		(width 0.1397)
		(layer "F.Cu")
		(net "I2C_C_SCL_NCT7904")
	)
	(via
		(at 38.9128 -165.9128)
		(size 0.7112)
		(drill 0.3556)
		(layers "F.Cu" "B.Cu")
		(net "I2C_C_SCL_NCT7904")
	)
	(segment
		(start 36.877752 -165.069266)
		(end 36.63569 -165.069266)
		(width 0.1397)
		(layer "F.Cu")
		(net "I2C_C_SDA_NCT7904")
	)
	(segment
		(start 34.60369 -162.599116)
		(end 35.751516 -162.599116)
		(width 0.1397)
		(layer "F.Cu")
		(net "I2C_C_SDA_NCT7904")
	)
	(segment
		(start 36.8808 -163.7284)
		(end 37.181282 -164.028882)
		(width 0.1397)
		(layer "F.Cu")
		(net "I2C_C_SDA_NCT7904")
	)
	(segment
		(start 37.181282 -164.765736)
		(end 36.877752 -165.069266)
		(width 0.1397)
		(layer "F.Cu")
		(net "I2C_C_SDA_NCT7904")
	)
	(segment
		(start 35.751516 -162.599116)
		(end 36.8808 -163.7284)
		(width 0.1397)
		(layer "F.Cu")
		(net "I2C_C_SDA_NCT7904")
	)
	(segment
		(start 37.181282 -164.028882)
		(end 37.181282 -164.765736)
		(width 0.1397)
		(layer "F.Cu")
		(net "I2C_C_SDA_NCT7904")
	)
	(via
		(at 36.8808 -163.7284)
		(size 0.7112)
		(drill 0.3556)
		(layers "F.Cu" "B.Cu")
		(net "I2C_C_SDA_NCT7904")
	)
	(segment
		(start 36.195 -249.36196)
		(end 36.18484 -249.3518)
		(width 0.1397)
		(layer "F.Cu")
		(net "I2C_C_SCL_LEDDRV")
	)
	(segment
		(start 36.3474 -255.778)
		(end 35.8521 -255.2827)
		(width 0.1397)
		(layer "F.Cu")
		(net "I2C_C_SCL_LEDDRV")
	)
	(segment
		(start 36.195 -251.333)
		(end 36.195 -249.36196)
		(width 0.1397)
		(layer "F.Cu")
		(net "I2C_C_SCL_LEDDRV")
	)
	(segment
		(start 35.3314 -252.1966)
		(end 36.195 -251.333)
		(width 0.1397)
		(layer "F.Cu")
		(net "I2C_C_SCL_LEDDRV")
	)
	(segment
		(start 35.8521 -255.2827)
		(end 35.8521 -254.3175)
		(width 0.1397)
		(layer "F.Cu")
		(net "I2C_C_SCL_LEDDRV")
	)
	(segment
		(start 35.4457 -253.9111)
		(end 35.3314 -253.9111)
		(width 0.1397)
		(layer "F.Cu")
		(net "I2C_C_SCL_LEDDRV")
	)
	(segment
		(start 36.3474 -255.8034)
		(end 36.3474 -255.778)
		(width 0.1397)
		(layer "F.Cu")
		(net "I2C_C_SCL_LEDDRV")
	)
	(segment
		(start 35.3314 -253.9111)
		(end 35.3314 -252.1966)
		(width 0.1397)
		(layer "F.Cu")
		(net "I2C_C_SCL_LEDDRV")
	)
	(segment
		(start 35.8521 -254.3175)
		(end 35.4457 -253.9111)
		(width 0.1397)
		(layer "F.Cu")
		(net "I2C_C_SCL_LEDDRV")
	)
	(via
		(at 36.3474 -255.8034)
		(size 0.7112)
		(drill 0.3556)
		(layers "F.Cu" "B.Cu")
		(net "I2C_C_SCL_LEDDRV")
	)
	(segment
		(start 35.433 -241.935)
		(end 35.433 -241.681)
		(width 0.1397)
		(layer "F.Cu")
		(net "LED_DRV_A2")
	)
	(segment
		(start 35.433 -241.0079)
		(end 35.687 -240.7539)
		(width 0.1397)
		(layer "F.Cu")
		(net "LED_DRV_A2")
	)
	(segment
		(start 36.18484 -242.68684)
		(end 35.433 -241.935)
		(width 0.1397)
		(layer "F.Cu")
		(net "LED_DRV_A2")
	)
	(segment
		(start 36.18484 -243.713)
		(end 36.18484 -242.68684)
		(width 0.1397)
		(layer "F.Cu")
		(net "LED_DRV_A2")
	)
	(segment
		(start 35.433 -241.681)
		(end 35.433 -241.0079)
		(width 0.1397)
		(layer "F.Cu")
		(net "LED_DRV_A2")
	)
	(via
		(at 35.433 -241.681)
		(size 0.7112)
		(drill 0.3556)
		(layers "F.Cu" "B.Cu")
		(net "LED_DRV_A2")
	)
	(segment
		(start 35.433 -242.57)
		(end 35.5346 -242.6716)
		(width 0.1397)
		(layer "F.Cu")
		(net "LED_DRV_A1")
	)
	(segment
		(start 33.909 -241.3889)
		(end 34.544 -240.7539)
		(width 0.1397)
		(layer "F.Cu")
		(net "LED_DRV_A1")
	)
	(segment
		(start 34.417 -242.57)
		(end 35.433 -242.57)
		(width 0.1397)
		(layer "F.Cu")
		(net "LED_DRV_A1")
	)
	(segment
		(start 35.5346 -242.6716)
		(end 35.5346 -243.713)
		(width 0.1397)
		(layer "F.Cu")
		(net "LED_DRV_A1")
	)
	(segment
		(start 33.909 -242.062)
		(end 33.909 -241.3889)
		(width 0.1397)
		(layer "F.Cu")
		(net "LED_DRV_A1")
	)
	(segment
		(start 33.909 -242.062)
		(end 34.417 -242.57)
		(width 0.1397)
		(layer "F.Cu")
		(net "LED_DRV_A1")
	)
	(via
		(at 33.909 -242.062)
		(size 0.7112)
		(drill 0.3556)
		(layers "F.Cu" "B.Cu")
		(net "LED_DRV_A1")
	)
	(segment
		(start 33.02 -243.14785)
		(end 33.249362 -243.377212)
		(width 0.1397)
		(layer "F.Cu")
		(net "LED_DRV_A0")
	)
	(segment
		(start 33.249362 -243.434362)
		(end 33.528 -243.713)
		(width 0.1397)
		(layer "F.Cu")
		(net "LED_DRV_A0")
	)
	(segment
		(start 33.528 -243.713)
		(end 34.88436 -243.713)
		(width 0.1397)
		(layer "F.Cu")
		(net "LED_DRV_A0")
	)
	(segment
		(start 33.02 -241.554)
		(end 33.02 -243.14785)
		(width 0.1397)
		(layer "F.Cu")
		(net "LED_DRV_A0")
	)
	(segment
		(start 33.401 -240.7539)
		(end 33.401 -241.173)
		(width 0.1397)
		(layer "F.Cu")
		(net "LED_DRV_A0")
	)
	(segment
		(start 33.249362 -243.377212)
		(end 33.249362 -243.434362)
		(width 0.1397)
		(layer "F.Cu")
		(net "LED_DRV_A0")
	)
	(segment
		(start 33.401 -241.173)
		(end 33.02 -241.554)
		(width 0.1397)
		(layer "F.Cu")
		(net "LED_DRV_A0")
	)
	(via
		(at 33.249362 -243.377212)
		(size 0.7112)
		(drill 0.3556)
		(layers "F.Cu" "B.Cu")
		(net "LED_DRV_A0")
	)
	(segment
		(start 45.085 -400.177)
		(end 45.085 -398.653)
		(width 0.508)
		(layer "F.Cu")
		(net "ADM1276_GATE_DRV3")
	)
	(segment
		(start 38.354 -379.476)
		(end 38.989 -380.111)
		(width 0.508)
		(layer "F.Cu")
		(net "ADM1276_GATE_DRV3")
	)
	(segment
		(start 38.354 -378.7775)
		(end 38.354 -379.476)
		(width 0.508)
		(layer "F.Cu")
		(net "ADM1276_GATE_DRV3")
	)
	(via
		(at 39.878 -388.112)
		(size 0.7112)
		(drill 0.3556)
		(layers "F.Cu" "B.Cu")
		(net "ADM1276_GATE_DRV3")
	)
	(via
		(at 38.989 -380.111)
		(size 0.5588)
		(drill 0.3048)
		(layers "F.Cu" "B.Cu")
		(net "ADM1276_GATE_DRV3")
	)
	(via
		(at 45.085 -398.653)
		(size 0.5588)
		(drill 0.3048)
		(layers "F.Cu" "B.Cu")
		(net "ADM1276_GATE_DRV3")
	)
	(segment
		(start 45.085 -398.653)
		(end 44.043092 -398.653)
		(width 0.508)
		(layer "B.Cu")
		(net "ADM1276_GATE_DRV3")
	)
	(segment
		(start 39.878 -381)
		(end 39.878 -388.112)
		(width 0.508)
		(layer "B.Cu")
		(net "ADM1276_GATE_DRV3")
	)
	(segment
		(start 39.878 -394.487908)
		(end 39.878 -388.112)
		(width 0.508)
		(layer "B.Cu")
		(net "ADM1276_GATE_DRV3")
	)
	(segment
		(start 38.989 -380.111)
		(end 39.878 -381)
		(width 0.508)
		(layer "B.Cu")
		(net "ADM1276_GATE_DRV3")
	)
	(segment
		(start 44.043092 -398.653)
		(end 39.878 -394.487908)
		(width 0.508)
		(layer "B.Cu")
		(net "ADM1276_GATE_DRV3")
	)
	(segment
		(start 36.449 -398.154652)
		(end 36.453572 -398.15008)
		(width 0.508)
		(layer "F.Cu")
		(net "ADM1276_GATE_DRV2")
	)
	(segment
		(start 36.449 -400.177)
		(end 36.449 -398.154652)
		(width 0.508)
		(layer "F.Cu")
		(net "ADM1276_GATE_DRV2")
	)
	(segment
		(start 37.211 -378.7775)
		(end 37.211 -380.238)
		(width 0.508)
		(layer "F.Cu")
		(net "ADM1276_GATE_DRV2")
	)
	(segment
		(start 37.211 -380.238)
		(end 37.465 -380.492)
		(width 0.508)
		(layer "F.Cu")
		(net "ADM1276_GATE_DRV2")
	)
	(via
		(at 37.465 -380.492)
		(size 0.5588)
		(drill 0.3048)
		(layers "F.Cu" "B.Cu")
		(net "ADM1276_GATE_DRV2")
	)
	(via
		(at 37.465 -382.27)
		(size 0.7112)
		(drill 0.3556)
		(layers "F.Cu" "B.Cu")
		(net "ADM1276_GATE_DRV2")
	)
	(via
		(at 36.453572 -391.16)
		(size 0.7112)
		(drill 0.3556)
		(layers "F.Cu" "B.Cu")
		(net "ADM1276_GATE_DRV2")
	)
	(via
		(at 36.453572 -398.15008)
		(size 0.5588)
		(drill 0.3048)
		(layers "F.Cu" "B.Cu")
		(net "ADM1276_GATE_DRV2")
	)
	(segment
		(start 37.465 -386.461)
		(end 37.465 -382.27)
		(width 0.508)
		(layer "B.Cu")
		(net "ADM1276_GATE_DRV2")
	)
	(segment
		(start 37.465 -380.492)
		(end 37.465 -382.27)
		(width 0.508)
		(layer "B.Cu")
		(net "ADM1276_GATE_DRV2")
	)
	(segment
		(start 36.453572 -398.15008)
		(end 36.453572 -391.16)
		(width 0.508)
		(layer "B.Cu")
		(net "ADM1276_GATE_DRV2")
	)
	(segment
		(start 36.453572 -391.16)
		(end 36.453572 -387.472428)
		(width 0.508)
		(layer "B.Cu")
		(net "ADM1276_GATE_DRV2")
	)
	(segment
		(start 36.453572 -387.472428)
		(end 37.465 -386.461)
		(width 0.508)
		(layer "B.Cu")
		(net "ADM1276_GATE_DRV2")
	)
	(segment
		(start 31.4579 -253.5936)
		(end 32.4358 -253.5936)
		(width 0.1397)
		(layer "F.Cu")
		(net "I2C_C_SDA_EEPROM")
	)
	(segment
		(start 30.89656 -253.03226)
		(end 31.3182 -253.4539)
		(width 0.1397)
		(layer "F.Cu")
		(net "I2C_C_SDA_EEPROM")
	)
	(segment
		(start 31.3182 -253.4539)
		(end 31.4579 -253.5936)
		(width 0.1397)
		(layer "F.Cu")
		(net "I2C_C_SDA_EEPROM")
	)
	(segment
		(start 30.89656 -250.2408)
		(end 30.89656 -253.03226)
		(width 0.1397)
		(layer "F.Cu")
		(net "I2C_C_SDA_EEPROM")
	)
	(via
		(at 32.4358 -253.5936)
		(size 0.7112)
		(drill 0.3556)
		(layers "F.Cu" "B.Cu")
		(net "I2C_C_SDA_EEPROM")
	)
	(segment
		(start 27.559 -400.177)
		(end 27.559 -398.526)
		(width 0.508)
		(layer "F.Cu")
		(net "ADM1276_GATE_DRV1")
	)
	(segment
		(start 36.068 -378.7775)
		(end 36.068 -379.6792)
		(width 0.508)
		(layer "F.Cu")
		(net "ADM1276_GATE_DRV1")
	)
	(via
		(at 27.559 -395.351)
		(size 0.7112)
		(drill 0.3556)
		(layers "F.Cu" "B.Cu")
		(net "ADM1276_GATE_DRV1")
	)
	(via
		(at 36.068 -379.6792)
		(size 0.5588)
		(drill 0.3048)
		(layers "F.Cu" "B.Cu")
		(net "ADM1276_GATE_DRV1")
	)
	(via
		(at 34.036 -385.953)
		(size 0.7112)
		(drill 0.3556)
		(layers "F.Cu" "B.Cu")
		(net "ADM1276_GATE_DRV1")
	)
	(via
		(at 27.559 -398.526)
		(size 0.5588)
		(drill 0.3048)
		(layers "F.Cu" "B.Cu")
		(net "ADM1276_GATE_DRV1")
	)
	(segment
		(start 34.0106 -385.953)
		(end 34.036 -385.953)
		(width 0.508)
		(layer "B.Cu")
		(net "ADM1276_GATE_DRV1")
	)
	(segment
		(start 34.036 -385.826)
		(end 36.068 -383.794)
		(width 0.508)
		(layer "B.Cu")
		(net "ADM1276_GATE_DRV1")
	)
	(segment
		(start 27.559 -395.351)
		(end 27.559 -392.4046)
		(width 0.508)
		(layer "B.Cu")
		(net "ADM1276_GATE_DRV1")
	)
	(segment
		(start 36.068 -383.794)
		(end 36.068 -379.6792)
		(width 0.508)
		(layer "B.Cu")
		(net "ADM1276_GATE_DRV1")
	)
	(segment
		(start 34.036 -385.953)
		(end 34.036 -385.826)
		(width 0.508)
		(layer "B.Cu")
		(net "ADM1276_GATE_DRV1")
	)
	(segment
		(start 27.559 -392.4046)
		(end 34.0106 -385.953)
		(width 0.508)
		(layer "B.Cu")
		(net "ADM1276_GATE_DRV1")
	)
	(segment
		(start 27.559 -395.351)
		(end 27.559 -398.526)
		(width 0.508)
		(layer "B.Cu")
		(net "ADM1276_GATE_DRV1")
	)
	(segment
		(start 30.24632 -252.1966)
		(end 30.24632 -250.2408)
		(width 0.1397)
		(layer "F.Cu")
		(net "I2C_C_SCL_EEPROM")
	)
	(segment
		(start 30.3022 -253.4539)
		(end 30.24632 -253.39802)
		(width 0.1397)
		(layer "F.Cu")
		(net "I2C_C_SCL_EEPROM")
	)
	(segment
		(start 30.24632 -253.39802)
		(end 30.24632 -252.1966)
		(width 0.1397)
		(layer "F.Cu")
		(net "I2C_C_SCL_EEPROM")
	)
	(via
		(at 30.24632 -252.1966)
		(size 0.7112)
		(drill 0.3556)
		(layers "F.Cu" "B.Cu")
		(net "I2C_C_SCL_EEPROM")
	)
	(segment
		(start 41.275 -134.0866)
		(end 39.7891 -134.0866)
		(width 0.508)
		(layer "F.Cu")
		(net "P12VL_NET")
	)
	(segment
		(start 44.704 -120.154192)
		(end 44.006008 -120.154192)
		(width 0.508)
		(layer "F.Cu")
		(net "P12VL_NET")
	)
	(segment
		(start 39.7891 -134.0866)
		(end 39.5224 -134.3533)
		(width 0.508)
		(layer "F.Cu")
		(net "P12VL_NET")
	)
	(segment
		(start 40.132 -120.154192)
		(end 40.132 -120.3452)
		(width 0.508)
		(layer "F.Cu")
		(net "P12VL_NET")
	)
	(segment
		(start 44.006008 -120.154192)
		(end 41.9862 -122.174)
		(width 0.508)
		(layer "F.Cu")
		(net "P12VL_NET")
	)
	(segment
		(start 40.132 -120.3452)
		(end 41.9862 -122.1994)
		(width 0.508)
		(layer "F.Cu")
		(net "P12VL_NET")
	)
	(segment
		(start 41.9862 -122.174)
		(end 41.9862 -122.1994)
		(width 0.508)
		(layer "F.Cu")
		(net "P12VL_NET")
	)
	(via
		(at 33.274 -113.538)
		(size 0.7112)
		(drill 0.4064)
		(layers "F.Cu" "B.Cu")
		(net "P12VL_NET")
	)
	(via
		(at 34.417 -120.523)
		(size 0.7112)
		(drill 0.4064)
		(layers "F.Cu" "B.Cu")
		(net "P12VL_NET")
	)
	(via
		(at 49.53 -118.745)
		(size 0.7112)
		(drill 0.4064)
		(layers "F.Cu" "B.Cu")
		(net "P12VL_NET")
	)
	(via
		(at 48.3616 -115.189)
		(size 0.7112)
		(drill 0.4064)
		(layers "F.Cu" "B.Cu")
		(net "P12VL_NET")
	)
	(via
		(at 33.147 -120.523)
		(size 0.7112)
		(drill 0.4064)
		(layers "F.Cu" "B.Cu")
		(net "P12VL_NET")
	)
	(via
		(at 36.6776 -119.5832)
		(size 0.7112)
		(drill 0.3556)
		(layers "F.Cu" "B.Cu")
		(net "P12VL_NET")
	)
	(via
		(at 34.417 -117.094)
		(size 0.7112)
		(drill 0.4064)
		(layers "F.Cu" "B.Cu")
		(net "P12VL_NET")
	)
	(via
		(at 47.879 -120.523)
		(size 0.7112)
		(drill 0.4064)
		(layers "F.Cu" "B.Cu")
		(net "P12VL_NET")
	)
	(via
		(at 34.417 -118.872)
		(size 0.7112)
		(drill 0.4064)
		(layers "F.Cu" "B.Cu")
		(net "P12VL_NET")
	)
	(via
		(at 33.147 -115.316)
		(size 0.7112)
		(drill 0.4064)
		(layers "F.Cu" "B.Cu")
		(net "P12VL_NET")
	)
	(via
		(at 49.657 -115.189)
		(size 0.7112)
		(drill 0.4064)
		(layers "F.Cu" "B.Cu")
		(net "P12VL_NET")
	)
	(via
		(at 41.1226 -114.7064)
		(size 0.7112)
		(drill 0.4064)
		(layers "F.Cu" "B.Cu")
		(net "P12VL_NET")
	)
	(via
		(at 41.148 -116.2304)
		(size 0.7112)
		(drill 0.4064)
		(layers "F.Cu" "B.Cu")
		(net "P12VL_NET")
	)
	(via
		(at 41.275 -134.0866)
		(size 0.5588)
		(drill 0.3048)
		(layers "F.Cu" "B.Cu")
		(net "P12VL_NET")
	)
	(via
		(at 34.544 -113.538)
		(size 0.7112)
		(drill 0.4064)
		(layers "F.Cu" "B.Cu")
		(net "P12VL_NET")
	)
	(via
		(at 48.2346 -118.745)
		(size 0.7112)
		(drill 0.4064)
		(layers "F.Cu" "B.Cu")
		(net "P12VL_NET")
	)
	(via
		(at 49.6824 -113.665)
		(size 0.7112)
		(drill 0.4064)
		(layers "F.Cu" "B.Cu")
		(net "P12VL_NET")
	)
	(via
		(at 48.320706 -113.652046)
		(size 0.7112)
		(drill 0.4064)
		(layers "F.Cu" "B.Cu")
		(net "P12VL_NET")
	)
	(via
		(at 34.417 -115.316)
		(size 0.7112)
		(drill 0.4064)
		(layers "F.Cu" "B.Cu")
		(net "P12VL_NET")
	)
	(via
		(at 41.0464 -113.2586)
		(size 0.7112)
		(drill 0.4064)
		(layers "F.Cu" "B.Cu")
		(net "P12VL_NET")
	)
	(via
		(at 41.1226 -117.6782)
		(size 0.7112)
		(drill 0.4064)
		(layers "F.Cu" "B.Cu")
		(net "P12VL_NET")
	)
	(via
		(at 49.403 -120.523)
		(size 0.7112)
		(drill 0.4064)
		(layers "F.Cu" "B.Cu")
		(net "P12VL_NET")
	)
	(via
		(at 33.147 -117.094)
		(size 0.7112)
		(drill 0.4064)
		(layers "F.Cu" "B.Cu")
		(net "P12VL_NET")
	)
	(via
		(at 48.2346 -116.967)
		(size 0.7112)
		(drill 0.4064)
		(layers "F.Cu" "B.Cu")
		(net "P12VL_NET")
	)
	(via
		(at 41.9862 -122.1994)
		(size 0.5588)
		(drill 0.3048)
		(layers "F.Cu" "B.Cu")
		(net "P12VL_NET")
	)
	(via
		(at 33.147 -118.872)
		(size 0.7112)
		(drill 0.4064)
		(layers "F.Cu" "B.Cu")
		(net "P12VL_NET")
	)
	(via
		(at 49.53 -116.967)
		(size 0.7112)
		(drill 0.4064)
		(layers "F.Cu" "B.Cu")
		(net "P12VL_NET")
	)
	(segment
		(start 41.9862 -124.1806)
		(end 41.275 -124.8918)
		(width 0.508)
		(layer "B.Cu")
		(net "P12VL_NET")
	)
	(segment
		(start 41.275 -124.8918)
		(end 41.275 -134.0866)
		(width 0.508)
		(layer "B.Cu")
		(net "P12VL_NET")
	)
	(segment
		(start 41.9862 -122.1994)
		(end 41.9862 -124.1806)
		(width 0.508)
		(layer "B.Cu")
		(net "P12VL_NET")
	)
	(segment
		(start 21.6535 -134.7343)
		(end 22.2758 -134.112)
		(width 0.508)
		(layer "F.Cu")
		(net "P12VU_NET")
	)
	(segment
		(start 19.8628 -122.3518)
		(end 18.288 -120.777)
		(width 0.508)
		(layer "F.Cu")
		(net "P12VU_NET")
	)
	(segment
		(start 19.8628 -122.3518)
		(end 21.933408 -120.281192)
		(width 0.508)
		(layer "F.Cu")
		(net "P12VU_NET")
	)
	(segment
		(start 21.933408 -120.281192)
		(end 22.86 -120.281192)
		(width 0.508)
		(layer "F.Cu")
		(net "P12VU_NET")
	)
	(segment
		(start 20.6756 -134.7343)
		(end 21.6535 -134.7343)
		(width 0.508)
		(layer "F.Cu")
		(net "P12VU_NET")
	)
	(segment
		(start 18.288 -120.777)
		(end 18.288 -120.281192)
		(width 0.508)
		(layer "F.Cu")
		(net "P12VU_NET")
	)
	(via
		(at 16.0782 -117.9576)
		(size 0.7112)
		(drill 0.4064)
		(layers "F.Cu" "B.Cu")
		(net "P12VU_NET")
	)
	(via
		(at 22.8092 -115.0366)
		(size 0.7112)
		(drill 0.4064)
		(layers "F.Cu" "B.Cu")
		(net "P12VU_NET")
	)
	(via
		(at 25.273 -120.142)
		(size 0.7112)
		(drill 0.4064)
		(layers "F.Cu" "B.Cu")
		(net "P12VU_NET")
	)
	(via
		(at 15.875 -121.158)
		(size 0.7112)
		(drill 0.4064)
		(layers "F.Cu" "B.Cu")
		(net "P12VU_NET")
	)
	(via
		(at 29.718 -118.364)
		(size 0.7112)
		(drill 0.4064)
		(layers "F.Cu" "B.Cu")
		(net "P12VU_NET")
	)
	(via
		(at 30.861 -120.777)
		(size 0.7112)
		(drill 0.4064)
		(layers "F.Cu" "B.Cu")
		(net "P12VU_NET")
	)
	(via
		(at 29.718 -115.57)
		(size 0.7112)
		(drill 0.4064)
		(layers "F.Cu" "B.Cu")
		(net "P12VU_NET")
	)
	(via
		(at 28.321 -120.142)
		(size 0.7112)
		(drill 0.4064)
		(layers "F.Cu" "B.Cu")
		(net "P12VU_NET")
	)
	(via
		(at 31.115 -119.253)
		(size 0.7112)
		(drill 0.4064)
		(layers "F.Cu" "B.Cu")
		(net "P12VU_NET")
	)
	(via
		(at 29.337 -121.0818)
		(size 0.7112)
		(drill 0.3556)
		(layers "F.Cu" "B.Cu")
		(net "P12VU_NET")
	)
	(via
		(at 22.8092 -116.586)
		(size 0.7112)
		(drill 0.4064)
		(layers "F.Cu" "B.Cu")
		(net "P12VU_NET")
	)
	(via
		(at 22.2758 -134.112)
		(size 0.5588)
		(drill 0.3048)
		(layers "F.Cu" "B.Cu")
		(net "P12VU_NET")
	)
	(via
		(at 16.256 -114.554)
		(size 0.7112)
		(drill 0.4064)
		(layers "F.Cu" "B.Cu")
		(net "P12VU_NET")
	)
	(via
		(at 31.115 -114.427)
		(size 0.7112)
		(drill 0.4064)
		(layers "F.Cu" "B.Cu")
		(net "P12VU_NET")
	)
	(via
		(at 15.875 -120.1166)
		(size 0.7112)
		(drill 0.4064)
		(layers "F.Cu" "B.Cu")
		(net "P12VU_NET")
	)
	(via
		(at 19.8628 -122.3518)
		(size 0.7112)
		(drill 0.4064)
		(layers "F.Cu" "B.Cu")
		(net "P12VU_NET")
	)
	(via
		(at 27.051 -119.253)
		(size 0.7112)
		(drill 0.3556)
		(layers "F.Cu" "B.Cu")
		(net "P12VU_NET")
	)
	(via
		(at 16.256 -116.84)
		(size 0.7112)
		(drill 0.4064)
		(layers "F.Cu" "B.Cu")
		(net "P12VU_NET")
	)
	(via
		(at 29.718 -116.967)
		(size 0.7112)
		(drill 0.4064)
		(layers "F.Cu" "B.Cu")
		(net "P12VU_NET")
	)
	(via
		(at 29.718 -119.761)
		(size 0.7112)
		(drill 0.4064)
		(layers "F.Cu" "B.Cu")
		(net "P12VU_NET")
	)
	(via
		(at 29.718 -114.046)
		(size 0.7112)
		(drill 0.4064)
		(layers "F.Cu" "B.Cu")
		(net "P12VU_NET")
	)
	(via
		(at 31.115 -117.729)
		(size 0.7112)
		(drill 0.4064)
		(layers "F.Cu" "B.Cu")
		(net "P12VU_NET")
	)
	(via
		(at 22.8092 -118.0592)
		(size 0.7112)
		(drill 0.4064)
		(layers "F.Cu" "B.Cu")
		(net "P12VU_NET")
	)
	(via
		(at 16.256 -113.411)
		(size 0.7112)
		(drill 0.4064)
		(layers "F.Cu" "B.Cu")
		(net "P12VU_NET")
	)
	(via
		(at 31.115 -116.205)
		(size 0.7112)
		(drill 0.4064)
		(layers "F.Cu" "B.Cu")
		(net "P12VU_NET")
	)
	(via
		(at 22.8092 -113.284)
		(size 0.7112)
		(drill 0.4064)
		(layers "F.Cu" "B.Cu")
		(net "P12VU_NET")
	)
	(via
		(at 16.256 -115.697)
		(size 0.7112)
		(drill 0.4064)
		(layers "F.Cu" "B.Cu")
		(net "P12VU_NET")
	)
	(via
		(at 15.9004 -118.999)
		(size 0.7112)
		(drill 0.4064)
		(layers "F.Cu" "B.Cu")
		(net "P12VU_NET")
	)
	(segment
		(start 22.8092 -133.393942)
		(end 22.8092 -127.704596)
		(width 0.508)
		(layer "B.Cu")
		(net "P12VU_NET")
	)
	(segment
		(start 22.2758 -134.112)
		(end 22.2758 -133.927342)
		(width 0.508)
		(layer "B.Cu")
		(net "P12VU_NET")
	)
	(segment
		(start 19.8628 -124.758196)
		(end 19.8628 -122.3518)
		(width 0.508)
		(layer "B.Cu")
		(net "P12VU_NET")
	)
	(segment
		(start 22.2758 -133.927342)
		(end 22.8092 -133.393942)
		(width 0.508)
		(layer "B.Cu")
		(net "P12VU_NET")
	)
	(segment
		(start 22.8092 -127.704596)
		(end 19.8628 -124.758196)
		(width 0.508)
		(layer "B.Cu")
		(net "P12VU_NET")
	)
	(segment
		(start 41.7068 -138.3665)
		(end 41.4909 -138.5824)
		(width 0.508)
		(layer "F.Cu")
		(net "P12VL_2490_RC")
	)
	(segment
		(start 41.7068 -137.6426)
		(end 41.7068 -138.3665)
		(width 0.508)
		(layer "F.Cu")
		(net "P12VL_2490_RC")
	)
	(segment
		(start 41.4909 -138.5824)
		(end 41.4909 -139.5222)
		(width 0.508)
		(layer "F.Cu")
		(net "P12VL_2490_RC")
	)
	(via
		(at 41.7068 -137.6426)
		(size 0.7112)
		(drill 0.3556)
		(layers "F.Cu" "B.Cu")
		(net "P12VL_2490_RC")
	)
	(segment
		(start 30.099 -112.268)
		(end 29.9339 -112.1029)
		(width 0.508)
		(layer "F.Cu")
		(net "P12VU_2490_GATE_DRV")
	)
	(segment
		(start 28.829 -111.125)
		(end 29.9339 -111.125)
		(width 0.508)
		(layer "F.Cu")
		(net "P12VU_2490_GATE_DRV")
	)
	(segment
		(start 29.9339 -112.1029)
		(end 29.9339 -111.125)
		(width 0.508)
		(layer "F.Cu")
		(net "P12VU_2490_GATE_DRV")
	)
	(segment
		(start 28.321 -111.633)
		(end 28.829 -111.125)
		(width 0.508)
		(layer "F.Cu")
		(net "P12VU_2490_GATE_DRV")
	)
	(via
		(at 30.099 -112.268)
		(size 0.7112)
		(drill 0.3556)
		(layers "F.Cu" "B.Cu")
		(net "P12VU_2490_GATE_DRV")
	)
	(segment
		(start 39.624 -111.633)
		(end 39.624 -110.0455)
		(width 0.508)
		(layer "F.Cu")
		(net "P12VL_2490_GATE_DRV")
	)
	(segment
		(start 39.624 -110.0455)
		(end 39.0017 -109.4232)
		(width 0.508)
		(layer "F.Cu")
		(net "P12VL_2490_GATE_DRV")
	)
	(segment
		(start 39.624 -111.633)
		(end 40.965374 -111.633)
		(width 0.508)
		(layer "F.Cu")
		(net "P12VL_2490_GATE_DRV")
	)
	(segment
		(start 40.965374 -111.633)
		(end 41.303448 -111.294926)
		(width 0.508)
		(layer "F.Cu")
		(net "P12VL_2490_GATE_DRV")
	)
	(via
		(at 41.303448 -111.294926)
		(size 0.7112)
		(drill 0.3556)
		(layers "F.Cu" "B.Cu")
		(net "P12VL_2490_GATE_DRV")
	)
	(segment
		(start 40.8813 -136.271)
		(end 40.8813 -135.3693)
		(width 0.508)
		(layer "F.Cu")
		(net "P12VL_2490_SENSE")
	)
	(segment
		(start 39.5224 -135.2423)
		(end 38.6207 -135.2423)
		(width 0.508)
		(layer "F.Cu")
		(net "P12VL_2490_SENSE")
	)
	(segment
		(start 39.5224 -135.2423)
		(end 40.5765 -135.2423)
		(width 0.508)
		(layer "F.Cu")
		(net "P12VL_2490_SENSE")
	)
	(segment
		(start 38.6207 -135.2423)
		(end 38.481 -135.382)
		(width 0.508)
		(layer "F.Cu")
		(net "P12VL_2490_SENSE")
	)
	(segment
		(start 40.8813 -136.271)
		(end 38.7604 -136.271)
		(width 0.3048)
		(layer "F.Cu")
		(net "P12VL_2490_SENSE")
	)
	(segment
		(start 38.7604 -136.271)
		(end 38.39718 -136.63422)
		(width 0.3048)
		(layer "F.Cu")
		(net "P12VL_2490_SENSE")
	)
	(segment
		(start 40.8813 -135.3693)
		(end 40.6654 -135.1534)
		(width 0.508)
		(layer "F.Cu")
		(net "P12VL_2490_SENSE")
	)
	(segment
		(start 38.39718 -136.63422)
		(end 38.39718 -137.9093)
		(width 0.3048)
		(layer "F.Cu")
		(net "P12VL_2490_SENSE")
	)
	(segment
		(start 40.5765 -135.2423)
		(end 40.6654 -135.1534)
		(width 0.508)
		(layer "F.Cu")
		(net "P12VL_2490_SENSE")
	)
	(via
		(at 38.481 -135.382)
		(size 0.7112)
		(drill 0.3556)
		(layers "F.Cu" "B.Cu")
		(net "P12VL_2490_SENSE")
	)
	(segment
		(start 43.3451 -135.2804)
		(end 43.3324 -135.2677)
		(width 0.508)
		(layer "F.Cu")
		(net "P12VL_2490_VCC")
	)
	(segment
		(start 41.4274 -136.8806)
		(end 41.7703 -136.5377)
		(width 0.3048)
		(layer "F.Cu")
		(net "P12VL_2490_VCC")
	)
	(segment
		(start 41.7703 -135.5725)
		(end 42.1894 -135.1534)
		(width 0.508)
		(layer "F.Cu")
		(net "P12VL_2490_VCC")
	)
	(segment
		(start 38.89629 -137.9093)
		(end 38.89629 -137.07491)
		(width 0.3048)
		(layer "F.Cu")
		(net "P12VL_2490_VCC")
	)
	(segment
		(start 43.3324 -135.2677)
		(end 42.3037 -135.2677)
		(width 0.508)
		(layer "F.Cu")
		(net "P12VL_2490_VCC")
	)
	(segment
		(start 39.0906 -136.8806)
		(end 41.4274 -136.8806)
		(width 0.3048)
		(layer "F.Cu")
		(net "P12VL_2490_VCC")
	)
	(segment
		(start 42.3037 -135.2677)
		(end 42.1894 -135.1534)
		(width 0.508)
		(layer "F.Cu")
		(net "P12VL_2490_VCC")
	)
	(segment
		(start 43.3451 -136.2456)
		(end 43.3451 -135.2804)
		(width 0.508)
		(layer "F.Cu")
		(net "P12VL_2490_VCC")
	)
	(segment
		(start 41.7703 -136.5377)
		(end 41.7703 -136.271)
		(width 0.3048)
		(layer "F.Cu")
		(net "P12VL_2490_VCC")
	)
	(segment
		(start 43.3451 -135.2804)
		(end 44.2976 -135.2804)
		(width 0.508)
		(layer "F.Cu")
		(net "P12VL_2490_VCC")
	)
	(segment
		(start 44.2976 -135.2804)
		(end 44.3992 -135.1788)
		(width 0.508)
		(layer "F.Cu")
		(net "P12VL_2490_VCC")
	)
	(segment
		(start 38.89629 -137.07491)
		(end 39.0906 -136.8806)
		(width 0.3048)
		(layer "F.Cu")
		(net "P12VL_2490_VCC")
	)
	(segment
		(start 41.7703 -136.271)
		(end 41.7703 -135.5725)
		(width 0.508)
		(layer "F.Cu")
		(net "P12VL_2490_VCC")
	)
	(via
		(at 44.3992 -135.1788)
		(size 0.7112)
		(drill 0.3556)
		(layers "F.Cu" "B.Cu")
		(net "P12VL_2490_VCC")
	)
	(segment
		(start 35.6616 -143.9164)
		(end 36.3474 -143.9164)
		(width 0.254)
		(layer "F.Cu")
		(net "P12VL_2490_TIMER")
	)
	(segment
		(start 36.3474 -143.9164)
		(end 37.39642 -142.86738)
		(width 0.254)
		(layer "F.Cu")
		(net "P12VL_2490_TIMER")
	)
	(segment
		(start 37.39642 -142.86738)
		(end 37.39642 -142.0495)
		(width 0.254)
		(layer "F.Cu")
		(net "P12VL_2490_TIMER")
	)
	(segment
		(start 34.3916 -143.9164)
		(end 35.6616 -143.9164)
		(width 0.254)
		(layer "F.Cu")
		(net "P12VL_2490_TIMER")
	)
	(segment
		(start 34.3408 -143.8656)
		(end 34.3916 -143.9164)
		(width 0.254)
		(layer "F.Cu")
		(net "P12VL_2490_TIMER")
	)
	(via
		(at 34.3408 -143.8656)
		(size 0.7112)
		(drill 0.3556)
		(layers "F.Cu" "B.Cu")
		(net "P12VL_2490_TIMER")
	)
	(segment
		(start 37.8968 -143.2687)
		(end 36.8935 -144.272)
		(width 0.254)
		(layer "F.Cu")
		(net "P12VL_2490_PROG")
	)
	(segment
		(start 36.9062 -147.0025)
		(end 36.9062 -145.22958)
		(width 0.254)
		(layer "F.Cu")
		(net "P12VL_2490_PROG")
	)
	(segment
		(start 37.8968 -142.0495)
		(end 37.8968 -143.2687)
		(width 0.254)
		(layer "F.Cu")
		(net "P12VL_2490_PROG")
	)
	(segment
		(start 37.006784 -145.093436)
		(end 37.006784 -144.385284)
		(width 0.254)
		(layer "F.Cu")
		(net "P12VL_2490_PROG")
	)
	(segment
		(start 36.88842 -145.2118)
		(end 37.006784 -145.093436)
		(width 0.254)
		(layer "F.Cu")
		(net "P12VL_2490_PROG")
	)
	(segment
		(start 37.006784 -144.385284)
		(end 36.8935 -144.272)
		(width 0.254)
		(layer "F.Cu")
		(net "P12VL_2490_PROG")
	)
	(segment
		(start 36.9062 -145.22958)
		(end 36.88842 -145.2118)
		(width 0.254)
		(layer "F.Cu")
		(net "P12VL_2490_PROG")
	)
	(via
		(at 36.88842 -145.2118)
		(size 0.7112)
		(drill 0.3556)
		(layers "F.Cu" "B.Cu")
		(net "P12VL_2490_PROG")
	)
	(segment
		(start 37.9222 -144.4117)
		(end 37.9222 -145.8976)
		(width 0.254)
		(layer "F.Cu")
		(net "P12VL_2490_VREF")
	)
	(segment
		(start 37.7825 -144.272)
		(end 37.9222 -144.4117)
		(width 0.254)
		(layer "F.Cu")
		(net "P12VL_2490_VREF")
	)
	(segment
		(start 37.9222 -145.9992)
		(end 37.9222 -146.9263)
		(width 0.254)
		(layer "F.Cu")
		(net "P12VL_2490_VREF")
	)
	(segment
		(start 37.973 -145.9484)
		(end 37.9222 -145.9992)
		(width 0.254)
		(layer "F.Cu")
		(net "P12VL_2490_VREF")
	)
	(segment
		(start 37.9222 -145.8976)
		(end 37.973 -145.9484)
		(width 0.254)
		(layer "F.Cu")
		(net "P12VL_2490_VREF")
	)
	(segment
		(start 38.39718 -143.65732)
		(end 37.7825 -144.272)
		(width 0.254)
		(layer "F.Cu")
		(net "P12VL_2490_VREF")
	)
	(segment
		(start 38.39718 -142.0495)
		(end 38.39718 -143.65732)
		(width 0.254)
		(layer "F.Cu")
		(net "P12VL_2490_VREF")
	)
	(segment
		(start 37.9222 -146.9263)
		(end 37.973 -146.9771)
		(width 0.254)
		(layer "F.Cu")
		(net "P12VL_2490_VREF")
	)
	(via
		(at 37.973 -145.9484)
		(size 0.7112)
		(drill 0.3556)
		(layers "F.Cu" "B.Cu")
		(net "P12VL_2490_VREF")
	)
	(segment
		(start 34.7853 -137.9093)
		(end 36.89731 -137.9093)
		(width 0.1397)
		(layer "F.Cu")
		(net "P12VL_2490_PG")
	)
	(segment
		(start 34.716466 -139.347702)
		(end 34.739834 -139.324334)
		(width 0.1397)
		(layer "F.Cu")
		(net "P12VL_2490_PG")
	)
	(segment
		(start 34.716466 -140.645134)
		(end 34.716466 -139.347702)
		(width 0.1397)
		(layer "F.Cu")
		(net "P12VL_2490_PG")
	)
	(segment
		(start 34.739834 -139.324334)
		(end 34.741866 -139.322302)
		(width 0.1397)
		(layer "F.Cu")
		(net "P12VL_2490_PG")
	)
	(segment
		(start 34.741866 -139.322302)
		(end 34.741866 -137.952734)
		(width 0.1397)
		(layer "F.Cu")
		(net "P12VL_2490_PG")
	)
	(segment
		(start 34.741866 -137.952734)
		(end 34.7853 -137.9093)
		(width 0.1397)
		(layer "F.Cu")
		(net "P12VL_2490_PG")
	)
	(segment
		(start 18.7706 -141.0589)
		(end 18.7706 -139.7254)
		(width 0.1397)
		(layer "F.Cu")
		(net "P12VU_2490_PG")
	)
	(segment
		(start 19.8755 -138.3665)
		(end 20.69211 -138.3665)
		(width 0.1397)
		(layer "F.Cu")
		(net "P12VU_2490_PG")
	)
	(segment
		(start 18.7198 -139.6746)
		(end 18.7198 -138.0109)
		(width 0.1397)
		(layer "F.Cu")
		(net "P12VU_2490_PG")
	)
	(segment
		(start 18.7706 -139.7254)
		(end 18.7198 -139.6746)
		(width 0.1397)
		(layer "F.Cu")
		(net "P12VU_2490_PG")
	)
	(segment
		(start 19.5199 -138.0109)
		(end 19.8755 -138.3665)
		(width 0.1397)
		(layer "F.Cu")
		(net "P12VU_2490_PG")
	)
	(segment
		(start 18.7198 -138.0109)
		(end 19.5199 -138.0109)
		(width 0.1397)
		(layer "F.Cu")
		(net "P12VU_2490_PG")
	)
	(segment
		(start 25.0571 -140.8049)
		(end 25.0571 -140.5382)
		(width 0.508)
		(layer "F.Cu")
		(net "P12VU_2490_RC")
	)
	(segment
		(start 25.0571 -140.5382)
		(end 25.0571 -139.5984)
		(width 0.508)
		(layer "F.Cu")
		(net "P12VU_2490_RC")
	)
	(segment
		(start 25.8572 -141.5796)
		(end 25.8318 -141.5796)
		(width 0.508)
		(layer "F.Cu")
		(net "P12VU_2490_RC")
	)
	(segment
		(start 25.8318 -141.5796)
		(end 25.0571 -140.8049)
		(width 0.508)
		(layer "F.Cu")
		(net "P12VU_2490_RC")
	)
	(via
		(at 25.8572 -141.5796)
		(size 0.7112)
		(drill 0.3556)
		(layers "F.Cu" "B.Cu")
		(net "P12VU_2490_RC")
	)
	(segment
		(start 21.6916 -138.3665)
		(end 21.6916 -139.2936)
		(width 0.3048)
		(layer "F.Cu")
		(net "P12VU_2490_GATE")
	)
	(segment
		(start 25.9461 -139.1031)
		(end 25.9461 -139.5984)
		(width 0.508)
		(layer "F.Cu")
		(net "P12VU_2490_GATE")
	)
	(segment
		(start 23.2156 -139.6746)
		(end 24.3078 -138.5824)
		(width 0.508)
		(layer "F.Cu")
		(net "P12VU_2490_GATE")
	)
	(segment
		(start 18.8595 -109.5502)
		(end 19.3548 -109.5502)
		(width 0.508)
		(layer "F.Cu")
		(net "P12VU_2490_GATE")
	)
	(segment
		(start 27.7368 -139.5984)
		(end 28.0416 -139.9032)
		(width 0.508)
		(layer "F.Cu")
		(net "P12VU_2490_GATE")
	)
	(segment
		(start 21.6916 -139.2936)
		(end 22.0726 -139.6746)
		(width 0.3048)
		(layer "F.Cu")
		(net "P12VU_2490_GATE")
	)
	(segment
		(start 19.3548 -109.5502)
		(end 19.812 -109.093)
		(width 0.508)
		(layer "F.Cu")
		(net "P12VU_2490_GATE")
	)
	(segment
		(start 24.3078 -138.5824)
		(end 25.3492 -138.5824)
		(width 0.508)
		(layer "F.Cu")
		(net "P12VU_2490_GATE")
	)
	(segment
		(start 30.8229 -111.7219)
		(end 30.8229 -111.125)
		(width 0.508)
		(layer "F.Cu")
		(net "P12VU_2490_GATE")
	)
	(segment
		(start 25.3492 -138.5824)
		(end 25.4254 -138.5824)
		(width 0.508)
		(layer "F.Cu")
		(net "P12VU_2490_GATE")
	)
	(segment
		(start 25.9461 -139.5984)
		(end 27.7368 -139.5984)
		(width 0.508)
		(layer "F.Cu")
		(net "P12VU_2490_GATE")
	)
	(segment
		(start 25.4254 -138.5824)
		(end 25.9461 -139.1031)
		(width 0.508)
		(layer "F.Cu")
		(net "P12VU_2490_GATE")
	)
	(segment
		(start 31.115 -112.014)
		(end 30.8229 -111.7219)
		(width 0.508)
		(layer "F.Cu")
		(net "P12VU_2490_GATE")
	)
	(segment
		(start 22.0726 -139.6746)
		(end 23.2156 -139.6746)
		(width 0.508)
		(layer "F.Cu")
		(net "P12VU_2490_GATE")
	)
	(via
		(at 19.812 -109.093)
		(size 0.5588)
		(drill 0.3048)
		(layers "F.Cu" "B.Cu")
		(net "P12VU_2490_GATE")
	)
	(via
		(at 26.7462 -133.4008)
		(size 0.7112)
		(drill 0.3556)
		(layers "F.Cu" "B.Cu")
		(net "P12VU_2490_GATE")
	)
	(via
		(at 31.115 -112.014)
		(size 0.5588)
		(drill 0.3048)
		(layers "F.Cu" "B.Cu")
		(net "P12VU_2490_GATE")
	)
	(via
		(at 25.3492 -138.5824)
		(size 0.7112)
		(drill 0.3556)
		(layers "F.Cu" "B.Cu")
		(net "P12VU_2490_GATE")
	)
	(via
		(at 28.0416 -139.9032)
		(size 0.5588)
		(drill 0.3048)
		(layers "F.Cu" "B.Cu")
		(net "P12VU_2490_GATE")
	)
	(segment
		(start 29.8196 -112.014)
		(end 26.29535 -115.53825)
		(width 0.508)
		(layer "B.Cu")
		(net "P12VU_2490_GATE")
	)
	(segment
		(start 26.29535 -132.94995)
		(end 26.7462 -133.4008)
		(width 0.508)
		(layer "B.Cu")
		(net "P12VU_2490_GATE")
	)
	(segment
		(start 31.115 -112.014)
		(end 29.8196 -112.014)
		(width 0.508)
		(layer "B.Cu")
		(net "P12VU_2490_GATE")
	)
	(segment
		(start 26.7462 -138.6078)
		(end 26.7462 -133.4008)
		(width 0.508)
		(layer "B.Cu")
		(net "P12VU_2490_GATE")
	)
	(segment
		(start 19.939 -109.22)
		(end 28.321 -109.22)
		(width 0.508)
		(layer "B.Cu")
		(net "P12VU_2490_GATE")
	)
	(segment
		(start 28.0416 -139.9032)
		(end 26.7462 -138.6078)
		(width 0.508)
		(layer "B.Cu")
		(net "P12VU_2490_GATE")
	)
	(segment
		(start 28.321 -109.22)
		(end 31.115 -112.014)
		(width 0.508)
		(layer "B.Cu")
		(net "P12VU_2490_GATE")
	)
	(segment
		(start 19.812 -109.093)
		(end 19.939 -109.22)
		(width 0.508)
		(layer "B.Cu")
		(net "P12VU_2490_GATE")
	)
	(segment
		(start 26.29535 -115.53825)
		(end 26.29535 -132.94995)
		(width 0.508)
		(layer "B.Cu")
		(net "P12VU_2490_GATE")
	)
	(segment
		(start 20.4724 -144.3228)
		(end 19.3802 -144.3228)
		(width 0.254)
		(layer "F.Cu")
		(net "P12VU_2490_TIMER")
	)
	(segment
		(start 18.8214 -144.8816)
		(end 17.8816 -143.9418)
		(width 0.254)
		(layer "F.Cu")
		(net "P12VU_2490_TIMER")
	)
	(segment
		(start 21.19122 -143.60398)
		(end 20.4724 -144.3228)
		(width 0.254)
		(layer "F.Cu")
		(net "P12VU_2490_TIMER")
	)
	(segment
		(start 17.8816 -143.9418)
		(end 17.8816 -143.637)
		(width 0.254)
		(layer "F.Cu")
		(net "P12VU_2490_TIMER")
	)
	(segment
		(start 19.3802 -144.3228)
		(end 18.8214 -144.8816)
		(width 0.254)
		(layer "F.Cu")
		(net "P12VU_2490_TIMER")
	)
	(segment
		(start 21.19122 -142.5067)
		(end 21.19122 -143.60398)
		(width 0.254)
		(layer "F.Cu")
		(net "P12VU_2490_TIMER")
	)
	(via
		(at 17.8816 -143.637)
		(size 0.7112)
		(drill 0.3556)
		(layers "F.Cu" "B.Cu")
		(net "P12VU_2490_TIMER")
	)
	(segment
		(start 21.2471 -144.4879)
		(end 21.6916 -144.0434)
		(width 0.254)
		(layer "F.Cu")
		(net "P12VU_2490_PROG")
	)
	(segment
		(start 21.2471 -145.7325)
		(end 21.2471 -144.7546)
		(width 0.254)
		(layer "F.Cu")
		(net "P12VU_2490_PROG")
	)
	(segment
		(start 21.0566 -145.923)
		(end 21.2471 -145.7325)
		(width 0.254)
		(layer "F.Cu")
		(net "P12VU_2490_PROG")
	)
	(segment
		(start 19.9644 -145.0467)
		(end 20.0533 -145.0467)
		(width 0.254)
		(layer "F.Cu")
		(net "P12VU_2490_PROG")
	)
	(segment
		(start 20.9296 -145.923)
		(end 21.0566 -145.923)
		(width 0.254)
		(layer "F.Cu")
		(net "P12VU_2490_PROG")
	)
	(segment
		(start 21.6916 -144.0434)
		(end 21.6916 -142.5067)
		(width 0.254)
		(layer "F.Cu")
		(net "P12VU_2490_PROG")
	)
	(segment
		(start 20.0533 -145.0467)
		(end 20.9296 -145.923)
		(width 0.254)
		(layer "F.Cu")
		(net "P12VU_2490_PROG")
	)
	(segment
		(start 21.2471 -144.7546)
		(end 21.2471 -144.4879)
		(width 0.254)
		(layer "F.Cu")
		(net "P12VU_2490_PROG")
	)
	(via
		(at 21.0566 -145.923)
		(size 0.7112)
		(drill 0.3556)
		(layers "F.Cu" "B.Cu")
		(net "P12VU_2490_PROG")
	)
	(segment
		(start 21.239226 -146.705574)
		(end 21.239226 -147.762468)
		(width 0.254)
		(layer "F.Cu")
		(net "P12VU_2490_VREF")
	)
	(segment
		(start 22.1996 -145.8341)
		(end 22.0091 -146.0246)
		(width 0.254)
		(layer "F.Cu")
		(net "P12VU_2490_VREF")
	)
	(segment
		(start 22.0091 -146.0246)
		(end 21.9202 -146.0246)
		(width 0.254)
		(layer "F.Cu")
		(net "P12VU_2490_VREF")
	)
	(segment
		(start 22.1361 -144.7546)
		(end 22.1361 -145.7706)
		(width 0.254)
		(layer "F.Cu")
		(net "P12VU_2490_VREF")
	)
	(segment
		(start 22.19198 -144.69872)
		(end 22.19198 -142.5067)
		(width 0.254)
		(layer "F.Cu")
		(net "P12VU_2490_VREF")
	)
	(segment
		(start 21.9202 -146.0246)
		(end 21.239226 -146.705574)
		(width 0.254)
		(layer "F.Cu")
		(net "P12VU_2490_VREF")
	)
	(segment
		(start 22.1361 -144.7546)
		(end 22.19198 -144.69872)
		(width 0.254)
		(layer "F.Cu")
		(net "P12VU_2490_VREF")
	)
	(segment
		(start 22.1361 -145.7706)
		(end 22.1996 -145.8341)
		(width 0.254)
		(layer "F.Cu")
		(net "P12VU_2490_VREF")
	)
	(via
		(at 21.239226 -147.762468)
		(size 0.7112)
		(drill 0.3556)
		(layers "F.Cu" "B.Cu")
		(net "P12VU_2490_VREF")
	)
	(segment
		(start 22.69109 -136.85901)
		(end 22.9489 -136.6012)
		(width 0.254)
		(layer "F.Cu")
		(net "P12VU_2490_VCC")
	)
	(segment
		(start 23.368 -135.6233)
		(end 23.299166 -135.554466)
		(width 0.508)
		(layer "F.Cu")
		(net "P12VU_2490_VCC")
	)
	(segment
		(start 24.4094 -135.6233)
		(end 23.368 -135.6233)
		(width 0.508)
		(layer "F.Cu")
		(net "P12VU_2490_VCC")
	)
	(segment
		(start 24.4221 -137.3759)
		(end 24.4221 -136.6012)
		(width 0.508)
		(layer "F.Cu")
		(net "P12VU_2490_VCC")
	)
	(segment
		(start 24.6126 -137.5664)
		(end 24.4221 -137.3759)
		(width 0.508)
		(layer "F.Cu")
		(net "P12VU_2490_VCC")
	)
	(segment
		(start 24.4221 -136.6012)
		(end 24.4221 -135.636)
		(width 0.508)
		(layer "F.Cu")
		(net "P12VU_2490_VCC")
	)
	(segment
		(start 22.69109 -138.3665)
		(end 22.69109 -136.85901)
		(width 0.254)
		(layer "F.Cu")
		(net "P12VU_2490_VCC")
	)
	(segment
		(start 22.9489 -136.6012)
		(end 22.9489 -135.904732)
		(width 0.508)
		(layer "F.Cu")
		(net "P12VU_2490_VCC")
	)
	(segment
		(start 24.4221 -135.636)
		(end 24.4094 -135.6233)
		(width 0.508)
		(layer "F.Cu")
		(net "P12VU_2490_VCC")
	)
	(segment
		(start 22.9489 -135.904732)
		(end 23.299166 -135.554466)
		(width 0.508)
		(layer "F.Cu")
		(net "P12VU_2490_VCC")
	)
	(via
		(at 24.6126 -137.5664)
		(size 0.7112)
		(drill 0.3556)
		(layers "F.Cu" "B.Cu")
		(net "P12VU_2490_VCC")
	)
	(segment
		(start 38.70833 -161.244026)
		(end 38.43909 -161.513266)
		(width 0.1397)
		(layer "F.Cu")
		(net "NCT7904_CLK")
	)
	(segment
		(start 38.43909 -162.6616)
		(end 38.43909 -161.513266)
		(width 0.1397)
		(layer "F.Cu")
		(net "NCT7904_CLK")
	)
	(segment
		(start 40.5892 -161.244026)
		(end 38.70833 -161.244026)
		(width 0.1397)
		(layer "F.Cu")
		(net "NCT7904_CLK")
	)
	(via
		(at 38.43909 -162.6616)
		(size 0.7112)
		(drill 0.3556)
		(layers "F.Cu" "B.Cu")
		(net "NCT7904_CLK")
	)
	(segment
		(start 20.6756 -135.6233)
		(end 20.2565 -135.6233)
		(width 0.508)
		(layer "F.Cu")
		(net "P12VU_2490_SENSE")
	)
	(segment
		(start 22.0599 -136.6012)
		(end 22.0599 -135.8392)
		(width 0.508)
		(layer "F.Cu")
		(net "P12VU_2490_SENSE")
	)
	(segment
		(start 20.6756 -135.6233)
		(end 21.706332 -135.6233)
		(width 0.508)
		(layer "F.Cu")
		(net "P12VU_2490_SENSE")
	)
	(segment
		(start 22.0599 -135.8392)
		(end 21.775166 -135.554466)
		(width 0.508)
		(layer "F.Cu")
		(net "P12VU_2490_SENSE")
	)
	(segment
		(start 22.19198 -136.73328)
		(end 22.0599 -136.6012)
		(width 0.254)
		(layer "F.Cu")
		(net "P12VU_2490_SENSE")
	)
	(segment
		(start 22.19198 -138.3665)
		(end 22.19198 -136.73328)
		(width 0.254)
		(layer "F.Cu")
		(net "P12VU_2490_SENSE")
	)
	(segment
		(start 21.706332 -135.6233)
		(end 21.775166 -135.554466)
		(width 0.508)
		(layer "F.Cu")
		(net "P12VU_2490_SENSE")
	)
	(segment
		(start 20.2565 -135.6233)
		(end 19.6596 -136.2202)
		(width 0.508)
		(layer "F.Cu")
		(net "P12VU_2490_SENSE")
	)
	(via
		(at 19.6596 -136.2202)
		(size 0.7112)
		(drill 0.3556)
		(layers "F.Cu" "B.Cu")
		(net "P12VU_2490_SENSE")
	)
	(segment
		(start 22.96795 -158.01467)
		(end 23.231602 -158.278322)
		(width 0.1397)
		(layer "F.Cu")
		(net "NCT7904_TMPALM")
	)
	(segment
		(start 23.48611 -155.046934)
		(end 22.96795 -155.565094)
		(width 0.1397)
		(layer "F.Cu")
		(net "NCT7904_TMPALM")
	)
	(segment
		(start 26.12009 -159.098996)
		(end 24.052276 -159.098996)
		(width 0.1397)
		(layer "F.Cu")
		(net "NCT7904_TMPALM")
	)
	(segment
		(start 22.96795 -155.565094)
		(end 22.96795 -158.01467)
		(width 0.1397)
		(layer "F.Cu")
		(net "NCT7904_TMPALM")
	)
	(segment
		(start 24.052276 -159.098996)
		(end 23.231602 -158.278322)
		(width 0.1397)
		(layer "F.Cu")
		(net "NCT7904_TMPALM")
	)
	(via
		(at 23.231602 -158.278322)
		(size 0.7112)
		(drill 0.3556)
		(layers "F.Cu" "B.Cu")
		(net "NCT7904_TMPALM")
	)
	(segment
		(start 31.61157 -166.815262)
		(end 31.61157 -164.091366)
		(width 0.1397)
		(layer "F.Cu")
		(net "NCT7904_RSTOUT")
	)
	(segment
		(start 32.075374 -167.279066)
		(end 31.801308 -167.005)
		(width 0.1397)
		(layer "F.Cu")
		(net "NCT7904_RSTOUT")
	)
	(segment
		(start 31.801308 -167.005)
		(end 31.61157 -166.815262)
		(width 0.1397)
		(layer "F.Cu")
		(net "NCT7904_RSTOUT")
	)
	(segment
		(start 32.85109 -167.279066)
		(end 32.075374 -167.279066)
		(width 0.1397)
		(layer "F.Cu")
		(net "NCT7904_RSTOUT")
	)
	(via
		(at 31.801308 -167.005)
		(size 0.7112)
		(drill 0.3556)
		(layers "F.Cu" "B.Cu")
		(net "NCT7904_RSTOUT")
	)
	(segment
		(start 35.873944 -159.098996)
		(end 37.74313 -157.22981)
		(width 0.1397)
		(layer "F.Cu")
		(net "NCT7904_SMI")
	)
	(segment
		(start 37.74313 -157.22981)
		(end 37.74313 -157.0482)
		(width 0.1397)
		(layer "F.Cu")
		(net "NCT7904_SMI")
	)
	(segment
		(start 34.60369 -159.098996)
		(end 35.873944 -159.098996)
		(width 0.1397)
		(layer "F.Cu")
		(net "NCT7904_SMI")
	)
	(segment
		(start 37.74313 -157.0482)
		(end 38.56482 -156.22651)
		(width 0.1397)
		(layer "F.Cu")
		(net "NCT7904_SMI")
	)
	(segment
		(start 38.56482 -156.22651)
		(end 38.678866 -156.22651)
		(width 0.1397)
		(layer "F.Cu")
		(net "NCT7904_SMI")
	)
	(via
		(at 37.74313 -157.0482)
		(size 0.7112)
		(drill 0.3556)
		(layers "F.Cu" "B.Cu")
		(net "NCT7904_SMI")
	)
	(segment
		(start 23.614634 -157.447234)
		(end 24.767286 -158.599886)
		(width 0.1397)
		(layer "F.Cu")
		(net "NCT7904_LED")
	)
	(segment
		(start 24.767286 -158.599886)
		(end 26.12009 -158.599886)
		(width 0.1397)
		(layer "F.Cu")
		(net "NCT7904_LED")
	)
	(segment
		(start 23.614634 -156.80309)
		(end 23.614634 -157.447234)
		(width 0.1397)
		(layer "F.Cu")
		(net "NCT7904_LED")
	)
	(segment
		(start 37.67709 -160.624266)
		(end 37.252402 -161.048954)
		(width 0.1397)
		(layer "F.Cu")
		(net "NCT7904_CLKIN")
	)
	(segment
		(start 36.70173 -161.599626)
		(end 37.252402 -161.048954)
		(width 0.1397)
		(layer "F.Cu")
		(net "NCT7904_CLKIN")
	)
	(segment
		(start 38.43909 -160.624266)
		(end 37.67709 -160.624266)
		(width 0.1397)
		(layer "F.Cu")
		(net "NCT7904_CLKIN")
	)
	(segment
		(start 34.60369 -161.599626)
		(end 36.70173 -161.599626)
		(width 0.1397)
		(layer "F.Cu")
		(net "NCT7904_CLKIN")
	)
	(via
		(at 37.252402 -161.048954)
		(size 0.7112)
		(drill 0.3556)
		(layers "F.Cu" "B.Cu")
		(net "NCT7904_CLKIN")
	)
	(segment
		(start 24.01443 -152.68194)
		(end 24.01443 -152.704038)
		(width 0.1397)
		(layer "F.Cu")
		(net "NCT7904_RESET")
	)
	(segment
		(start 24.3459 -153.035508)
		(end 24.3459 -157.38475)
		(width 0.1397)
		(layer "F.Cu")
		(net "NCT7904_RESET")
	)
	(segment
		(start 25.060656 -158.099506)
		(end 26.12009 -158.099506)
		(width 0.1397)
		(layer "F.Cu")
		(net "NCT7904_RESET")
	)
	(segment
		(start 24.01443 -152.704038)
		(end 24.3459 -153.035508)
		(width 0.1397)
		(layer "F.Cu")
		(net "NCT7904_RESET")
	)
	(segment
		(start 23.63851 -151.770334)
		(end 23.63851 -152.30602)
		(width 0.1397)
		(layer "F.Cu")
		(net "NCT7904_RESET")
	)
	(segment
		(start 23.63851 -152.30602)
		(end 24.01443 -152.68194)
		(width 0.1397)
		(layer "F.Cu")
		(net "NCT7904_RESET")
	)
	(segment
		(start 24.3459 -157.38475)
		(end 25.060656 -158.099506)
		(width 0.1397)
		(layer "F.Cu")
		(net "NCT7904_RESET")
	)
	(via
		(at 24.01443 -152.704038)
		(size 0.7112)
		(drill 0.3556)
		(layers "F.Cu" "B.Cu")
		(net "NCT7904_RESET")
	)
	(segment
		(start 35.578034 -364.871)
		(end 37.338 -366.630966)
		(width 0.254)
		(layer "F.Cu")
		(net "ADM1276_LATCH#")
	)
	(segment
		(start 26.543 -364.998)
		(end 26.543 -363.474)
		(width 0.254)
		(layer "F.Cu")
		(net "ADM1276_LATCH#")
	)
	(segment
		(start 26.67 -361.6325)
		(end 27.305 -361.6325)
		(width 0.254)
		(layer "F.Cu")
		(net "ADM1276_LATCH#")
	)
	(segment
		(start 42.0116 -363.2835)
		(end 41.991026 -363.304074)
		(width 0.254)
		(layer "F.Cu")
		(net "ADM1276_LATCH#")
	)
	(segment
		(start 42.865802 -369.062)
		(end 43.654726 -368.273076)
		(width 0.254)
		(layer "F.Cu")
		(net "ADM1276_LATCH#")
	)
	(segment
		(start 42.035476 -365.117126)
		(end 42.035476 -363.307376)
		(width 0.254)
		(layer "F.Cu")
		(net "ADM1276_LATCH#")
	)
	(segment
		(start 42.035476 -363.307376)
		(end 42.0116 -363.2835)
		(width 0.254)
		(layer "F.Cu")
		(net "ADM1276_LATCH#")
	)
	(segment
		(start 42.537126 -365.117126)
		(end 42.035476 -365.117126)
		(width 0.254)
		(layer "F.Cu")
		(net "ADM1276_LATCH#")
	)
	(segment
		(start 37.338 -366.630966)
		(end 37.338 -367.048034)
		(width 0.254)
		(layer "F.Cu")
		(net "ADM1276_LATCH#")
	)
	(segment
		(start 38.335966 -368.046)
		(end 39.116 -368.046)
		(width 0.254)
		(layer "F.Cu")
		(net "ADM1276_LATCH#")
	)
	(segment
		(start 28.418028 -366.3696)
		(end 27.9146 -366.3696)
		(width 0.254)
		(layer "F.Cu")
		(net "ADM1276_LATCH#")
	)
	(segment
		(start 27.305 -361.6325)
		(end 27.8511 -362.1786)
		(width 0.254)
		(layer "F.Cu")
		(net "ADM1276_LATCH#")
	)
	(segment
		(start 25.527 -362.458)
		(end 25.527 -361.6325)
		(width 0.254)
		(layer "F.Cu")
		(net "ADM1276_LATCH#")
	)
	(segment
		(start 25.527 -361.6325)
		(end 26.67 -361.6325)
		(width 0.254)
		(layer "F.Cu")
		(net "ADM1276_LATCH#")
	)
	(segment
		(start 39.116 -368.046)
		(end 39.37 -368.3)
		(width 0.254)
		(layer "F.Cu")
		(net "ADM1276_LATCH#")
	)
	(segment
		(start 33.528 -364.871)
		(end 35.578034 -364.871)
		(width 0.254)
		(layer "F.Cu")
		(net "ADM1276_LATCH#")
	)
	(segment
		(start 27.9146 -366.3696)
		(end 26.543 -364.998)
		(width 0.254)
		(layer "F.Cu")
		(net "ADM1276_LATCH#")
	)
	(segment
		(start 43.654726 -368.273076)
		(end 43.654726 -366.234726)
		(width 0.254)
		(layer "F.Cu")
		(net "ADM1276_LATCH#")
	)
	(segment
		(start 40.64 -368.3)
		(end 41.402 -369.062)
		(width 0.254)
		(layer "F.Cu")
		(net "ADM1276_LATCH#")
	)
	(segment
		(start 41.402 -369.062)
		(end 42.865802 -369.062)
		(width 0.254)
		(layer "F.Cu")
		(net "ADM1276_LATCH#")
	)
	(segment
		(start 39.37 -368.3)
		(end 40.64 -368.3)
		(width 0.254)
		(layer "F.Cu")
		(net "ADM1276_LATCH#")
	)
	(segment
		(start 26.543 -363.474)
		(end 26.162 -363.093)
		(width 0.254)
		(layer "F.Cu")
		(net "ADM1276_LATCH#")
	)
	(segment
		(start 43.654726 -366.234726)
		(end 42.537126 -365.117126)
		(width 0.254)
		(layer "F.Cu")
		(net "ADM1276_LATCH#")
	)
	(segment
		(start 41.991026 -363.304074)
		(end 40.851074 -363.304074)
		(width 0.254)
		(layer "F.Cu")
		(net "ADM1276_LATCH#")
	)
	(segment
		(start 27.8511 -363.0041)
		(end 27.94 -363.093)
		(width 0.254)
		(layer "F.Cu")
		(net "ADM1276_LATCH#")
	)
	(segment
		(start 37.338 -367.048034)
		(end 38.335966 -368.046)
		(width 0.254)
		(layer "F.Cu")
		(net "ADM1276_LATCH#")
	)
	(segment
		(start 27.8511 -362.1786)
		(end 27.8511 -363.0041)
		(width 0.254)
		(layer "F.Cu")
		(net "ADM1276_LATCH#")
	)
	(segment
		(start 26.162 -363.093)
		(end 25.527 -362.458)
		(width 0.254)
		(layer "F.Cu")
		(net "ADM1276_LATCH#")
	)
	(via
		(at 26.162 -363.093)
		(size 0.7112)
		(drill 0.3556)
		(layers "F.Cu" "B.Cu")
		(net "ADM1276_LATCH#")
	)
	(via
		(at 33.528 -364.871)
		(size 0.5588)
		(drill 0.3048)
		(layers "F.Cu" "B.Cu")
		(net "ADM1276_LATCH#")
	)
	(via
		(at 27.94 -363.093)
		(size 0.5588)
		(drill 0.3048)
		(layers "F.Cu" "B.Cu")
		(net "ADM1276_LATCH#")
	)
	(segment
		(start 27.94 -363.093)
		(end 28.321 -363.474)
		(width 0.254)
		(layer "B.Cu")
		(net "ADM1276_LATCH#")
	)
	(segment
		(start 32.258 -364.871)
		(end 33.528 -364.871)
		(width 0.254)
		(layer "B.Cu")
		(net "ADM1276_LATCH#")
	)
	(segment
		(start 28.321 -363.474)
		(end 30.861 -363.474)
		(width 0.254)
		(layer "B.Cu")
		(net "ADM1276_LATCH#")
	)
	(segment
		(start 30.861 -363.474)
		(end 32.258 -364.871)
		(width 0.254)
		(layer "B.Cu")
		(net "ADM1276_LATCH#")
	)
	(segment
		(start 33.8074 -367.6904)
		(end 35.2552 -369.1382)
		(width 0.254)
		(layer "F.Cu")
		(net "ADM1276_PWRGD")
	)
	(segment
		(start 33.076642 -368.158014)
		(end 33.544256 -367.6904)
		(width 0.254)
		(layer "F.Cu")
		(net "ADM1276_PWRGD")
	)
	(segment
		(start 33.544256 -367.6904)
		(end 33.782 -367.6904)
		(width 0.254)
		(layer "F.Cu")
		(net "ADM1276_PWRGD")
	)
	(segment
		(start 32.1564 -368.158014)
		(end 33.076642 -368.158014)
		(width 0.254)
		(layer "F.Cu")
		(net "ADM1276_PWRGD")
	)
	(segment
		(start 35.2552 -369.1382)
		(end 35.5981 -369.1382)
		(width 0.254)
		(layer "F.Cu")
		(net "ADM1276_PWRGD")
	)
	(segment
		(start 33.782 -367.6904)
		(end 33.8074 -367.6904)
		(width 0.254)
		(layer "F.Cu")
		(net "ADM1276_PWRGD")
	)
	(via
		(at 33.782 -367.6904)
		(size 0.7112)
		(drill 0.3556)
		(layers "F.Cu" "B.Cu")
		(net "ADM1276_PWRGD")
	)
	(segment
		(start 31.96209 -151.93137)
		(end 31.11246 -152.781)
		(width 0.1397)
		(layer "F.Cu")
		(net "NCT7904_VSEN8")
	)
	(segment
		(start 31.11246 -152.781)
		(end 31.11246 -155.607766)
		(width 0.1397)
		(layer "F.Cu")
		(net "NCT7904_VSEN8")
	)
	(segment
		(start 31.96209 -150.781766)
		(end 31.96209 -151.93137)
		(width 0.1397)
		(layer "F.Cu")
		(net "NCT7904_VSEN8")
	)
	(segment
		(start 39.38524 -158.22676)
		(end 39.9288 -157.6832)
		(width 0.1397)
		(layer "F.Cu")
		(net "NCT7904_VSEN1")
	)
	(segment
		(start 36.130484 -160.099756)
		(end 38.00348 -158.22676)
		(width 0.1397)
		(layer "F.Cu")
		(net "NCT7904_VSEN1")
	)
	(segment
		(start 34.60369 -160.099756)
		(end 36.130484 -160.099756)
		(width 0.1397)
		(layer "F.Cu")
		(net "NCT7904_VSEN1")
	)
	(segment
		(start 41.3131 -158.1658)
		(end 40.8305 -157.6832)
		(width 0.1397)
		(layer "F.Cu")
		(net "NCT7904_VSEN1")
	)
	(segment
		(start 40.8305 -157.6832)
		(end 39.9288 -157.6832)
		(width 0.1397)
		(layer "F.Cu")
		(net "NCT7904_VSEN1")
	)
	(segment
		(start 38.00348 -158.22676)
		(end 39.38524 -158.22676)
		(width 0.1397)
		(layer "F.Cu")
		(net "NCT7904_VSEN1")
	)
	(via
		(at 39.9288 -157.6832)
		(size 0.7112)
		(drill 0.3556)
		(layers "F.Cu" "B.Cu")
		(net "NCT7904_VSEN1")
	)
	(segment
		(start 30.1117 -154.493468)
		(end 30.11551 -154.489658)
		(width 0.1397)
		(layer "F.Cu")
		(net "NCT7904_VSEN6")
	)
	(segment
		(start 29.6672 -149.516084)
		(end 30.681168 -149.516084)
		(width 0.1397)
		(layer "F.Cu")
		(net "NCT7904_VSEN6")
	)
	(segment
		(start 30.1498 -150.582884)
		(end 30.401768 -150.330916)
		(width 0.1397)
		(layer "F.Cu")
		(net "NCT7904_VSEN6")
	)
	(segment
		(start 30.401768 -150.330916)
		(end 30.4038 -150.330916)
		(width 0.1397)
		(layer "F.Cu")
		(net "NCT7904_VSEN6")
	)
	(segment
		(start 30.11551 -150.582884)
		(end 30.1498 -150.582884)
		(width 0.1397)
		(layer "F.Cu")
		(net "NCT7904_VSEN6")
	)
	(segment
		(start 30.1117 -155.607766)
		(end 30.1117 -154.493468)
		(width 0.1397)
		(layer "F.Cu")
		(net "NCT7904_VSEN6")
	)
	(segment
		(start 30.681168 -149.516084)
		(end 30.6832 -149.518116)
		(width 0.1397)
		(layer "F.Cu")
		(net "NCT7904_VSEN6")
	)
	(segment
		(start 30.11551 -154.489658)
		(end 30.11551 -150.582884)
		(width 0.1397)
		(layer "F.Cu")
		(net "NCT7904_VSEN6")
	)
	(segment
		(start 30.4038 -150.330916)
		(end 30.6832 -150.051516)
		(width 0.1397)
		(layer "F.Cu")
		(net "NCT7904_VSEN6")
	)
	(segment
		(start 30.6832 -150.051516)
		(end 30.6832 -149.518116)
		(width 0.1397)
		(layer "F.Cu")
		(net "NCT7904_VSEN6")
	)
	(via
		(at 30.11551 -150.582884)
		(size 0.7112)
		(drill 0.3556)
		(layers "F.Cu" "B.Cu")
		(net "NCT7904_VSEN6")
	)
	(segment
		(start 29.11221 -155.607766)
		(end 29.11221 -153.71191)
		(width 0.1397)
		(layer "F.Cu")
		(net "NCT7904_D2+")
	)
	(segment
		(start 26.547572 -320.000122)
		(end 27.468322 -320.000122)
		(width 0.1397)
		(layer "F.Cu")
		(net "NCT7904_D2+")
	)
	(segment
		(start 27.468322 -320.000122)
		(end 28.452572 -319.015872)
		(width 0.1397)
		(layer "F.Cu")
		(net "NCT7904_D2+")
	)
	(segment
		(start 29.11221 -153.71191)
		(end 28.6893 -153.289)
		(width 0.1397)
		(layer "F.Cu")
		(net "NCT7904_D2+")
	)
	(segment
		(start 28.452572 -319.015872)
		(end 30.226 -319.015872)
		(width 0.1397)
		(layer "F.Cu")
		(net "NCT7904_D2+")
	)
	(segment
		(start 28.6893 -152.417272)
		(end 28.86837 -152.238202)
		(width 0.1397)
		(layer "F.Cu")
		(net "NCT7904_D2+")
	)
	(segment
		(start 28.6893 -153.289)
		(end 28.6893 -152.417272)
		(width 0.1397)
		(layer "F.Cu")
		(net "NCT7904_D2+")
	)
	(via
		(at 30.226 -319.015872)
		(size 0.5588)
		(drill 0.3048)
		(layers "F.Cu" "B.Cu")
		(net "NCT7904_D2+")
	)
	(via
		(at 28.86837 -152.238202)
		(size 0.5588)
		(drill 0.3048)
		(layers "F.Cu" "B.Cu")
		(net "NCT7904_D2+")
	)
	(via
		(at 31.496 -316.8904)
		(size 0.7112)
		(drill 0.3556)
		(layers "F.Cu" "B.Cu")
		(net "NCT7904_D2+")
	)
	(segment
		(start 34.0106 -274.594828)
		(end 34.0106 -272.96364)
		(width 0.1397)
		(layer "B.Cu")
		(net "NCT7904_D2+")
	)
	(segment
		(start 41.6306 -216.23655)
		(end 39.51605 -214.122)
		(width 0.1397)
		(layer "B.Cu")
		(net "NCT7904_D2+")
	)
	(segment
		(start 41.6306 -246.0244)
		(end 41.6306 -216.23655)
		(width 0.1397)
		(layer "B.Cu")
		(net "NCT7904_D2+")
	)
	(segment
		(start 34.0106 -272.96364)
		(end 34.010854 -272.963386)
		(width 0.1397)
		(layer "B.Cu")
		(net "NCT7904_D2+")
	)
	(segment
		(start 34.010854 -272.963386)
		(end 34.010854 -259.322316)
		(width 0.1397)
		(layer "B.Cu")
		(net "NCT7904_D2+")
	)
	(segment
		(start 36.56965 -173.76775)
		(end 36.56965 -170.777154)
		(width 0.1397)
		(layer "B.Cu")
		(net "NCT7904_D2+")
	)
	(segment
		(start 35.311842 -168.624758)
		(end 35.83305 -168.10355)
		(width 0.1397)
		(layer "B.Cu")
		(net "NCT7904_D2+")
	)
	(segment
		(start 34.010854 -274.595082)
		(end 34.0106 -274.594828)
		(width 0.1397)
		(layer "B.Cu")
		(net "NCT7904_D2+")
	)
	(segment
		(start 36.060126 -210.673696)
		(end 36.060126 -174.277274)
		(width 0.1397)
		(layer "B.Cu")
		(net "NCT7904_D2+")
	)
	(segment
		(start 35.83305 -159.202882)
		(end 28.86837 -152.238202)
		(width 0.1397)
		(layer "B.Cu")
		(net "NCT7904_D2+")
	)
	(segment
		(start 34.010854 -275.488146)
		(end 34.010854 -274.595082)
		(width 0.1397)
		(layer "B.Cu")
		(net "NCT7904_D2+")
	)
	(segment
		(start 31.496 -278.003)
		(end 34.010854 -275.488146)
		(width 0.1397)
		(layer "B.Cu")
		(net "NCT7904_D2+")
	)
	(segment
		(start 34.45637 -256.50063)
		(end 40.8686 -250.0884)
		(width 0.1397)
		(layer "B.Cu")
		(net "NCT7904_D2+")
	)
	(segment
		(start 34.010854 -259.322316)
		(end 34.45637 -258.8768)
		(width 0.1397)
		(layer "B.Cu")
		(net "NCT7904_D2+")
	)
	(segment
		(start 39.50843 -214.122)
		(end 36.060126 -210.673696)
		(width 0.1397)
		(layer "B.Cu")
		(net "NCT7904_D2+")
	)
	(segment
		(start 35.311842 -169.519346)
		(end 35.311842 -168.624758)
		(width 0.1397)
		(layer "B.Cu")
		(net "NCT7904_D2+")
	)
	(segment
		(start 35.83305 -168.10355)
		(end 35.83305 -159.202882)
		(width 0.1397)
		(layer "B.Cu")
		(net "NCT7904_D2+")
	)
	(segment
		(start 36.060126 -174.277274)
		(end 36.56965 -173.76775)
		(width 0.1397)
		(layer "B.Cu")
		(net "NCT7904_D2+")
	)
	(segment
		(start 36.56965 -170.777154)
		(end 35.311842 -169.519346)
		(width 0.1397)
		(layer "B.Cu")
		(net "NCT7904_D2+")
	)
	(segment
		(start 40.8686 -250.0884)
		(end 40.8686 -246.7864)
		(width 0.1397)
		(layer "B.Cu")
		(net "NCT7904_D2+")
	)
	(segment
		(start 34.45637 -258.8768)
		(end 34.45637 -256.50063)
		(width 0.1397)
		(layer "B.Cu")
		(net "NCT7904_D2+")
	)
	(segment
		(start 39.51605 -214.122)
		(end 39.50843 -214.122)
		(width 0.1397)
		(layer "B.Cu")
		(net "NCT7904_D2+")
	)
	(segment
		(start 30.226 -319.015872)
		(end 31.496 -317.745872)
		(width 0.1397)
		(layer "B.Cu")
		(net "NCT7904_D2+")
	)
	(segment
		(start 40.8686 -246.7864)
		(end 41.6306 -246.0244)
		(width 0.1397)
		(layer "B.Cu")
		(net "NCT7904_D2+")
	)
	(segment
		(start 31.496 -316.8904)
		(end 31.496 -278.003)
		(width 0.1397)
		(layer "B.Cu")
		(net "NCT7904_D2+")
	)
	(segment
		(start 31.496 -317.745872)
		(end 31.496 -316.8904)
		(width 0.1397)
		(layer "B.Cu")
		(net "NCT7904_D2+")
	)
	(segment
		(start 29.5783 -153.289)
		(end 29.5783 -151.7269)
		(width 0.1397)
		(layer "F.Cu")
		(net "NCT7904_D2-")
	)
	(segment
		(start 29.662628 -320.984372)
		(end 30.353 -320.294)
		(width 0.1397)
		(layer "F.Cu")
		(net "NCT7904_D2-")
	)
	(segment
		(start 29.61132 -153.32202)
		(end 29.5783 -153.289)
		(width 0.1397)
		(layer "F.Cu")
		(net "NCT7904_D2-")
	)
	(segment
		(start 28.452572 -320.984372)
		(end 29.662628 -320.984372)
		(width 0.1397)
		(layer "F.Cu")
		(net "NCT7904_D2-")
	)
	(segment
		(start 29.61132 -155.607766)
		(end 29.61132 -153.32202)
		(width 0.1397)
		(layer "F.Cu")
		(net "NCT7904_D2-")
	)
	(segment
		(start 29.5783 -151.7269)
		(end 29.464 -151.6126)
		(width 0.1397)
		(layer "F.Cu")
		(net "NCT7904_D2-")
	)
	(via
		(at 30.353 -320.294)
		(size 0.5588)
		(drill 0.3048)
		(layers "F.Cu" "B.Cu")
		(net "NCT7904_D2-")
	)
	(via
		(at 29.464 -151.6126)
		(size 0.5588)
		(drill 0.3048)
		(layers "F.Cu" "B.Cu")
		(net "NCT7904_D2-")
	)
	(via
		(at 31.163768 -319.483232)
		(size 0.7112)
		(drill 0.3556)
		(layers "F.Cu" "B.Cu")
		(net "NCT7904_D2-")
	)
	(segment
		(start 37.01415 -174.0662)
		(end 37.01415 -170.49115)
		(width 0.1397)
		(layer "B.Cu")
		(net "NCT7904_D2-")
	)
	(segment
		(start 34.455354 -275.932646)
		(end 34.455354 -274.410932)
		(width 0.1397)
		(layer "B.Cu")
		(net "NCT7904_D2-")
	)
	(segment
		(start 35.756342 -169.233342)
		(end 35.756342 -168.815258)
		(width 0.1397)
		(layer "B.Cu")
		(net "NCT7904_D2-")
	)
	(segment
		(start 32.131 -278.257)
		(end 34.455354 -275.932646)
		(width 0.1397)
		(layer "B.Cu")
		(net "NCT7904_D2-")
	)
	(segment
		(start 36.504626 -210.489546)
		(end 36.504626 -174.575724)
		(width 0.1397)
		(layer "B.Cu")
		(net "NCT7904_D2-")
	)
	(segment
		(start 36.27755 -168.29405)
		(end 36.27755 -158.42615)
		(width 0.1397)
		(layer "B.Cu")
		(net "NCT7904_D2-")
	)
	(segment
		(start 42.1132 -216.0905)
		(end 39.6875 -213.6648)
		(width 0.1397)
		(layer "B.Cu")
		(net "NCT7904_D2-")
	)
	(segment
		(start 42.1132 -250.317)
		(end 42.1132 -216.0905)
		(width 0.1397)
		(layer "B.Cu")
		(net "NCT7904_D2-")
	)
	(segment
		(start 39.67988 -213.6648)
		(end 36.504626 -210.489546)
		(width 0.1397)
		(layer "B.Cu")
		(net "NCT7904_D2-")
	)
	(segment
		(start 37.01415 -170.49115)
		(end 35.756342 -169.233342)
		(width 0.1397)
		(layer "B.Cu")
		(net "NCT7904_D2-")
	)
	(segment
		(start 36.27755 -158.42615)
		(end 29.464 -151.6126)
		(width 0.1397)
		(layer "B.Cu")
		(net "NCT7904_D2-")
	)
	(segment
		(start 34.925 -256.794)
		(end 40.8432 -250.8758)
		(width 0.1397)
		(layer "B.Cu")
		(net "NCT7904_D2-")
	)
	(segment
		(start 34.455354 -274.410932)
		(end 34.4551 -274.410678)
		(width 0.1397)
		(layer "B.Cu")
		(net "NCT7904_D2-")
	)
	(segment
		(start 36.504626 -174.575724)
		(end 37.01415 -174.0662)
		(width 0.1397)
		(layer "B.Cu")
		(net "NCT7904_D2-")
	)
	(segment
		(start 30.353 -320.294)
		(end 31.163768 -319.483232)
		(width 0.1397)
		(layer "B.Cu")
		(net "NCT7904_D2-")
	)
	(segment
		(start 31.163768 -319.483232)
		(end 32.131 -318.516)
		(width 0.1397)
		(layer "B.Cu")
		(net "NCT7904_D2-")
	)
	(segment
		(start 34.925 -259.0546)
		(end 34.925 -256.794)
		(width 0.1397)
		(layer "B.Cu")
		(net "NCT7904_D2-")
	)
	(segment
		(start 34.455354 -273.147536)
		(end 34.455354 -259.524246)
		(width 0.1397)
		(layer "B.Cu")
		(net "NCT7904_D2-")
	)
	(segment
		(start 32.131 -318.516)
		(end 32.131 -278.257)
		(width 0.1397)
		(layer "B.Cu")
		(net "NCT7904_D2-")
	)
	(segment
		(start 41.5544 -250.8758)
		(end 42.1132 -250.317)
		(width 0.1397)
		(layer "B.Cu")
		(net "NCT7904_D2-")
	)
	(segment
		(start 39.6875 -213.6648)
		(end 39.67988 -213.6648)
		(width 0.1397)
		(layer "B.Cu")
		(net "NCT7904_D2-")
	)
	(segment
		(start 40.8432 -250.8758)
		(end 41.5544 -250.8758)
		(width 0.1397)
		(layer "B.Cu")
		(net "NCT7904_D2-")
	)
	(segment
		(start 34.4551 -274.410678)
		(end 34.4551 -273.14779)
		(width 0.1397)
		(layer "B.Cu")
		(net "NCT7904_D2-")
	)
	(segment
		(start 34.4551 -273.14779)
		(end 34.455354 -273.147536)
		(width 0.1397)
		(layer "B.Cu")
		(net "NCT7904_D2-")
	)
	(segment
		(start 34.455354 -259.524246)
		(end 34.925 -259.0546)
		(width 0.1397)
		(layer "B.Cu")
		(net "NCT7904_D2-")
	)
	(segment
		(start 35.756342 -168.815258)
		(end 36.27755 -168.29405)
		(width 0.1397)
		(layer "B.Cu")
		(net "NCT7904_D2-")
	)
	(segment
		(start 27.5463 -154.107388)
		(end 27.5463 -151.003)
		(width 0.1397)
		(layer "F.Cu")
		(net "NCT7904_D1+")
	)
	(segment
		(start 27.559 -150.5839)
		(end 27.559 -149.225)
		(width 0.1397)
		(layer "F.Cu")
		(net "NCT7904_D1+")
	)
	(segment
		(start 26.547572 -144.999964)
		(end 27.009852 -145.462244)
		(width 0.1397)
		(layer "F.Cu")
		(net "NCT7904_D1+")
	)
	(segment
		(start 27.0256 -147.461732)
		(end 27.009852 -147.445984)
		(width 0.1397)
		(layer "F.Cu")
		(net "NCT7904_D1+")
	)
	(segment
		(start 27.3431 -150.7998)
		(end 27.559 -150.5839)
		(width 0.1397)
		(layer "F.Cu")
		(net "NCT7904_D1+")
	)
	(segment
		(start 28.11145 -155.607766)
		(end 28.11145 -154.672538)
		(width 0.1397)
		(layer "F.Cu")
		(net "NCT7904_D1+")
	)
	(segment
		(start 27.559 -149.225)
		(end 27.0256 -148.6916)
		(width 0.1397)
		(layer "F.Cu")
		(net "NCT7904_D1+")
	)
	(segment
		(start 28.11145 -154.672538)
		(end 27.5463 -154.107388)
		(width 0.1397)
		(layer "F.Cu")
		(net "NCT7904_D1+")
	)
	(segment
		(start 28.452572 -144.015714)
		(end 27.531822 -144.015714)
		(width 0.1397)
		(layer "F.Cu")
		(net "NCT7904_D1+")
	)
	(segment
		(start 27.5463 -151.003)
		(end 27.3431 -150.7998)
		(width 0.1397)
		(layer "F.Cu")
		(net "NCT7904_D1+")
	)
	(segment
		(start 27.009852 -145.462244)
		(end 27.009852 -147.445984)
		(width 0.1397)
		(layer "F.Cu")
		(net "NCT7904_D1+")
	)
	(segment
		(start 27.531822 -144.015714)
		(end 26.547572 -144.999964)
		(width 0.1397)
		(layer "F.Cu")
		(net "NCT7904_D1+")
	)
	(segment
		(start 27.0256 -148.6916)
		(end 27.0256 -147.461732)
		(width 0.1397)
		(layer "F.Cu")
		(net "NCT7904_D1+")
	)
	(via
		(at 27.009852 -147.445984)
		(size 0.7112)
		(drill 0.3556)
		(layers "F.Cu" "B.Cu")
		(net "NCT7904_D1+")
	)
	(segment
		(start 28.61183 -154.544268)
		(end 27.9908 -153.923238)
		(width 0.1397)
		(layer "F.Cu")
		(net "NCT7904_D1-")
	)
	(segment
		(start 27.9908 -153.923238)
		(end 27.9908 -151.0411)
		(width 0.1397)
		(layer "F.Cu")
		(net "NCT7904_D1-")
	)
	(segment
		(start 28.067 -150.6347)
		(end 28.067 -148.950172)
		(width 0.1397)
		(layer "F.Cu")
		(net "NCT7904_D1-")
	)
	(segment
		(start 28.067 -148.950172)
		(end 28.452572 -148.5646)
		(width 0.1397)
		(layer "F.Cu")
		(net "NCT7904_D1-")
	)
	(segment
		(start 28.61183 -155.607766)
		(end 28.61183 -154.544268)
		(width 0.1397)
		(layer "F.Cu")
		(net "NCT7904_D1-")
	)
	(segment
		(start 27.9908 -151.0411)
		(end 28.2321 -150.7998)
		(width 0.1397)
		(layer "F.Cu")
		(net "NCT7904_D1-")
	)
	(segment
		(start 28.452572 -145.984214)
		(end 28.452572 -148.5646)
		(width 0.1397)
		(layer "F.Cu")
		(net "NCT7904_D1-")
	)
	(segment
		(start 28.2321 -150.7998)
		(end 28.067 -150.6347)
		(width 0.1397)
		(layer "F.Cu")
		(net "NCT7904_D1-")
	)
	(via
		(at 28.452572 -148.5646)
		(size 0.7112)
		(drill 0.3556)
		(layers "F.Cu" "B.Cu")
		(net "NCT7904_D1-")
	)
	(segment
		(start 29.1592 -253.42088)
		(end 29.59608 -252.984)
		(width 0.1397)
		(layer "F.Cu")
		(net "EEPROM_WP")
	)
	(segment
		(start 29.1592 -253.4539)
		(end 29.1592 -253.42088)
		(width 0.1397)
		(layer "F.Cu")
		(net "EEPROM_WP")
	)
	(segment
		(start 28.0416 -253.4539)
		(end 29.1592 -253.4539)
		(width 0.1397)
		(layer "F.Cu")
		(net "EEPROM_WP")
	)
	(segment
		(start 29.59608 -252.984)
		(end 29.59608 -250.2408)
		(width 0.1397)
		(layer "F.Cu")
		(net "EEPROM_WP")
	)
	(via
		(at 28.0416 -253.4539)
		(size 0.7112)
		(drill 0.3556)
		(layers "F.Cu" "B.Cu")
		(net "EEPROM_WP")
	)
	(segment
		(start 8.509 -61.3918)
		(end 8.509 -63.4365)
		(width 0.1397)
		(layer "F.Cu")
		(net "LED_DR_LED5_K")
	)
	(segment
		(start 8.509 -63.4365)
		(end 9.4488 -64.3763)
		(width 0.1397)
		(layer "F.Cu")
		(net "LED_DR_LED5_K")
	)
	(segment
		(start 6.477 -59.3598)
		(end 8.509 -61.3918)
		(width 0.1397)
		(layer "F.Cu")
		(net "LED_DR_LED5_K")
	)
	(segment
		(start 7.323836 -56.099964)
		(end 6.477 -56.9468)
		(width 0.1397)
		(layer "F.Cu")
		(net "LED_DR_LED5_K")
	)
	(segment
		(start 7.949946 -56.099964)
		(end 7.323836 -56.099964)
		(width 0.1397)
		(layer "F.Cu")
		(net "LED_DR_LED5_K")
	)
	(segment
		(start 6.477 -56.9468)
		(end 6.477 -59.3598)
		(width 0.1397)
		(layer "F.Cu")
		(net "LED_DR_LED5_K")
	)
	(segment
		(start 7.949946 -232.134918)
		(end 8.580628 -232.7656)
		(width 0.1397)
		(layer "F.Cu")
		(net "LED_DR_LED3_K")
	)
	(segment
		(start 8.580628 -232.7656)
		(end 11.5189 -232.7656)
		(width 0.1397)
		(layer "F.Cu")
		(net "LED_DR_LED3_K")
	)
	(segment
		(start 7.949946 -267.865098)
		(end 7.140702 -267.865098)
		(width 0.1397)
		(layer "F.Cu")
		(net "LED_DR_LED2_K")
	)
	(segment
		(start 7.140702 -267.865098)
		(end 6.1976 -268.8082)
		(width 0.1397)
		(layer "F.Cu")
		(net "LED_DR_LED2_K")
	)
	(segment
		(start 6.1976 -272.986246)
		(end 7.6327 -274.421346)
		(width 0.1397)
		(layer "F.Cu")
		(net "LED_DR_LED2_K")
	)
	(segment
		(start 7.6327 -274.421346)
		(end 7.6327 -275.2344)
		(width 0.1397)
		(layer "F.Cu")
		(net "LED_DR_LED2_K")
	)
	(segment
		(start 6.1976 -268.8082)
		(end 6.1976 -272.986246)
		(width 0.1397)
		(layer "F.Cu")
		(net "LED_DR_LED2_K")
	)
	(segment
		(start 6.4262 -415.7853)
		(end 5.6007 -416.6108)
		(width 0.1397)
		(layer "F.Cu")
		(net "LED_DR_LED1_K")
	)
	(segment
		(start 7.949946 -411.465014)
		(end 6.4262 -412.98876)
		(width 0.1397)
		(layer "F.Cu")
		(net "LED_DR_LED1_K")
	)
	(segment
		(start 6.4262 -412.98876)
		(end 6.4262 -415.7853)
		(width 0.1397)
		(layer "F.Cu")
		(net "LED_DR_LED1_K")
	)
	(segment
		(start 24.9174 -361.061)
		(end 24.5999 -360.7435)
		(width 0.1397)
		(layer "F.Cu")
		(net "ADM1276_ADR")
	)
	(segment
		(start 27.813 -365.252)
		(end 28.59405 -365.252)
		(width 0.1397)
		(layer "F.Cu")
		(net "ADM1276_ADR")
	)
	(segment
		(start 25.019 -362.8136)
		(end 24.9174 -362.712)
		(width 0.1397)
		(layer "F.Cu")
		(net "ADM1276_ADR")
	)
	(segment
		(start 24.9174 -362.712)
		(end 24.9174 -361.061)
		(width 0.1397)
		(layer "F.Cu")
		(net "ADM1276_ADR")
	)
	(segment
		(start 28.59405 -365.252)
		(end 29.068014 -365.725964)
		(width 0.1397)
		(layer "F.Cu")
		(net "ADM1276_ADR")
	)
	(segment
		(start 29.068014 -365.725964)
		(end 29.068014 -366.3696)
		(width 0.1397)
		(layer "F.Cu")
		(net "ADM1276_ADR")
	)
	(segment
		(start 24.5999 -360.7435)
		(end 24.2824 -360.7435)
		(width 0.1397)
		(layer "F.Cu")
		(net "ADM1276_ADR")
	)
	(segment
		(start 24.2824 -360.7435)
		(end 23.241 -360.7435)
		(width 0.1397)
		(layer "F.Cu")
		(net "ADM1276_ADR")
	)
	(via
		(at 25.019 -362.8136)
		(size 0.7112)
		(drill 0.4064)
		(layers "F.Cu" "B.Cu")
		(net "ADM1276_ADR")
	)
	(via
		(at 25.8064 -363.474)
		(size 0.7112)
		(drill 0.3556)
		(layers "F.Cu" "B.Cu")
		(net "ADM1276_ADR")
	)
	(via
		(at 27.813 -365.252)
		(size 0.7112)
		(drill 0.4064)
		(layers "F.Cu" "B.Cu")
		(net "ADM1276_ADR")
	)
	(segment
		(start 25.146 -362.8136)
		(end 25.8064 -363.474)
		(width 0.1397)
		(layer "B.Cu")
		(net "ADM1276_ADR")
	)
	(segment
		(start 26.0604 -363.728)
		(end 25.8064 -363.474)
		(width 0.1397)
		(layer "B.Cu")
		(net "ADM1276_ADR")
	)
	(segment
		(start 27.813 -365.252)
		(end 26.289 -363.728)
		(width 0.1397)
		(layer "B.Cu")
		(net "ADM1276_ADR")
	)
	(segment
		(start 26.289 -363.728)
		(end 26.0604 -363.728)
		(width 0.1397)
		(layer "B.Cu")
		(net "ADM1276_ADR")
	)
	(segment
		(start 25.019 -362.8136)
		(end 25.146 -362.8136)
		(width 0.1397)
		(layer "B.Cu")
		(net "ADM1276_ADR")
	)
	(segment
		(start 7.949946 -443.900052)
		(end 6.5786 -442.528706)
		(width 0.1397)
		(layer "F.Cu")
		(net "LED_DR_LED0_K")
	)
	(segment
		(start 6.5786 -442.528706)
		(end 6.5786 -438.1881)
		(width 0.1397)
		(layer "F.Cu")
		(net "LED_DR_LED0_K")
	)
	(segment
		(start 37.5666 -253.9111)
		(end 37.5666 -252.7046)
		(width 0.1397)
		(layer "F.Cu")
		(net "LED_DR_LED7_RESERVE")
	)
	(segment
		(start 37.48532 -249.3518)
		(end 37.48532 -252.62332)
		(width 0.1397)
		(layer "F.Cu")
		(net "LED_DR_LED7_RESERVE")
	)
	(segment
		(start 37.5666 -252.7046)
		(end 37.4904 -252.6284)
		(width 0.1397)
		(layer "F.Cu")
		(net "LED_DR_LED7_RESERVE")
	)
	(segment
		(start 37.48532 -252.62332)
		(end 37.4904 -252.6284)
		(width 0.1397)
		(layer "F.Cu")
		(net "LED_DR_LED7_RESERVE")
	)
	(segment
		(start 30.1117 -164.091366)
		(end 30.1117 -165.5953)
		(width 0.1397)
		(layer "F.Cu")
		(net "FANIN_12")
	)
	(segment
		(start 30.1117 -165.5953)
		(end 29.8196 -165.8874)
		(width 0.1397)
		(layer "F.Cu")
		(net "FANIN_12")
	)
	(segment
		(start 20.701 -19.177)
		(end 20.701 -18.161)
		(width 0.1397)
		(layer "F.Cu")
		(net "FANIN_12")
	)
	(segment
		(start 21.7805 -18.161)
		(end 20.701 -18.161)
		(width 0.1397)
		(layer "F.Cu")
		(net "FANIN_12")
	)
	(via
		(at 20.701 -19.177)
		(size 0.5588)
		(drill 0.3048)
		(layers "F.Cu" "B.Cu")
		(net "FANIN_12")
	)
	(via
		(at 29.8196 -165.8874)
		(size 0.5588)
		(drill 0.3048)
		(layers "F.Cu" "B.Cu")
		(net "FANIN_12")
	)
	(via
		(at 14.922246 -25.692354)
		(size 0.7112)
		(drill 0.3556)
		(layers "F.Cu" "B.Cu")
		(net "FANIN_12")
	)
	(segment
		(start 9.270746 -123.876308)
		(end 9.270746 -124.2441)
		(width 0.1397)
		(layer "B.Cu")
		(net "FANIN_12")
	)
	(segment
		(start 9.270492 -123.507754)
		(end 9.270492 -123.876054)
		(width 0.1397)
		(layer "B.Cu")
		(net "FANIN_12")
	)
	(segment
		(start 14.186154 -26.428446)
		(end 14.186154 -46.665134)
		(width 0.1397)
		(layer "B.Cu")
		(net "FANIN_12")
	)
	(segment
		(start 13.10005 -52.57165)
		(end 13.10005 -53.765958)
		(width 0.1397)
		(layer "B.Cu")
		(net "FANIN_12")
	)
	(segment
		(start 12.79525 -64.97955)
		(end 9.7028 -68.072)
		(width 0.1397)
		(layer "B.Cu")
		(net "FANIN_12")
	)
	(segment
		(start 12.64285 -48.208438)
		(end 12.64285 -52.11445)
		(width 0.1397)
		(layer "B.Cu")
		(net "FANIN_12")
	)
	(segment
		(start 13.10005 -53.765958)
		(end 12.65555 -54.210458)
		(width 0.1397)
		(layer "B.Cu")
		(net "FANIN_12")
	)
	(segment
		(start 10.514584 -113.130584)
		(end 10.514584 -122.263662)
		(width 0.1397)
		(layer "B.Cu")
		(net "FANIN_12")
	)
	(segment
		(start 9.245346 -110.000796)
		(end 9.245092 -110.00105)
		(width 0.1397)
		(layer "B.Cu")
		(net "FANIN_12")
	)
	(segment
		(start 9.245346 -92.1512)
		(end 9.245346 -110.000796)
		(width 0.1397)
		(layer "B.Cu")
		(net "FANIN_12")
	)
	(segment
		(start 29.8196 -165.614096)
		(end 29.8196 -165.8874)
		(width 0.1397)
		(layer "B.Cu")
		(net "FANIN_12")
	)
	(segment
		(start 9.245346 -111.861346)
		(end 10.514584 -113.130584)
		(width 0.1397)
		(layer "B.Cu")
		(net "FANIN_12")
	)
	(segment
		(start 10.514584 -122.263662)
		(end 9.270492 -123.507754)
		(width 0.1397)
		(layer "B.Cu")
		(net "FANIN_12")
	)
	(segment
		(start 12.65555 -54.210458)
		(end 12.65555 -60.217558)
		(width 0.1397)
		(layer "B.Cu")
		(net "FANIN_12")
	)
	(segment
		(start 9.245346 -111.842804)
		(end 9.245346 -111.861346)
		(width 0.1397)
		(layer "B.Cu")
		(net "FANIN_12")
	)
	(segment
		(start 20.701 -19.177)
		(end 20.701 -19.9136)
		(width 0.1397)
		(layer "B.Cu")
		(net "FANIN_12")
	)
	(segment
		(start 15.741142 -148.6154)
		(end 16.453104 -148.6154)
		(width 0.1397)
		(layer "B.Cu")
		(net "FANIN_12")
	)
	(segment
		(start 12.65555 -60.217558)
		(end 12.79525 -60.357258)
		(width 0.1397)
		(layer "B.Cu")
		(net "FANIN_12")
	)
	(segment
		(start 9.271 -133.2992)
		(end 12.3444 -136.3726)
		(width 0.1397)
		(layer "B.Cu")
		(net "FANIN_12")
	)
	(segment
		(start 19.05 -151.212296)
		(end 19.05 -154.844496)
		(width 0.1397)
		(layer "B.Cu")
		(net "FANIN_12")
	)
	(segment
		(start 20.701 -19.9136)
		(end 14.922246 -25.692354)
		(width 0.1397)
		(layer "B.Cu")
		(net "FANIN_12")
	)
	(segment
		(start 9.271 -124.244354)
		(end 9.271 -133.2992)
		(width 0.1397)
		(layer "B.Cu")
		(net "FANIN_12")
	)
	(segment
		(start 12.3444 -143.0274)
		(end 15.0114 -145.6944)
		(width 0.1397)
		(layer "B.Cu")
		(net "FANIN_12")
	)
	(segment
		(start 14.186154 -46.665134)
		(end 12.64285 -48.208438)
		(width 0.1397)
		(layer "B.Cu")
		(net "FANIN_12")
	)
	(segment
		(start 9.245092 -111.84255)
		(end 9.245346 -111.842804)
		(width 0.1397)
		(layer "B.Cu")
		(net "FANIN_12")
	)
	(segment
		(start 12.3444 -136.3726)
		(end 12.3444 -143.0274)
		(width 0.1397)
		(layer "B.Cu")
		(net "FANIN_12")
	)
	(segment
		(start 16.453104 -148.6154)
		(end 19.05 -151.212296)
		(width 0.1397)
		(layer "B.Cu")
		(net "FANIN_12")
	)
	(segment
		(start 15.0114 -145.6944)
		(end 15.0114 -147.885658)
		(width 0.1397)
		(layer "B.Cu")
		(net "FANIN_12")
	)
	(segment
		(start 9.2456 -92.150438)
		(end 9.2456 -92.150946)
		(width 0.1397)
		(layer "B.Cu")
		(net "FANIN_12")
	)
	(segment
		(start 15.0114 -147.885658)
		(end 15.741142 -148.6154)
		(width 0.1397)
		(layer "B.Cu")
		(net "FANIN_12")
	)
	(segment
		(start 9.7028 -91.693238)
		(end 9.2456 -92.150438)
		(width 0.1397)
		(layer "B.Cu")
		(net "FANIN_12")
	)
	(segment
		(start 9.270746 -124.2441)
		(end 9.271 -124.244354)
		(width 0.1397)
		(layer "B.Cu")
		(net "FANIN_12")
	)
	(segment
		(start 14.922246 -25.692354)
		(end 14.186154 -26.428446)
		(width 0.1397)
		(layer "B.Cu")
		(net "FANIN_12")
	)
	(segment
		(start 12.79525 -60.357258)
		(end 12.79525 -64.97955)
		(width 0.1397)
		(layer "B.Cu")
		(net "FANIN_12")
	)
	(segment
		(start 9.2456 -92.150946)
		(end 9.245346 -92.1512)
		(width 0.1397)
		(layer "B.Cu")
		(net "FANIN_12")
	)
	(segment
		(start 9.245092 -110.00105)
		(end 9.245092 -111.84255)
		(width 0.1397)
		(layer "B.Cu")
		(net "FANIN_12")
	)
	(segment
		(start 19.05 -154.844496)
		(end 29.8196 -165.614096)
		(width 0.1397)
		(layer "B.Cu")
		(net "FANIN_12")
	)
	(segment
		(start 12.64285 -52.11445)
		(end 13.10005 -52.57165)
		(width 0.1397)
		(layer "B.Cu")
		(net "FANIN_12")
	)
	(segment
		(start 9.7028 -68.072)
		(end 9.7028 -91.693238)
		(width 0.1397)
		(layer "B.Cu")
		(net "FANIN_12")
	)
	(segment
		(start 9.270492 -123.876054)
		(end 9.270746 -123.876308)
		(width 0.1397)
		(layer "B.Cu")
		(net "FANIN_12")
	)
	(segment
		(start 21.347938 -15.595092)
		(end 22.389846 -15.595092)
		(width 0.1397)
		(layer "F.Cu")
		(net "FANIN_11")
	)
	(segment
		(start 22.389846 -15.595092)
		(end 22.416262 -15.621508)
		(width 0.1397)
		(layer "F.Cu")
		(net "FANIN_11")
	)
	(segment
		(start 31.115 -166.0271)
		(end 31.11246 -166.02456)
		(width 0.1397)
		(layer "F.Cu")
		(net "FANIN_11")
	)
	(segment
		(start 22.416262 -15.621508)
		(end 22.416262 -16.637)
		(width 0.1397)
		(layer "F.Cu")
		(net "FANIN_11")
	)
	(segment
		(start 31.11246 -166.02456)
		(end 31.11246 -164.091366)
		(width 0.1397)
		(layer "F.Cu")
		(net "FANIN_11")
	)
	(via
		(at 31.115 -166.0271)
		(size 0.5588)
		(drill 0.3048)
		(layers "F.Cu" "B.Cu")
		(net "FANIN_11")
	)
	(via
		(at 22.416262 -16.637)
		(size 0.5588)
		(drill 0.3048)
		(layers "F.Cu" "B.Cu")
		(net "FANIN_11")
	)
	(via
		(at 19.9136 -21.8694)
		(size 0.7112)
		(drill 0.3556)
		(layers "F.Cu" "B.Cu")
		(net "FANIN_11")
	)
	(segment
		(start 13.18895 -54.83225)
		(end 14.24305 -53.77815)
		(width 0.1397)
		(layer "B.Cu")
		(net "FANIN_11")
	)
	(segment
		(start 13.81125 -58.69305)
		(end 13.18895 -58.07075)
		(width 0.1397)
		(layer "B.Cu")
		(net "FANIN_11")
	)
	(segment
		(start 10.959084 -122.448066)
		(end 10.959084 -112.927892)
		(width 0.1397)
		(layer "B.Cu")
		(net "FANIN_11")
	)
	(segment
		(start 9.715246 -123.691904)
		(end 10.959084 -122.448066)
		(width 0.1397)
		(layer "B.Cu")
		(net "FANIN_11")
	)
	(segment
		(start 9.689846 -108.908088)
		(end 9.6901 -108.907834)
		(width 0.1397)
		(layer "B.Cu")
		(net "FANIN_11")
	)
	(segment
		(start 15.4686 -145.5166)
		(end 12.7889 -142.8369)
		(width 0.1397)
		(layer "B.Cu")
		(net "FANIN_11")
	)
	(segment
		(start 19.8882 -21.8694)
		(end 19.9136 -21.8694)
		(width 0.1397)
		(layer "B.Cu")
		(net "FANIN_11")
	)
	(segment
		(start 9.7155 -124.060204)
		(end 9.715246 -124.05995)
		(width 0.1397)
		(layer "B.Cu")
		(net "FANIN_11")
	)
	(segment
		(start 13.81125 -64.598804)
		(end 13.81125 -58.69305)
		(width 0.1397)
		(layer "B.Cu")
		(net "FANIN_11")
	)
	(segment
		(start 14.6304 -46.849792)
		(end 14.6304 -46.849538)
		(width 0.1397)
		(layer "B.Cu")
		(net "FANIN_11")
	)
	(segment
		(start 31.115 -166.0271)
		(end 19.5072 -154.4193)
		(width 0.1397)
		(layer "B.Cu")
		(net "FANIN_11")
	)
	(segment
		(start 9.6901 -108.907834)
		(end 9.6901 -92.334588)
		(width 0.1397)
		(layer "B.Cu")
		(net "FANIN_11")
	)
	(segment
		(start 9.689846 -110.184946)
		(end 9.689846 -108.908088)
		(width 0.1397)
		(layer "B.Cu")
		(net "FANIN_11")
	)
	(segment
		(start 9.689592 -110.1852)
		(end 9.689846 -110.184946)
		(width 0.1397)
		(layer "B.Cu")
		(net "FANIN_11")
	)
	(segment
		(start 10.1473 -68.262754)
		(end 13.81125 -64.598804)
		(width 0.1397)
		(layer "B.Cu")
		(net "FANIN_11")
	)
	(segment
		(start 14.630654 -46.849284)
		(end 14.630654 -27.126946)
		(width 0.1397)
		(layer "B.Cu")
		(net "FANIN_11")
	)
	(segment
		(start 15.912592 -148.1582)
		(end 15.4686 -147.714208)
		(width 0.1397)
		(layer "B.Cu")
		(net "FANIN_11")
	)
	(segment
		(start 12.7889 -136.1567)
		(end 9.7155 -133.0833)
		(width 0.1397)
		(layer "B.Cu")
		(net "FANIN_11")
	)
	(segment
		(start 9.7155 -133.0833)
		(end 9.7155 -124.060204)
		(width 0.1397)
		(layer "B.Cu")
		(net "FANIN_11")
	)
	(segment
		(start 14.6304 -46.849538)
		(end 14.630654 -46.849284)
		(width 0.1397)
		(layer "B.Cu")
		(net "FANIN_11")
	)
	(segment
		(start 14.630654 -27.126946)
		(end 19.8882 -21.8694)
		(width 0.1397)
		(layer "B.Cu")
		(net "FANIN_11")
	)
	(segment
		(start 14.24305 -53.77815)
		(end 14.24305 -52.330858)
		(width 0.1397)
		(layer "B.Cu")
		(net "FANIN_11")
	)
	(segment
		(start 21.463 -20.32)
		(end 21.463 -17.590262)
		(width 0.1397)
		(layer "B.Cu")
		(net "FANIN_11")
	)
	(segment
		(start 13.08735 -48.392842)
		(end 14.6304 -46.849792)
		(width 0.1397)
		(layer "B.Cu")
		(net "FANIN_11")
	)
	(segment
		(start 19.5072 -154.4193)
		(end 19.5072 -151.040846)
		(width 0.1397)
		(layer "B.Cu")
		(net "FANIN_11")
	)
	(segment
		(start 14.24305 -52.330858)
		(end 13.08735 -51.175158)
		(width 0.1397)
		(layer "B.Cu")
		(net "FANIN_11")
	)
	(segment
		(start 12.7889 -142.8369)
		(end 12.7889 -136.1567)
		(width 0.1397)
		(layer "B.Cu")
		(net "FANIN_11")
	)
	(segment
		(start 16.624554 -148.1582)
		(end 15.912592 -148.1582)
		(width 0.1397)
		(layer "B.Cu")
		(net "FANIN_11")
	)
	(segment
		(start 13.18895 -58.07075)
		(end 13.18895 -54.83225)
		(width 0.1397)
		(layer "B.Cu")
		(net "FANIN_11")
	)
	(segment
		(start 19.5072 -151.040846)
		(end 16.624554 -148.1582)
		(width 0.1397)
		(layer "B.Cu")
		(net "FANIN_11")
	)
	(segment
		(start 13.08735 -51.175158)
		(end 13.08735 -48.392842)
		(width 0.1397)
		(layer "B.Cu")
		(net "FANIN_11")
	)
	(segment
		(start 9.689592 -111.6584)
		(end 9.689592 -110.1852)
		(width 0.1397)
		(layer "B.Cu")
		(net "FANIN_11")
	)
	(segment
		(start 15.4686 -147.714208)
		(end 15.4686 -145.5166)
		(width 0.1397)
		(layer "B.Cu")
		(net "FANIN_11")
	)
	(segment
		(start 19.9136 -21.8694)
		(end 21.463 -20.32)
		(width 0.1397)
		(layer "B.Cu")
		(net "FANIN_11")
	)
	(segment
		(start 21.463 -17.590262)
		(end 22.416262 -16.637)
		(width 0.1397)
		(layer "B.Cu")
		(net "FANIN_11")
	)
	(segment
		(start 9.715246 -124.05995)
		(end 9.715246 -123.691904)
		(width 0.1397)
		(layer "B.Cu")
		(net "FANIN_11")
	)
	(segment
		(start 10.959084 -112.927892)
		(end 9.689592 -111.6584)
		(width 0.1397)
		(layer "B.Cu")
		(net "FANIN_11")
	)
	(segment
		(start 10.1473 -91.877388)
		(end 10.1473 -68.262754)
		(width 0.1397)
		(layer "B.Cu")
		(net "FANIN_11")
	)
	(segment
		(start 9.6901 -92.334588)
		(end 10.1473 -91.877388)
		(width 0.1397)
		(layer "B.Cu")
		(net "FANIN_11")
	)
	(segment
		(start 25.1206 -209.0166)
		(end 18.3896 -209.0166)
		(width 0.1397)
		(layer "F.Cu")
		(net "PWM_OUT")
	)
	(segment
		(start 23.674324 -173.33341)
		(end 22.328886 -173.33341)
		(width 0.1397)
		(layer "F.Cu")
		(net "PWM_OUT")
	)
	(segment
		(start 25.0698 -222.7834)
		(end 25.781 -222.0722)
		(width 0.1397)
		(layer "F.Cu")
		(net "PWM_OUT")
	)
	(segment
		(start 25.781 -168.9608)
		(end 26.5176 -168.9608)
		(width 0.1397)
		(layer "F.Cu")
		(net "PWM_OUT")
	)
	(segment
		(start 25.781 -222.0722)
		(end 25.781 -222.0468)
		(width 0.1397)
		(layer "F.Cu")
		(net "PWM_OUT")
	)
	(segment
		(start 25.4508 -168.6306)
		(end 25.781 -168.9608)
		(width 0.1397)
		(layer "F.Cu")
		(net "PWM_OUT")
	)
	(segment
		(start 22.328886 -173.33341)
		(end 21.995638 -173.000162)
		(width 0.1397)
		(layer "F.Cu")
		(net "PWM_OUT")
	)
	(segment
		(start 26.5176 -168.9608)
		(end 27.3812 -169.8244)
		(width 0.1397)
		(layer "F.Cu")
		(net "PWM_OUT")
	)
	(segment
		(start 27.3812 -169.8244)
		(end 28.1559 -169.8244)
		(width 0.1397)
		(layer "F.Cu")
		(net "PWM_OUT")
	)
	(segment
		(start 28.1559 -169.8244)
		(end 28.6639 -170.3324)
		(width 0.1397)
		(layer "F.Cu")
		(net "PWM_OUT")
	)
	(via
		(at 21.995638 -173.000162)
		(size 0.5588)
		(drill 0.3048)
		(layers "F.Cu" "B.Cu")
		(net "PWM_OUT")
	)
	(via
		(at 25.781 -222.0468)
		(size 0.5588)
		(drill 0.3048)
		(layers "F.Cu" "B.Cu")
		(net "PWM_OUT")
	)
	(via
		(at 25.0698 -222.7834)
		(size 0.7112)
		(drill 0.3556)
		(layers "F.Cu" "B.Cu")
		(net "PWM_OUT")
	)
	(via
		(at 25.1206 -209.0166)
		(size 0.5588)
		(drill 0.3048)
		(layers "F.Cu" "B.Cu")
		(net "PWM_OUT")
	)
	(via
		(at 25.4508 -168.6306)
		(size 0.5588)
		(drill 0.3048)
		(layers "F.Cu" "B.Cu")
		(net "PWM_OUT")
	)
	(via
		(at 18.3896 -209.0166)
		(size 0.5588)
		(drill 0.3048)
		(layers "F.Cu" "B.Cu")
		(net "PWM_OUT")
	)
	(segment
		(start 24.99995 -221.26575)
		(end 25.781 -222.0468)
		(width 0.1397)
		(layer "B.Cu")
		(net "PWM_OUT")
	)
	(segment
		(start 25.361646 -168.6306)
		(end 23.583646 -170.4086)
		(width 0.1397)
		(layer "B.Cu")
		(net "PWM_OUT")
	)
	(segment
		(start 18.3896 -209.0166)
		(end 18.3896 -194.57035)
		(width 0.1397)
		(layer "B.Cu")
		(net "PWM_OUT")
	)
	(segment
		(start 25.1206 -209.0166)
		(end 25.1206 -212.09)
		(width 0.1397)
		(layer "B.Cu")
		(net "PWM_OUT")
	)
	(segment
		(start 21.995638 -174.82693)
		(end 21.995638 -173.000162)
		(width 0.1397)
		(layer "B.Cu")
		(net "PWM_OUT")
	)
	(segment
		(start 25.1206 -212.09)
		(end 24.99995 -212.21065)
		(width 0.1397)
		(layer "B.Cu")
		(net "PWM_OUT")
	)
	(segment
		(start 24.99995 -212.21065)
		(end 24.99995 -221.26575)
		(width 0.1397)
		(layer "B.Cu")
		(net "PWM_OUT")
	)
	(segment
		(start 25.4508 -168.6306)
		(end 25.361646 -168.6306)
		(width 0.1397)
		(layer "B.Cu")
		(net "PWM_OUT")
	)
	(segment
		(start 21.06295 -175.759618)
		(end 21.995638 -174.82693)
		(width 0.1397)
		(layer "B.Cu")
		(net "PWM_OUT")
	)
	(segment
		(start 23.583646 -171.412154)
		(end 21.995638 -173.000162)
		(width 0.1397)
		(layer "B.Cu")
		(net "PWM_OUT")
	)
	(segment
		(start 21.06295 -191.897)
		(end 21.06295 -175.759618)
		(width 0.1397)
		(layer "B.Cu")
		(net "PWM_OUT")
	)
	(segment
		(start 18.3896 -194.57035)
		(end 21.06295 -191.897)
		(width 0.1397)
		(layer "B.Cu")
		(net "PWM_OUT")
	)
	(segment
		(start 23.583646 -170.4086)
		(end 23.583646 -171.412154)
		(width 0.1397)
		(layer "B.Cu")
		(net "PWM_OUT")
	)
	(segment
		(start 21.3741 -173.4566)
		(end 21.1963 -173.2788)
		(width 0.1397)
		(layer "F.Cu")
		(net "THERMHOT#")
	)
	(segment
		(start 21.3741 -174.3456)
		(end 21.3741 -173.4566)
		(width 0.1397)
		(layer "F.Cu")
		(net "THERMHOT#")
	)
	(segment
		(start 23.674324 -174.60341)
		(end 22.47519 -174.60341)
		(width 0.1397)
		(layer "F.Cu")
		(net "THERMHOT#")
	)
	(segment
		(start 22.47519 -174.60341)
		(end 21.844 -175.2346)
		(width 0.1397)
		(layer "F.Cu")
		(net "THERMHOT#")
	)
	(segment
		(start 21.3741 -174.3456)
		(end 21.3741 -174.7647)
		(width 0.1397)
		(layer "F.Cu")
		(net "THERMHOT#")
	)
	(segment
		(start 21.3741 -174.7647)
		(end 21.844 -175.2346)
		(width 0.1397)
		(layer "F.Cu")
		(net "THERMHOT#")
	)
	(via
		(at 21.844 -175.2346)
		(size 0.7112)
		(drill 0.3556)
		(layers "F.Cu" "B.Cu")
		(net "THERMHOT#")
	)
	(segment
		(start 25.2476 -368.4778)
		(end 25.3238 -368.4778)
		(width 0.508)
		(layer "F.Cu")
		(net "ADM1276_ISET")
	)
	(segment
		(start 24.545798 -367.775998)
		(end 25.2476 -368.4778)
		(width 0.508)
		(layer "F.Cu")
		(net "ADM1276_ISET")
	)
	(segment
		(start 24.0665 -365.506)
		(end 24.0665 -366.4712)
		(width 0.508)
		(layer "F.Cu")
		(net "ADM1276_ISET")
	)
	(segment
		(start 24.0665 -367.411)
		(end 24.1554 -367.411)
		(width 0.508)
		(layer "F.Cu")
		(net "ADM1276_ISET")
	)
	(segment
		(start 24.1554 -367.411)
		(end 24.520398 -367.775998)
		(width 0.508)
		(layer "F.Cu")
		(net "ADM1276_ISET")
	)
	(segment
		(start 25.3238 -368.4778)
		(end 25.654 -368.808)
		(width 0.381)
		(layer "F.Cu")
		(net "ADM1276_ISET")
	)
	(segment
		(start 25.654 -368.808)
		(end 27.2796 -368.808)
		(width 0.381)
		(layer "F.Cu")
		(net "ADM1276_ISET")
	)
	(segment
		(start 24.0665 -366.4712)
		(end 24.0665 -367.411)
		(width 0.508)
		(layer "F.Cu")
		(net "ADM1276_ISET")
	)
	(segment
		(start 24.520398 -367.775998)
		(end 24.545798 -367.775998)
		(width 0.508)
		(layer "F.Cu")
		(net "ADM1276_ISET")
	)
	(via
		(at 25.3238 -368.4778)
		(size 0.7112)
		(drill 0.3556)
		(layers "F.Cu" "B.Cu")
		(net "ADM1276_ISET")
	)
	(segment
		(start 38.7858 -241.940334)
		(end 38.797738 -241.928396)
		(width 0.1397)
		(layer "F.Cu")
		(net "LED_DR_LED3")
	)
	(segment
		(start 7.949946 -234.674918)
		(end 9.071864 -233.553)
		(width 0.1397)
		(layer "F.Cu")
		(net "LED_DR_LED3")
	)
	(segment
		(start 38.797738 -241.928396)
		(end 39.059104 -241.928396)
		(width 0.1397)
		(layer "F.Cu")
		(net "LED_DR_LED3")
	)
	(segment
		(start 37.465 -228.727)
		(end 37.211 -228.473)
		(width 0.1397)
		(layer "F.Cu")
		(net "LED_DR_LED3")
	)
	(segment
		(start 38.7858 -243.713)
		(end 38.7858 -241.940334)
		(width 0.1397)
		(layer "F.Cu")
		(net "LED_DR_LED3")
	)
	(segment
		(start 9.071864 -233.553)
		(end 14.8844 -233.553)
		(width 0.1397)
		(layer "F.Cu")
		(net "LED_DR_LED3")
	)
	(segment
		(start 39.059104 -241.928396)
		(end 39.878 -241.1095)
		(width 0.1397)
		(layer "F.Cu")
		(net "LED_DR_LED3")
	)
	(segment
		(start 16.2814 -232.156)
		(end 16.2814 -231.8639)
		(width 0.1397)
		(layer "F.Cu")
		(net "LED_DR_LED3")
	)
	(segment
		(start 16.2941 -231.8639)
		(end 19.431 -228.727)
		(width 0.1397)
		(layer "F.Cu")
		(net "LED_DR_LED3")
	)
	(segment
		(start 14.8844 -233.553)
		(end 16.2814 -232.156)
		(width 0.1397)
		(layer "F.Cu")
		(net "LED_DR_LED3")
	)
	(segment
		(start 19.685 -228.473)
		(end 19.431 -228.727)
		(width 0.1397)
		(layer "F.Cu")
		(net "LED_DR_LED3")
	)
	(segment
		(start 16.2814 -231.8639)
		(end 16.2941 -231.8639)
		(width 0.1397)
		(layer "F.Cu")
		(net "LED_DR_LED3")
	)
	(segment
		(start 37.211 -228.473)
		(end 19.685 -228.473)
		(width 0.1397)
		(layer "F.Cu")
		(net "LED_DR_LED3")
	)
	(via
		(at 19.431 -228.727)
		(size 0.7112)
		(drill 0.3556)
		(layers "F.Cu" "B.Cu")
		(net "LED_DR_LED3")
	)
	(via
		(at 38.797738 -241.928396)
		(size 0.5588)
		(drill 0.3048)
		(layers "F.Cu" "B.Cu")
		(net "LED_DR_LED3")
	)
	(via
		(at 37.465 -228.727)
		(size 0.5588)
		(drill 0.3048)
		(layers "F.Cu" "B.Cu")
		(net "LED_DR_LED3")
	)
	(segment
		(start 38.862 -241.8588)
		(end 38.797738 -241.923062)
		(width 0.1397)
		(layer "B.Cu")
		(net "LED_DR_LED3")
	)
	(segment
		(start 38.862 -241.427)
		(end 38.862 -241.8588)
		(width 0.1397)
		(layer "B.Cu")
		(net "LED_DR_LED3")
	)
	(segment
		(start 38.797738 -241.923062)
		(end 38.797738 -241.928396)
		(width 0.1397)
		(layer "B.Cu")
		(net "LED_DR_LED3")
	)
	(segment
		(start 37.49675 -240.06175)
		(end 38.862 -241.427)
		(width 0.1397)
		(layer "B.Cu")
		(net "LED_DR_LED3")
	)
	(segment
		(start 37.465 -228.727)
		(end 37.49675 -228.75875)
		(width 0.1397)
		(layer "B.Cu")
		(net "LED_DR_LED3")
	)
	(segment
		(start 37.49675 -228.75875)
		(end 37.49675 -240.06175)
		(width 0.1397)
		(layer "B.Cu")
		(net "LED_DR_LED3")
	)
	(segment
		(start 35.6743 -371.4496)
		(end 35.6743 -370.4336)
		(width 0.381)
		(layer "F.Cu")
		(net "ADM1276_FLB")
	)
	(segment
		(start 34.1376 -369.3668)
		(end 34.1376 -369.3922)
		(width 0.381)
		(layer "F.Cu")
		(net "ADM1276_FLB")
	)
	(segment
		(start 34.1376 -369.4938)
		(end 34.1376 -369.3922)
		(width 0.381)
		(layer "F.Cu")
		(net "ADM1276_FLB")
	)
	(segment
		(start 33.5788 -368.808)
		(end 34.1376 -369.3668)
		(width 0.381)
		(layer "F.Cu")
		(net "ADM1276_FLB")
	)
	(segment
		(start 35.0774 -370.4336)
		(end 34.1376 -369.4938)
		(width 0.381)
		(layer "F.Cu")
		(net "ADM1276_FLB")
	)
	(segment
		(start 32.1564 -368.808)
		(end 33.5788 -368.808)
		(width 0.381)
		(layer "F.Cu")
		(net "ADM1276_FLB")
	)
	(segment
		(start 35.6743 -370.4336)
		(end 35.0774 -370.4336)
		(width 0.381)
		(layer "F.Cu")
		(net "ADM1276_FLB")
	)
	(via
		(at 34.1376 -369.3922)
		(size 0.7112)
		(drill 0.3556)
		(layers "F.Cu" "B.Cu")
		(net "ADM1276_FLB")
	)
	(segment
		(start 9.823958 -279.355042)
		(end 10.5283 -278.6507)
		(width 0.1397)
		(layer "F.Cu")
		(net "LED_DR_LED2")
	)
	(segment
		(start 38.31082 -241.66068)
		(end 38.862 -241.1095)
		(width 0.1397)
		(layer "F.Cu")
		(net "LED_DR_LED2")
	)
	(segment
		(start 32.3088 -257.8608)
		(end 29.7688 -257.8608)
		(width 0.1397)
		(layer "F.Cu")
		(net "LED_DR_LED2")
	)
	(segment
		(start 10.5283 -278.6507)
		(end 10.5283 -278.384)
		(width 0.1397)
		(layer "F.Cu")
		(net "LED_DR_LED2")
	)
	(segment
		(start 7.949946 -272.833846)
		(end 7.949946 -270.405098)
		(width 0.1397)
		(layer "F.Cu")
		(net "LED_DR_LED2")
	)
	(segment
		(start 38.13556 -242.526566)
		(end 38.042088 -242.433094)
		(width 0.1397)
		(layer "F.Cu")
		(net "LED_DR_LED2")
	)
	(segment
		(start 38.042088 -242.346734)
		(end 38.042088 -242.294918)
		(width 0.1397)
		(layer "F.Cu")
		(net "LED_DR_LED2")
	)
	(segment
		(start 38.042088 -242.294918)
		(end 38.31082 -242.026186)
		(width 0.1397)
		(layer "F.Cu")
		(net "LED_DR_LED2")
	)
	(segment
		(start 24.384 -252.476)
		(end 10.1854 -252.476)
		(width 0.1397)
		(layer "F.Cu")
		(net "LED_DR_LED2")
	)
	(segment
		(start 38.31082 -242.026186)
		(end 38.31082 -241.66068)
		(width 0.1397)
		(layer "F.Cu")
		(net "LED_DR_LED2")
	)
	(segment
		(start 29.7688 -257.8608)
		(end 24.384 -252.476)
		(width 0.1397)
		(layer "F.Cu")
		(net "LED_DR_LED2")
	)
	(segment
		(start 38.13556 -243.713)
		(end 38.13556 -242.526566)
		(width 0.1397)
		(layer "F.Cu")
		(net "LED_DR_LED2")
	)
	(segment
		(start 10.5283 -278.384)
		(end 10.5283 -275.4122)
		(width 0.1397)
		(layer "F.Cu")
		(net "LED_DR_LED2")
	)
	(segment
		(start 10.5283 -275.4122)
		(end 7.949946 -272.833846)
		(width 0.1397)
		(layer "F.Cu")
		(net "LED_DR_LED2")
	)
	(segment
		(start 9.525 -279.355042)
		(end 9.823958 -279.355042)
		(width 0.1397)
		(layer "F.Cu")
		(net "LED_DR_LED2")
	)
	(segment
		(start 10.1854 -252.476)
		(end 9.5758 -251.8664)
		(width 0.1397)
		(layer "F.Cu")
		(net "LED_DR_LED2")
	)
	(segment
		(start 38.042088 -242.433094)
		(end 38.042088 -242.346734)
		(width 0.1397)
		(layer "F.Cu")
		(net "LED_DR_LED2")
	)
	(via
		(at 9.5758 -251.8664)
		(size 0.7112)
		(drill 0.4064)
		(layers "F.Cu" "B.Cu")
		(net "LED_DR_LED2")
	)
	(via
		(at 32.3088 -257.8608)
		(size 0.5588)
		(drill 0.3048)
		(layers "F.Cu" "B.Cu")
		(net "LED_DR_LED2")
	)
	(via
		(at 9.525 -253.492)
		(size 0.7112)
		(drill 0.3556)
		(layers "F.Cu" "B.Cu")
		(net "LED_DR_LED2")
	)
	(via
		(at 9.525 -279.355042)
		(size 0.5588)
		(drill 0.3048)
		(layers "F.Cu" "B.Cu")
		(net "LED_DR_LED2")
	)
	(via
		(at 38.042088 -242.346734)
		(size 0.5588)
		(drill 0.3048)
		(layers "F.Cu" "B.Cu")
		(net "LED_DR_LED2")
	)
	(segment
		(start 32.385 -255.8288)
		(end 32.385 -257.7846)
		(width 0.1397)
		(layer "B.Cu")
		(net "LED_DR_LED2")
	)
	(segment
		(start 37.338 -243.116608)
		(end 37.338 -250.8758)
		(width 0.1397)
		(layer "B.Cu")
		(net "LED_DR_LED2")
	)
	(segment
		(start 37.338 -250.8758)
		(end 32.385 -255.8288)
		(width 0.1397)
		(layer "B.Cu")
		(net "LED_DR_LED2")
	)
	(segment
		(start 38.042088 -242.346734)
		(end 38.042088 -242.41252)
		(width 0.1397)
		(layer "B.Cu")
		(net "LED_DR_LED2")
	)
	(segment
		(start 32.385 -257.7846)
		(end 32.3088 -257.8608)
		(width 0.1397)
		(layer "B.Cu")
		(net "LED_DR_LED2")
	)
	(segment
		(start 9.5758 -251.8664)
		(end 9.525 -251.9172)
		(width 0.1397)
		(layer "B.Cu")
		(net "LED_DR_LED2")
	)
	(segment
		(start 9.525 -251.9172)
		(end 9.525 -253.492)
		(width 0.1397)
		(layer "B.Cu")
		(net "LED_DR_LED2")
	)
	(segment
		(start 9.525 -253.492)
		(end 9.525 -279.355042)
		(width 0.1397)
		(layer "B.Cu")
		(net "LED_DR_LED2")
	)
	(segment
		(start 38.042088 -242.41252)
		(end 37.338 -243.116608)
		(width 0.1397)
		(layer "B.Cu")
		(net "LED_DR_LED2")
	)
	(segment
		(start 30.367986 -366.3696)
		(end 30.367986 -363.869986)
		(width 0.1397)
		(layer "F.Cu")
		(net "ADM1276_GPIO2")
	)
	(segment
		(start 30.367986 -363.869986)
		(end 29.7434 -363.2454)
		(width 0.1397)
		(layer "F.Cu")
		(net "ADM1276_GPIO2")
	)
	(segment
		(start 29.7434 -363.2454)
		(end 29.972 -363.0168)
		(width 0.1397)
		(layer "F.Cu")
		(net "ADM1276_GPIO2")
	)
	(segment
		(start 29.972 -363.0168)
		(end 29.972 -361.7595)
		(width 0.1397)
		(layer "F.Cu")
		(net "ADM1276_GPIO2")
	)
	(segment
		(start 7.949946 -414.984946)
		(end 9.652 -416.687)
		(width 0.1397)
		(layer "F.Cu")
		(net "LED_DR_LED1")
	)
	(segment
		(start 37.211 -242.06962)
		(end 37.211 -241.7445)
		(width 0.1397)
		(layer "F.Cu")
		(net "LED_DR_LED1")
	)
	(segment
		(start 8.3566 -422.7195)
		(end 5.1816 -422.7195)
		(width 0.1397)
		(layer "F.Cu")
		(net "LED_DR_LED1")
	)
	(segment
		(start 37.211 -241.7445)
		(end 37.846 -241.1095)
		(width 0.1397)
		(layer "F.Cu")
		(net "LED_DR_LED1")
	)
	(segment
		(start 5.1816 -422.7195)
		(end 4.8895 -422.4274)
		(width 0.1397)
		(layer "F.Cu")
		(net "LED_DR_LED1")
	)
	(segment
		(start 9.652 -421.4241)
		(end 8.3566 -422.7195)
		(width 0.1397)
		(layer "F.Cu")
		(net "LED_DR_LED1")
	)
	(segment
		(start 37.48532 -242.34394)
		(end 37.211 -242.06962)
		(width 0.1397)
		(layer "F.Cu")
		(net "LED_DR_LED1")
	)
	(segment
		(start 37.48532 -243.713)
		(end 37.48532 -242.34394)
		(width 0.1397)
		(layer "F.Cu")
		(net "LED_DR_LED1")
	)
	(segment
		(start 9.652 -416.687)
		(end 9.652 -421.4241)
		(width 0.1397)
		(layer "F.Cu")
		(net "LED_DR_LED1")
	)
	(segment
		(start 7.949946 -414.005014)
		(end 7.949946 -414.984946)
		(width 0.1397)
		(layer "F.Cu")
		(net "LED_DR_LED1")
	)
	(via
		(at 37.211 -242.06962)
		(size 0.5588)
		(drill 0.3048)
		(layers "F.Cu" "B.Cu")
		(net "LED_DR_LED1")
	)
	(via
		(at 31.2166 -255.8796)
		(size 0.7112)
		(drill 0.3556)
		(layers "F.Cu" "B.Cu")
		(net "LED_DR_LED1")
	)
	(via
		(at 4.8895 -422.4274)
		(size 0.7112)
		(drill 0.4064)
		(layers "F.Cu" "B.Cu")
		(net "LED_DR_LED1")
	)
	(segment
		(start 35.84575 -241.87277)
		(end 35.84575 -250.78309)
		(width 0.1397)
		(layer "B.Cu")
		(net "LED_DR_LED1")
	)
	(segment
		(start 4.977384 -352.654616)
		(end 19.618452 -338.013548)
		(width 0.1397)
		(layer "B.Cu")
		(net "LED_DR_LED1")
	)
	(segment
		(start 4.088384 -416.120834)
		(end 4.088384 -379.766576)
		(width 0.1397)
		(layer "B.Cu")
		(net "LED_DR_LED1")
	)
	(segment
		(start 37.211 -242.06962)
		(end 36.735258 -241.593878)
		(width 0.1397)
		(layer "B.Cu")
		(net "LED_DR_LED1")
	)
	(segment
		(start 36.735258 -241.593878)
		(end 36.124642 -241.593878)
		(width 0.1397)
		(layer "B.Cu")
		(net "LED_DR_LED1")
	)
	(segment
		(start 4.8895 -422.4274)
		(end 4.8895 -416.92195)
		(width 0.1397)
		(layer "B.Cu")
		(net "LED_DR_LED1")
	)
	(segment
		(start 36.124642 -241.593878)
		(end 35.84575 -241.87277)
		(width 0.1397)
		(layer "B.Cu")
		(net "LED_DR_LED1")
	)
	(segment
		(start 31.2166 -274.9804)
		(end 31.2166 -255.8796)
		(width 0.1397)
		(layer "B.Cu")
		(net "LED_DR_LED1")
	)
	(segment
		(start 20.447 -288.671)
		(end 20.447 -285.75)
		(width 0.1397)
		(layer "B.Cu")
		(net "LED_DR_LED1")
	)
	(segment
		(start 4.8895 -416.92195)
		(end 4.088384 -416.120834)
		(width 0.1397)
		(layer "B.Cu")
		(net "LED_DR_LED1")
	)
	(segment
		(start 19.618452 -338.013548)
		(end 19.618452 -293.887652)
		(width 0.1397)
		(layer "B.Cu")
		(net "LED_DR_LED1")
	)
	(segment
		(start 18.889218 -293.158418)
		(end 18.889218 -290.228782)
		(width 0.1397)
		(layer "B.Cu")
		(net "LED_DR_LED1")
	)
	(segment
		(start 18.889218 -290.228782)
		(end 20.447 -288.671)
		(width 0.1397)
		(layer "B.Cu")
		(net "LED_DR_LED1")
	)
	(segment
		(start 19.618452 -293.887652)
		(end 18.889218 -293.158418)
		(width 0.1397)
		(layer "B.Cu")
		(net "LED_DR_LED1")
	)
	(segment
		(start 5.951474 -364.524798)
		(end 4.977384 -363.550708)
		(width 0.1397)
		(layer "B.Cu")
		(net "LED_DR_LED1")
	)
	(segment
		(start 5.951474 -377.903486)
		(end 5.951474 -364.524798)
		(width 0.1397)
		(layer "B.Cu")
		(net "LED_DR_LED1")
	)
	(segment
		(start 31.2166 -255.41224)
		(end 31.2166 -255.8796)
		(width 0.1397)
		(layer "B.Cu")
		(net "LED_DR_LED1")
	)
	(segment
		(start 35.84575 -250.78309)
		(end 31.2166 -255.41224)
		(width 0.1397)
		(layer "B.Cu")
		(net "LED_DR_LED1")
	)
	(segment
		(start 4.088384 -379.766576)
		(end 5.951474 -377.903486)
		(width 0.1397)
		(layer "B.Cu")
		(net "LED_DR_LED1")
	)
	(segment
		(start 4.977384 -363.550708)
		(end 4.977384 -352.654616)
		(width 0.1397)
		(layer "B.Cu")
		(net "LED_DR_LED1")
	)
	(segment
		(start 20.447 -285.75)
		(end 31.2166 -274.9804)
		(width 0.1397)
		(layer "B.Cu")
		(net "LED_DR_LED1")
	)
	(segment
		(start 36.322 -241.6175)
		(end 36.83 -241.1095)
		(width 0.1397)
		(layer "F.Cu")
		(net "LED_DR_LED0")
	)
	(segment
		(start 4.6609 -443.151006)
		(end 7.949946 -446.440052)
		(width 0.1397)
		(layer "F.Cu")
		(net "LED_DR_LED0")
	)
	(segment
		(start 36.322 -242.070128)
		(end 36.322 -242.19535)
		(width 0.1397)
		(layer "F.Cu")
		(net "LED_DR_LED0")
	)
	(segment
		(start 36.322 -242.19535)
		(end 36.83508 -242.70843)
		(width 0.1397)
		(layer "F.Cu")
		(net "LED_DR_LED0")
	)
	(segment
		(start 4.6609 -436.504842)
		(end 4.2418 -436.085742)
		(width 0.1397)
		(layer "F.Cu")
		(net "LED_DR_LED0")
	)
	(segment
		(start 4.6609 -437.0578)
		(end 4.6609 -436.504842)
		(width 0.1397)
		(layer "F.Cu")
		(net "LED_DR_LED0")
	)
	(segment
		(start 36.322 -242.070128)
		(end 36.322 -241.6175)
		(width 0.1397)
		(layer "F.Cu")
		(net "LED_DR_LED0")
	)
	(segment
		(start 36.83508 -242.70843)
		(end 36.83508 -243.713)
		(width 0.1397)
		(layer "F.Cu")
		(net "LED_DR_LED0")
	)
	(segment
		(start 4.2418 -434.213)
		(end 4.8768 -433.578)
		(width 0.1397)
		(layer "F.Cu")
		(net "LED_DR_LED0")
	)
	(segment
		(start 4.2418 -436.085742)
		(end 4.2418 -434.213)
		(width 0.1397)
		(layer "F.Cu")
		(net "LED_DR_LED0")
	)
	(segment
		(start 4.6609 -437.0578)
		(end 4.6609 -443.151006)
		(width 0.1397)
		(layer "F.Cu")
		(net "LED_DR_LED0")
	)
	(via
		(at 36.322 -242.070128)
		(size 0.5588)
		(drill 0.3048)
		(layers "F.Cu" "B.Cu")
		(net "LED_DR_LED0")
	)
	(via
		(at 4.8768 -433.578)
		(size 0.5588)
		(drill 0.3048)
		(layers "F.Cu" "B.Cu")
		(net "LED_DR_LED0")
	)
	(segment
		(start 5.421884 -352.845116)
		(end 20.062952 -338.204048)
		(width 0.1397)
		(layer "B.Cu")
		(net "LED_DR_LED0")
	)
	(segment
		(start 19.333718 -292.967918)
		(end 19.333718 -290.566602)
		(width 0.1397)
		(layer "B.Cu")
		(net "LED_DR_LED0")
	)
	(segment
		(start 20.062952 -338.204048)
		(end 20.062952 -293.697152)
		(width 0.1397)
		(layer "B.Cu")
		(net "LED_DR_LED0")
	)
	(segment
		(start 19.333718 -290.566602)
		(end 20.955 -288.94532)
		(width 0.1397)
		(layer "B.Cu")
		(net "LED_DR_LED0")
	)
	(segment
		(start 4.532884 -379.950726)
		(end 6.395974 -378.087636)
		(width 0.1397)
		(layer "B.Cu")
		(net "LED_DR_LED0")
	)
	(segment
		(start 5.44195 -416.84575)
		(end 4.532884 -415.936684)
		(width 0.1397)
		(layer "B.Cu")
		(net "LED_DR_LED0")
	)
	(segment
		(start 5.44195 -433.01285)
		(end 5.44195 -416.84575)
		(width 0.1397)
		(layer "B.Cu")
		(net "LED_DR_LED0")
	)
	(segment
		(start 31.8262 -255.7018)
		(end 36.322 -251.206)
		(width 0.1397)
		(layer "B.Cu")
		(net "LED_DR_LED0")
	)
	(segment
		(start 5.421884 -363.333284)
		(end 5.421884 -352.845116)
		(width 0.1397)
		(layer "B.Cu")
		(net "LED_DR_LED0")
	)
	(segment
		(start 31.8262 -275.0058)
		(end 31.8262 -255.7018)
		(width 0.1397)
		(layer "B.Cu")
		(net "LED_DR_LED0")
	)
	(segment
		(start 20.955 -285.877)
		(end 31.8262 -275.0058)
		(width 0.1397)
		(layer "B.Cu")
		(net "LED_DR_LED0")
	)
	(segment
		(start 20.062952 -293.697152)
		(end 19.333718 -292.967918)
		(width 0.1397)
		(layer "B.Cu")
		(net "LED_DR_LED0")
	)
	(segment
		(start 36.322 -251.206)
		(end 36.322 -242.070128)
		(width 0.1397)
		(layer "B.Cu")
		(net "LED_DR_LED0")
	)
	(segment
		(start 6.395974 -364.307374)
		(end 5.421884 -363.333284)
		(width 0.1397)
		(layer "B.Cu")
		(net "LED_DR_LED0")
	)
	(segment
		(start 20.955 -288.94532)
		(end 20.955 -285.877)
		(width 0.1397)
		(layer "B.Cu")
		(net "LED_DR_LED0")
	)
	(segment
		(start 4.532884 -415.936684)
		(end 4.532884 -379.950726)
		(width 0.1397)
		(layer "B.Cu")
		(net "LED_DR_LED0")
	)
	(segment
		(start 6.395974 -378.087636)
		(end 6.395974 -364.307374)
		(width 0.1397)
		(layer "B.Cu")
		(net "LED_DR_LED0")
	)
	(segment
		(start 4.8768 -433.578)
		(end 5.44195 -433.01285)
		(width 0.1397)
		(layer "B.Cu")
		(net "LED_DR_LED0")
	)
	(segment
		(start 39.43604 -249.3518)
		(end 39.43604 -247.58904)
		(width 0.1397)
		(layer "F.Cu")
		(net "LED_DR_LED4")
	)
	(segment
		(start 8.359902 -91.075002)
		(end 11.049 -88.385904)
		(width 0.1397)
		(layer "F.Cu")
		(net "LED_DR_LED4")
	)
	(segment
		(start 11.049 -88.385904)
		(end 11.049 -81.966562)
		(width 0.1397)
		(layer "F.Cu")
		(net "LED_DR_LED4")
	)
	(segment
		(start 5.21081 -78.613)
		(end 4.897882 -78.925928)
		(width 0.1397)
		(layer "F.Cu")
		(net "LED_DR_LED4")
	)
	(segment
		(start 39.43604 -247.58904)
		(end 39.37 -247.523)
		(width 0.1397)
		(layer "F.Cu")
		(net "LED_DR_LED4")
	)
	(segment
		(start 7.949946 -91.075002)
		(end 8.359902 -91.075002)
		(width 0.1397)
		(layer "F.Cu")
		(net "LED_DR_LED4")
	)
	(segment
		(start 41.4655 -252.5395)
		(end 41.529 -252.5395)
		(width 0.1397)
		(layer "F.Cu")
		(net "LED_DR_LED4")
	)
	(segment
		(start 14.6812 -225.3742)
		(end 14.224 -224.917)
		(width 0.1397)
		(layer "F.Cu")
		(net "LED_DR_LED4")
	)
	(segment
		(start 39.9542 -227.965)
		(end 18.415 -227.965)
		(width 0.1397)
		(layer "F.Cu")
		(net "LED_DR_LED4")
	)
	(segment
		(start 39.43604 -250.51004)
		(end 41.4655 -252.5395)
		(width 0.1397)
		(layer "F.Cu")
		(net "LED_DR_LED4")
	)
	(segment
		(start 11.049 -81.966562)
		(end 7.695438 -78.613)
		(width 0.1397)
		(layer "F.Cu")
		(net "LED_DR_LED4")
	)
	(segment
		(start 18.415 -227.965)
		(end 15.8242 -225.3742)
		(width 0.1397)
		(layer "F.Cu")
		(net "LED_DR_LED4")
	)
	(segment
		(start 15.8242 -225.3742)
		(end 14.6812 -225.3742)
		(width 0.1397)
		(layer "F.Cu")
		(net "LED_DR_LED4")
	)
	(segment
		(start 40.0812 -228.092)
		(end 39.9542 -227.965)
		(width 0.1397)
		(layer "F.Cu")
		(net "LED_DR_LED4")
	)
	(segment
		(start 39.43604 -249.3518)
		(end 39.43604 -250.51004)
		(width 0.1397)
		(layer "F.Cu")
		(net "LED_DR_LED4")
	)
	(segment
		(start 7.695438 -78.613)
		(end 5.21081 -78.613)
		(width 0.1397)
		(layer "F.Cu")
		(net "LED_DR_LED4")
	)
	(via
		(at 39.37 -247.523)
		(size 0.5588)
		(drill 0.3048)
		(layers "F.Cu" "B.Cu")
		(net "LED_DR_LED4")
	)
	(via
		(at 40.0812 -228.092)
		(size 0.5588)
		(drill 0.3048)
		(layers "F.Cu" "B.Cu")
		(net "LED_DR_LED4")
	)
	(via
		(at 14.224 -224.917)
		(size 0.5588)
		(drill 0.3048)
		(layers "F.Cu" "B.Cu")
		(net "LED_DR_LED4")
	)
	(via
		(at 14.683486 -216.535)
		(size 0.7112)
		(drill 0.3556)
		(layers "F.Cu" "B.Cu")
		(net "LED_DR_LED4")
	)
	(segment
		(start 8.3312 -133.6294)
		(end 11.43 -136.7282)
		(width 0.1397)
		(layer "B.Cu")
		(net "LED_DR_LED4")
	)
	(segment
		(start 39.37 -247.523)
		(end 39.37 -245.5926)
		(width 0.1397)
		(layer "B.Cu")
		(net "LED_DR_LED4")
	)
	(segment
		(start 14.224 -224.917)
		(end 14.224 -224.141792)
		(width 0.1397)
		(layer "B.Cu")
		(net "LED_DR_LED4")
	)
	(segment
		(start 40.259 -228.2698)
		(end 40.0812 -228.092)
		(width 0.1397)
		(layer "B.Cu")
		(net "LED_DR_LED4")
	)
	(segment
		(start 16.44015 -214.19185)
		(end 14.683486 -215.948514)
		(width 0.1397)
		(layer "B.Cu")
		(net "LED_DR_LED4")
	)
	(segment
		(start 11.43 -146.431)
		(end 16.891 -151.892)
		(width 0.1397)
		(layer "B.Cu")
		(net "LED_DR_LED4")
	)
	(segment
		(start 17.653 -172.224446)
		(end 16.44015 -173.437296)
		(width 0.1397)
		(layer "B.Cu")
		(net "LED_DR_LED4")
	)
	(segment
		(start 14.224 -224.141792)
		(end 14.683486 -223.682306)
		(width 0.1397)
		(layer "B.Cu")
		(net "LED_DR_LED4")
	)
	(segment
		(start 11.43 -136.7282)
		(end 11.43 -146.431)
		(width 0.1397)
		(layer "B.Cu")
		(net "LED_DR_LED4")
	)
	(segment
		(start 14.683486 -223.682306)
		(end 14.683486 -216.535)
		(width 0.1397)
		(layer "B.Cu")
		(net "LED_DR_LED4")
	)
	(segment
		(start 17.653 -169.213276)
		(end 17.653 -172.224446)
		(width 0.1397)
		(layer "B.Cu")
		(net "LED_DR_LED4")
	)
	(segment
		(start 40.259 -244.7036)
		(end 40.259 -228.2698)
		(width 0.1397)
		(layer "B.Cu")
		(net "LED_DR_LED4")
	)
	(segment
		(start 18.23085 -156.91485)
		(end 18.23085 -168.635426)
		(width 0.1397)
		(layer "B.Cu")
		(net "LED_DR_LED4")
	)
	(segment
		(start 16.891 -155.575)
		(end 18.23085 -156.91485)
		(width 0.1397)
		(layer "B.Cu")
		(net "LED_DR_LED4")
	)
	(segment
		(start 8.24865 -91.373706)
		(end 8.24865 -112.40135)
		(width 0.1397)
		(layer "B.Cu")
		(net "LED_DR_LED4")
	)
	(segment
		(start 8.24865 -112.40135)
		(end 5.392166 -115.257834)
		(width 0.1397)
		(layer "B.Cu")
		(net "LED_DR_LED4")
	)
	(segment
		(start 16.891 -151.892)
		(end 16.891 -155.575)
		(width 0.1397)
		(layer "B.Cu")
		(net "LED_DR_LED4")
	)
	(segment
		(start 14.683486 -215.948514)
		(end 14.683486 -216.535)
		(width 0.1397)
		(layer "B.Cu")
		(net "LED_DR_LED4")
	)
	(segment
		(start 5.392166 -117.685566)
		(end 8.3312 -120.6246)
		(width 0.1397)
		(layer "B.Cu")
		(net "LED_DR_LED4")
	)
	(segment
		(start 16.44015 -173.437296)
		(end 16.44015 -214.19185)
		(width 0.1397)
		(layer "B.Cu")
		(net "LED_DR_LED4")
	)
	(segment
		(start 39.37 -245.5926)
		(end 40.259 -244.7036)
		(width 0.1397)
		(layer "B.Cu")
		(net "LED_DR_LED4")
	)
	(segment
		(start 7.949946 -91.075002)
		(end 8.24865 -91.373706)
		(width 0.1397)
		(layer "B.Cu")
		(net "LED_DR_LED4")
	)
	(segment
		(start 5.392166 -115.257834)
		(end 5.392166 -117.685566)
		(width 0.1397)
		(layer "B.Cu")
		(net "LED_DR_LED4")
	)
	(segment
		(start 18.23085 -168.635426)
		(end 17.653 -169.213276)
		(width 0.1397)
		(layer "B.Cu")
		(net "LED_DR_LED4")
	)
	(segment
		(start 8.3312 -120.6246)
		(end 8.3312 -133.6294)
		(width 0.1397)
		(layer "B.Cu")
		(net "LED_DR_LED4")
	)
	(segment
		(start 10.31621 -68.2498)
		(end 9.177528 -67.111118)
		(width 0.1397)
		(layer "F.Cu")
		(net "LED_DR_LED5")
	)
	(segment
		(start 38.7858 -249.3518)
		(end 38.7858 -248.5898)
		(width 0.1397)
		(layer "F.Cu")
		(net "LED_DR_LED5")
	)
	(segment
		(start 38.7858 -248.5898)
		(end 38.227 -248.031)
		(width 0.1397)
		(layer "F.Cu")
		(net "LED_DR_LED5")
	)
	(segment
		(start 13.716 -70.0024)
		(end 13.716 -69.7738)
		(width 0.1397)
		(layer "F.Cu")
		(net "LED_DR_LED5")
	)
	(segment
		(start 38.7858 -250.8123)
		(end 40.513 -252.5395)
		(width 0.1397)
		(layer "F.Cu")
		(net "LED_DR_LED5")
	)
	(segment
		(start 13.716 -69.7738)
		(end 12.192 -68.2498)
		(width 0.1397)
		(layer "F.Cu")
		(net "LED_DR_LED5")
	)
	(segment
		(start 38.7858 -249.3518)
		(end 38.7858 -250.8123)
		(width 0.1397)
		(layer "F.Cu")
		(net "LED_DR_LED5")
	)
	(segment
		(start 11.3538 -62.043818)
		(end 7.949946 -58.639964)
		(width 0.1397)
		(layer "F.Cu")
		(net "LED_DR_LED5")
	)
	(segment
		(start 9.226296 -67.06235)
		(end 10.521696 -67.06235)
		(width 0.1397)
		(layer "F.Cu")
		(net "LED_DR_LED5")
	)
	(segment
		(start 11.3538 -66.230246)
		(end 11.3538 -62.043818)
		(width 0.1397)
		(layer "F.Cu")
		(net "LED_DR_LED5")
	)
	(segment
		(start 10.521696 -67.06235)
		(end 11.3538 -66.230246)
		(width 0.1397)
		(layer "F.Cu")
		(net "LED_DR_LED5")
	)
	(segment
		(start 9.177528 -67.111118)
		(end 9.226296 -67.06235)
		(width 0.1397)
		(layer "F.Cu")
		(net "LED_DR_LED5")
	)
	(segment
		(start 12.192 -68.2498)
		(end 10.31621 -68.2498)
		(width 0.1397)
		(layer "F.Cu")
		(net "LED_DR_LED5")
	)
	(via
		(at 13.716 -70.0024)
		(size 0.5588)
		(drill 0.3048)
		(layers "F.Cu" "B.Cu")
		(net "LED_DR_LED5")
	)
	(via
		(at 38.227 -248.031)
		(size 0.5588)
		(drill 0.3048)
		(layers "F.Cu" "B.Cu")
		(net "LED_DR_LED5")
	)
	(via
		(at 32.6644 -170.053)
		(size 0.7112)
		(drill 0.3556)
		(layers "F.Cu" "B.Cu")
		(net "LED_DR_LED5")
	)
	(segment
		(start 38.227 -244.01145)
		(end 38.227 -248.031)
		(width 0.1397)
		(layer "B.Cu")
		(net "LED_DR_LED5")
	)
	(segment
		(start 12.8143 -73.7235)
		(end 13.9192 -72.6186)
		(width 0.1397)
		(layer "B.Cu")
		(net "LED_DR_LED5")
	)
	(segment
		(start 22.098 -146.6088)
		(end 22.098 -143.9672)
		(width 0.1397)
		(layer "B.Cu")
		(net "LED_DR_LED5")
	)
	(segment
		(start 15.9004 -137.7696)
		(end 15.9004 -124.333)
		(width 0.1397)
		(layer "B.Cu")
		(net "LED_DR_LED5")
	)
	(segment
		(start 32.6644 -170.053)
		(end 32.6644 -172.19168)
		(width 0.1397)
		(layer "B.Cu")
		(net "LED_DR_LED5")
	)
	(segment
		(start 13.9192 -72.6186)
		(end 13.9192 -70.2056)
		(width 0.1397)
		(layer "B.Cu")
		(net "LED_DR_LED5")
	)
	(segment
		(start 23.08225 -147.59305)
		(end 22.098 -146.6088)
		(width 0.1397)
		(layer "B.Cu")
		(net "LED_DR_LED5")
	)
	(segment
		(start 32.6644 -170.053)
		(end 32.6644 -168.5036)
		(width 0.1397)
		(layer "B.Cu")
		(net "LED_DR_LED5")
	)
	(segment
		(start 23.08225 -151.327358)
		(end 23.08225 -147.59305)
		(width 0.1397)
		(layer "B.Cu")
		(net "LED_DR_LED5")
	)
	(segment
		(start 13.6398 -111.8362)
		(end 12.3571 -110.5535)
		(width 0.1397)
		(layer "B.Cu")
		(net "LED_DR_LED5")
	)
	(segment
		(start 22.46757 -151.942038)
		(end 23.08225 -151.327358)
		(width 0.1397)
		(layer "B.Cu")
		(net "LED_DR_LED5")
	)
	(segment
		(start 15.9004 -124.333)
		(end 13.6398 -122.0724)
		(width 0.1397)
		(layer "B.Cu")
		(net "LED_DR_LED5")
	)
	(segment
		(start 13.6398 -122.0724)
		(end 13.6398 -111.8362)
		(width 0.1397)
		(layer "B.Cu")
		(net "LED_DR_LED5")
	)
	(segment
		(start 33.92805 -173.45533)
		(end 33.92805 -211.09305)
		(width 0.1397)
		(layer "B.Cu")
		(net "LED_DR_LED5")
	)
	(segment
		(start 33.81375 -167.35425)
		(end 33.81375 -164.908992)
		(width 0.1397)
		(layer "B.Cu")
		(net "LED_DR_LED5")
	)
	(segment
		(start 32.6644 -172.19168)
		(end 33.92805 -173.45533)
		(width 0.1397)
		(layer "B.Cu")
		(net "LED_DR_LED5")
	)
	(segment
		(start 39.3065 -240.741708)
		(end 39.3065 -242.93195)
		(width 0.1397)
		(layer "B.Cu")
		(net "LED_DR_LED5")
	)
	(segment
		(start 12.3571 -110.5535)
		(end 12.3571 -93.44025)
		(width 0.1397)
		(layer "B.Cu")
		(net "LED_DR_LED5")
	)
	(segment
		(start 12.3571 -93.44025)
		(end 12.8143 -92.98305)
		(width 0.1397)
		(layer "B.Cu")
		(net "LED_DR_LED5")
	)
	(segment
		(start 33.92805 -211.09305)
		(end 37.94125 -215.10625)
		(width 0.1397)
		(layer "B.Cu")
		(net "LED_DR_LED5")
	)
	(segment
		(start 37.94125 -215.10625)
		(end 37.94125 -239.376458)
		(width 0.1397)
		(layer "B.Cu")
		(net "LED_DR_LED5")
	)
	(segment
		(start 13.9192 -70.2056)
		(end 13.716 -70.0024)
		(width 0.1397)
		(layer "B.Cu")
		(net "LED_DR_LED5")
	)
	(segment
		(start 32.6644 -168.5036)
		(end 33.81375 -167.35425)
		(width 0.1397)
		(layer "B.Cu")
		(net "LED_DR_LED5")
	)
	(segment
		(start 12.8143 -92.98305)
		(end 12.8143 -73.7235)
		(width 0.1397)
		(layer "B.Cu")
		(net "LED_DR_LED5")
	)
	(segment
		(start 37.94125 -239.376458)
		(end 39.3065 -240.741708)
		(width 0.1397)
		(layer "B.Cu")
		(net "LED_DR_LED5")
	)
	(segment
		(start 22.46757 -153.562812)
		(end 22.46757 -151.942038)
		(width 0.1397)
		(layer "B.Cu")
		(net "LED_DR_LED5")
	)
	(segment
		(start 22.098 -143.9672)
		(end 15.9004 -137.7696)
		(width 0.1397)
		(layer "B.Cu")
		(net "LED_DR_LED5")
	)
	(segment
		(start 33.81375 -164.908992)
		(end 22.46757 -153.562812)
		(width 0.1397)
		(layer "B.Cu")
		(net "LED_DR_LED5")
	)
	(segment
		(start 39.3065 -242.93195)
		(end 38.227 -244.01145)
		(width 0.1397)
		(layer "B.Cu")
		(net "LED_DR_LED5")
	)
	(segment
		(start 24.0665 -368.554)
		(end 24.13 -368.6175)
		(width 0.508)
		(layer "F.Cu")
		(net "ADM1276_VCAP")
	)
	(segment
		(start 24.13 -369.697)
		(end 24.7396 -369.697)
		(width 0.508)
		(layer "F.Cu")
		(net "ADM1276_VCAP")
	)
	(segment
		(start 24.7396 -369.697)
		(end 24.765 -369.7224)
		(width 0.508)
		(layer "F.Cu")
		(net "ADM1276_VCAP")
	)
	(segment
		(start 24.13 -368.6175)
		(end 24.13 -369.697)
		(width 0.508)
		(layer "F.Cu")
		(net "ADM1276_VCAP")
	)
	(segment
		(start 22.606 -362.2675)
		(end 23.241 -361.6325)
		(width 0.508)
		(layer "F.Cu")
		(net "ADM1276_VCAP")
	)
	(segment
		(start 25.3492 -369.7224)
		(end 25.613614 -369.457986)
		(width 0.381)
		(layer "F.Cu")
		(net "ADM1276_VCAP")
	)
	(segment
		(start 22.606 -362.755434)
		(end 22.606 -362.2675)
		(width 0.508)
		(layer "F.Cu")
		(net "ADM1276_VCAP")
	)
	(segment
		(start 25.613614 -369.457986)
		(end 27.2796 -369.457986)
		(width 0.381)
		(layer "F.Cu")
		(net "ADM1276_VCAP")
	)
	(segment
		(start 22.4028 -365.506)
		(end 22.1488 -365.76)
		(width 0.508)
		(layer "F.Cu")
		(net "ADM1276_VCAP")
	)
	(segment
		(start 24.765 -369.7224)
		(end 25.3492 -369.7224)
		(width 0.508)
		(layer "F.Cu")
		(net "ADM1276_VCAP")
	)
	(segment
		(start 23.1775 -365.506)
		(end 22.4028 -365.506)
		(width 0.508)
		(layer "F.Cu")
		(net "ADM1276_VCAP")
	)
	(via
		(at 22.606 -362.755434)
		(size 0.5588)
		(drill 0.3048)
		(layers "F.Cu" "B.Cu")
		(net "ADM1276_VCAP")
	)
	(via
		(at 22.1488 -365.76)
		(size 0.7112)
		(drill 0.4064)
		(layers "F.Cu" "B.Cu")
		(net "ADM1276_VCAP")
	)
	(via
		(at 24.348186 -367.883186)
		(size 0.7112)
		(drill 0.3556)
		(layers "F.Cu" "B.Cu")
		(net "ADM1276_VCAP")
	)
	(via
		(at 25.3492 -369.7224)
		(size 0.7112)
		(drill 0.4064)
		(layers "F.Cu" "B.Cu")
		(net "ADM1276_VCAP")
	)
	(segment
		(start 22.3266 -365.76)
		(end 23.1902 -364.8964)
		(width 0.508)
		(layer "B.Cu")
		(net "ADM1276_VCAP")
	)
	(segment
		(start 22.748494 -362.86948)
		(end 22.634448 -362.755434)
		(width 0.508)
		(layer "B.Cu")
		(net "ADM1276_VCAP")
	)
	(segment
		(start 22.76348 -362.86948)
		(end 22.748494 -362.86948)
		(width 0.508)
		(layer "B.Cu")
		(net "ADM1276_VCAP")
	)
	(segment
		(start 25.3492 -368.8842)
		(end 24.348186 -367.883186)
		(width 0.508)
		(layer "B.Cu")
		(net "ADM1276_VCAP")
	)
	(segment
		(start 25.3492 -369.7224)
		(end 25.3492 -368.8842)
		(width 0.508)
		(layer "B.Cu")
		(net "ADM1276_VCAP")
	)
	(segment
		(start 22.1488 -365.76)
		(end 22.3266 -365.76)
		(width 0.508)
		(layer "B.Cu")
		(net "ADM1276_VCAP")
	)
	(segment
		(start 22.1488 -365.76)
		(end 23.2156 -366.8268)
		(width 0.508)
		(layer "B.Cu")
		(net "ADM1276_VCAP")
	)
	(segment
		(start 23.2156 -366.8268)
		(end 23.2918 -366.8268)
		(width 0.508)
		(layer "B.Cu")
		(net "ADM1276_VCAP")
	)
	(segment
		(start 23.2918 -366.8268)
		(end 24.348186 -367.883186)
		(width 0.508)
		(layer "B.Cu")
		(net "ADM1276_VCAP")
	)
	(segment
		(start 23.1902 -363.2962)
		(end 22.76348 -362.86948)
		(width 0.508)
		(layer "B.Cu")
		(net "ADM1276_VCAP")
	)
	(segment
		(start 23.1902 -364.8964)
		(end 23.1902 -363.2962)
		(width 0.508)
		(layer "B.Cu")
		(net "ADM1276_VCAP")
	)
	(segment
		(start 22.634448 -362.755434)
		(end 22.606 -362.755434)
		(width 0.508)
		(layer "B.Cu")
		(net "ADM1276_VCAP")
	)
	(segment
		(start 24.500078 -438.831482)
		(end 24.500078 -443.95009)
		(width 0.635)
		(layer "F.Cu")
		(net "P12V_AUX")
	)
	(segment
		(start 19.38147 -463.049874)
		(end 24.500078 -463.049874)
		(width 0.635)
		(layer "F.Cu")
		(net "P12V_AUX")
	)
	(segment
		(start 38.391084 -359.1814)
		(end 38.619684 -359.41)
		(width 0.508)
		(layer "F.Cu")
		(net "P12V_AUX")
	)
	(segment
		(start 38.354 -369.443)
		(end 37.592 -369.443)
		(width 0.508)
		(layer "F.Cu")
		(net "P12V_AUX")
	)
	(segment
		(start 33.9725 -185.0136)
		(end 34.3916 -185.4327)
		(width 0.508)
		(layer "F.Cu")
		(net "P12V_AUX")
	)
	(segment
		(start 38.6207 -361.5436)
		(end 38.6207 -362.5469)
		(width 0.508)
		(layer "F.Cu")
		(net "P12V_AUX")
	)
	(segment
		(start 21.209 -372.1735)
		(end 21.209 -373.253)
		(width 0.508)
		(layer "F.Cu")
		(net "P12V_AUX")
	)
	(segment
		(start 38.619684 -361.542584)
		(end 38.6207 -361.5436)
		(width 0.508)
		(layer "F.Cu")
		(net "P12V_AUX")
	)
	(segment
		(start 38.735 -369.824)
		(end 38.354 -369.443)
		(width 0.508)
		(layer "F.Cu")
		(net "P12V_AUX")
	)
	(segment
		(start 38.619684 -360.4768)
		(end 38.619684 -359.41)
		(width 0.508)
		(layer "F.Cu")
		(net "P12V_AUX")
	)
	(segment
		(start 24.500078 -457.931266)
		(end 24.500078 -463.049874)
		(width 0.635)
		(layer "F.Cu")
		(net "P12V_AUX")
	)
	(segment
		(start 24.500078 -443.95009)
		(end 24.500078 -449.068698)
		(width 0.635)
		(layer "F.Cu")
		(net "P12V_AUX")
	)
	(segment
		(start 37.2872 -369.1382)
		(end 36.4871 -369.1382)
		(width 0.508)
		(layer "F.Cu")
		(net "P12V_AUX")
	)
	(segment
		(start 31.7246 -185.0136)
		(end 33.9725 -185.0136)
		(width 0.508)
		(layer "F.Cu")
		(net "P12V_AUX")
	)
	(segment
		(start 27.559 -378.7775)
		(end 27.305 -378.5235)
		(width 0.508)
		(layer "F.Cu")
		(net "P12V_AUX")
	)
	(segment
		(start 28.6385 -378.7775)
		(end 27.559 -378.7775)
		(width 0.508)
		(layer "F.Cu")
		(net "P12V_AUX")
	)
	(segment
		(start 44.397168 -159.561784)
		(end 44.245784 -159.561784)
		(width 0.508)
		(layer "F.Cu")
		(net "P12V_AUX")
	)
	(segment
		(start 19.38147 -443.95009)
		(end 24.500078 -443.95009)
		(width 0.635)
		(layer "F.Cu")
		(net "P12V_AUX")
	)
	(segment
		(start 40.2844 -191.1604)
		(end 38.562788 -191.1604)
		(width 0.508)
		(layer "F.Cu")
		(net "P12V_AUX")
	)
	(segment
		(start 45.1485 -158.810452)
		(end 44.397168 -159.561784)
		(width 0.508)
		(layer "F.Cu")
		(net "P12V_AUX")
	)
	(segment
		(start 38.562788 -191.1604)
		(end 34.3916 -186.989212)
		(width 0.508)
		(layer "F.Cu")
		(net "P12V_AUX")
	)
	(segment
		(start 35.5346 -359.4354)
		(end 35.7886 -359.1814)
		(width 0.508)
		(layer "F.Cu")
		(net "P12V_AUX")
	)
	(segment
		(start 24.500078 -463.049874)
		(end 29.618686 -463.049874)
		(width 0.635)
		(layer "F.Cu")
		(net "P12V_AUX")
	)
	(segment
		(start 22.047454 -378.917454)
		(end 21.59 -378.46)
		(width 0.508)
		(layer "F.Cu")
		(net "P12V_AUX")
	)
	(segment
		(start 37.592 -369.443)
		(end 37.2872 -369.1382)
		(width 0.508)
		(layer "F.Cu")
		(net "P12V_AUX")
	)
	(segment
		(start 45.1485 -158.5722)
		(end 45.1485 -158.810452)
		(width 0.508)
		(layer "F.Cu")
		(net "P12V_AUX")
	)
	(segment
		(start 34.3916 -186.989212)
		(end 34.3916 -185.4327)
		(width 0.508)
		(layer "F.Cu")
		(net "P12V_AUX")
	)
	(segment
		(start 21.59 -378.46)
		(end 21.3995 -378.2695)
		(width 0.508)
		(layer "F.Cu")
		(net "P12V_AUX")
	)
	(segment
		(start 42.1132 -372.491)
		(end 40.259 -372.491)
		(width 0.508)
		(layer "F.Cu")
		(net "P12V_AUX")
	)
	(segment
		(start 38.6207 -362.5469)
		(end 38.692074 -362.618274)
		(width 0.508)
		(layer "F.Cu")
		(net "P12V_AUX")
	)
	(segment
		(start 24.500078 -443.95009)
		(end 29.618686 -443.95009)
		(width 0.635)
		(layer "F.Cu")
		(net "P12V_AUX")
	)
	(segment
		(start 35.7886 -359.1814)
		(end 38.391084 -359.1814)
		(width 0.508)
		(layer "F.Cu")
		(net "P12V_AUX")
	)
	(segment
		(start 21.3995 -378.2695)
		(end 21.3995 -376.936)
		(width 0.508)
		(layer "F.Cu")
		(net "P12V_AUX")
	)
	(segment
		(start 24.500078 -463.049874)
		(end 24.500078 -468.168482)
		(width 0.635)
		(layer "F.Cu")
		(net "P12V_AUX")
	)
	(segment
		(start 26.911046 -378.917454)
		(end 22.047454 -378.917454)
		(width 0.508)
		(layer "F.Cu")
		(net "P12V_AUX")
	)
	(segment
		(start 27.305 -378.5235)
		(end 26.911046 -378.917454)
		(width 0.508)
		(layer "F.Cu")
		(net "P12V_AUX")
	)
	(segment
		(start 38.619684 -360.4768)
		(end 38.619684 -361.542584)
		(width 0.508)
		(layer "F.Cu")
		(net "P12V_AUX")
	)
	(segment
		(start 42.418 -372.1862)
		(end 42.1132 -372.491)
		(width 0.508)
		(layer "F.Cu")
		(net "P12V_AUX")
	)
	(via
		(at 16.383 -457.581)
		(size 0.7112)
		(drill 0.4064)
		(layers "F.Cu" "B.Cu")
		(net "P12V_AUX")
	)
	(via
		(at 29.845 -421.513)
		(size 0.7112)
		(drill 0.4064)
		(layers "F.Cu" "B.Cu")
		(net "P12V_AUX")
	)
	(via
		(at 14.097 -437.769)
		(size 0.7112)
		(drill 0.4064)
		(layers "F.Cu" "B.Cu")
		(net "P12V_AUX")
	)
	(via
		(at 19.304 -418.084)
		(size 0.7112)
		(drill 0.4064)
		(layers "F.Cu" "B.Cu")
		(net "P12V_AUX")
	)
	(via
		(at 21.971 -455.44994)
		(size 0.7112)
		(drill 0.4064)
		(layers "F.Cu" "B.Cu")
		(net "P12V_AUX")
	)
	(via
		(at 28.067 -457.454)
		(size 0.7112)
		(drill 0.4064)
		(layers "F.Cu" "B.Cu")
		(net "P12V_AUX")
	)
	(via
		(at 16.383 -418.084)
		(size 0.7112)
		(drill 0.4064)
		(layers "F.Cu" "B.Cu")
		(net "P12V_AUX")
	)
	(via
		(at 30.353 -430.93894)
		(size 0.7112)
		(drill 0.4064)
		(layers "F.Cu" "B.Cu")
		(net "P12V_AUX")
	)
	(via
		(at 35.5346 -359.4354)
		(size 0.5588)
		(drill 0.3048)
		(layers "F.Cu" "B.Cu")
		(net "P12V_AUX")
	)
	(via
		(at 21.971 -438.404)
		(size 0.7112)
		(drill 0.4064)
		(layers "F.Cu" "B.Cu")
		(net "P12V_AUX")
	)
	(via
		(at 40.386 -414.655)
		(size 0.7112)
		(drill 0.4064)
		(layers "F.Cu" "B.Cu")
		(net "P12V_AUX")
	)
	(via
		(at 16.256 -415.036)
		(size 0.7112)
		(drill 0.4064)
		(layers "F.Cu" "B.Cu")
		(net "P12V_AUX")
	)
	(via
		(at 37.719 -421.64)
		(size 0.7112)
		(drill 0.4064)
		(layers "F.Cu" "B.Cu")
		(net "P12V_AUX")
	)
	(via
		(at 15.875 -431.8)
		(size 0.7112)
		(drill 0.4064)
		(layers "F.Cu" "B.Cu")
		(net "P12V_AUX")
	)
	(via
		(at 34.925 -421.513)
		(size 0.7112)
		(drill 0.4064)
		(layers "F.Cu" "B.Cu")
		(net "P12V_AUX")
	)
	(via
		(at 28.6385 -378.7775)
		(size 0.5588)
		(drill 0.3048)
		(layers "F.Cu" "B.Cu")
		(net "P12V_AUX")
	)
	(via
		(at 40.2844 -191.1604)
		(size 0.5588)
		(drill 0.3048)
		(layers "F.Cu" "B.Cu")
		(net "P12V_AUX")
	)
	(via
		(at 40.259 -372.491)
		(size 0.5588)
		(drill 0.3048)
		(layers "F.Cu" "B.Cu")
		(net "P12V_AUX")
	)
	(via
		(at 35.052 -418.084)
		(size 0.7112)
		(drill 0.4064)
		(layers "F.Cu" "B.Cu")
		(net "P12V_AUX")
	)
	(via
		(at 24.384 -418.084)
		(size 0.7112)
		(drill 0.4064)
		(layers "F.Cu" "B.Cu")
		(net "P12V_AUX")
	)
	(via
		(at 13.589 -421.386)
		(size 0.7112)
		(drill 0.4064)
		(layers "F.Cu" "B.Cu")
		(net "P12V_AUX")
	)
	(via
		(at 16.383 -460.248)
		(size 0.7112)
		(drill 0.4064)
		(layers "F.Cu" "B.Cu")
		(net "P12V_AUX")
	)
	(via
		(at 35.052 -415.036)
		(size 0.7112)
		(drill 0.4064)
		(layers "F.Cu" "B.Cu")
		(net "P12V_AUX")
	)
	(via
		(at 26.162 -427.99)
		(size 0.7112)
		(drill 0.4064)
		(layers "F.Cu" "B.Cu")
		(net "P12V_AUX")
	)
	(via
		(at 30.353 -456.311)
		(size 0.7112)
		(drill 0.4064)
		(layers "F.Cu" "B.Cu")
		(net "P12V_AUX")
	)
	(via
		(at 25.019 -436.118)
		(size 0.7112)
		(drill 0.4064)
		(layers "F.Cu" "B.Cu")
		(net "P12V_AUX")
	)
	(via
		(at 29.972 -418.084)
		(size 0.7112)
		(drill 0.4064)
		(layers "F.Cu" "B.Cu")
		(net "P12V_AUX")
	)
	(via
		(at 19.431 -380.619)
		(size 0.7112)
		(drill 0.3556)
		(layers "F.Cu" "B.Cu")
		(net "P12V_AUX")
	)
	(via
		(at 27.94 -434.213)
		(size 0.7112)
		(drill 0.4064)
		(layers "F.Cu" "B.Cu")
		(net "P12V_AUX")
	)
	(via
		(at 19.177 -426.466)
		(size 0.7112)
		(drill 0.4064)
		(layers "F.Cu" "B.Cu")
		(net "P12V_AUX")
	)
	(via
		(at 27.813 -436.753)
		(size 0.7112)
		(drill 0.4064)
		(layers "F.Cu" "B.Cu")
		(net "P12V_AUX")
	)
	(via
		(at 24.638 -421.513)
		(size 0.7112)
		(drill 0.4064)
		(layers "F.Cu" "B.Cu")
		(net "P12V_AUX")
	)
	(via
		(at 21.844 -415.036)
		(size 0.7112)
		(drill 0.4064)
		(layers "F.Cu" "B.Cu")
		(net "P12V_AUX")
	)
	(via
		(at 30.607 -470.027)
		(size 0.7112)
		(drill 0.4064)
		(layers "F.Cu" "B.Cu")
		(net "P12V_AUX")
	)
	(via
		(at 29.718 -414.909)
		(size 0.7112)
		(drill 0.4064)
		(layers "F.Cu" "B.Cu")
		(net "P12V_AUX")
	)
	(via
		(at 30.607 -466.471)
		(size 0.7112)
		(drill 0.4064)
		(layers "F.Cu" "B.Cu")
		(net "P12V_AUX")
	)
	(via
		(at 32.385 -421.513)
		(size 0.7112)
		(drill 0.4064)
		(layers "F.Cu" "B.Cu")
		(net "P12V_AUX")
	)
	(via
		(at 25.273 -473.075)
		(size 0.7112)
		(drill 0.4064)
		(layers "F.Cu" "B.Cu")
		(net "P12V_AUX")
	)
	(via
		(at 16.383 -446.659)
		(size 0.7112)
		(drill 0.4064)
		(layers "F.Cu" "B.Cu")
		(net "P12V_AUX")
	)
	(via
		(at 24.638 -470.027)
		(size 0.7112)
		(drill 0.4064)
		(layers "F.Cu" "B.Cu")
		(net "P12V_AUX")
	)
	(via
		(at 44.245784 -159.561784)
		(size 0.5588)
		(drill 0.3048)
		(layers "F.Cu" "B.Cu")
		(net "P12V_AUX")
	)
	(via
		(at 13.716 -418.211)
		(size 0.7112)
		(drill 0.4064)
		(layers "F.Cu" "B.Cu")
		(net "P12V_AUX")
	)
	(via
		(at 30.353 -438.17794)
		(size 0.7112)
		(drill 0.4064)
		(layers "F.Cu" "B.Cu")
		(net "P12V_AUX")
	)
	(via
		(at 27.432 -418.084)
		(size 0.7112)
		(drill 0.4064)
		(layers "F.Cu" "B.Cu")
		(net "P12V_AUX")
	)
	(via
		(at 19.177 -466.979)
		(size 0.7112)
		(drill 0.4064)
		(layers "F.Cu" "B.Cu")
		(net "P12V_AUX")
	)
	(via
		(at 24.765 -426.593)
		(size 0.7112)
		(drill 0.4064)
		(layers "F.Cu" "B.Cu")
		(net "P12V_AUX")
	)
	(via
		(at 22.479 -453.39)
		(size 0.7112)
		(drill 0.4064)
		(layers "F.Cu" "B.Cu")
		(net "P12V_AUX")
	)
	(via
		(at 20.574 -457.708)
		(size 0.7112)
		(drill 0.4064)
		(layers "F.Cu" "B.Cu")
		(net "P12V_AUX")
	)
	(via
		(at 15.621 -435.991)
		(size 0.7112)
		(drill 0.3556)
		(layers "F.Cu" "B.Cu")
		(net "P12V_AUX")
	)
	(via
		(at 24.638 -423.926)
		(size 0.7112)
		(drill 0.4064)
		(layers "F.Cu" "B.Cu")
		(net "P12V_AUX")
	)
	(via
		(at 17.78 -423.672)
		(size 0.7112)
		(drill 0.4064)
		(layers "F.Cu" "B.Cu")
		(net "P12V_AUX")
	)
	(via
		(at 14.097 -440.817)
		(size 0.7112)
		(drill 0.4064)
		(layers "F.Cu" "B.Cu")
		(net "P12V_AUX")
	)
	(via
		(at 15.24 -439.42)
		(size 0.7112)
		(drill 0.4064)
		(layers "F.Cu" "B.Cu")
		(net "P12V_AUX")
	)
	(via
		(at 24.511 -415.036)
		(size 0.7112)
		(drill 0.4064)
		(layers "F.Cu" "B.Cu")
		(net "P12V_AUX")
	)
	(via
		(at 44.704 -418.084)
		(size 0.7112)
		(drill 0.4064)
		(layers "F.Cu" "B.Cu")
		(net "P12V_AUX")
	)
	(via
		(at 21.6154 -468.503)
		(size 0.7112)
		(drill 0.4064)
		(layers "F.Cu" "B.Cu")
		(net "P12V_AUX")
	)
	(via
		(at 27.051 -473.075)
		(size 0.7112)
		(drill 0.4064)
		(layers "F.Cu" "B.Cu")
		(net "P12V_AUX")
	)
	(via
		(at 27.559 -470.30894)
		(size 0.7112)
		(drill 0.4064)
		(layers "F.Cu" "B.Cu")
		(net "P12V_AUX")
	)
	(via
		(at 16.256 -468.503)
		(size 0.7112)
		(drill 0.4064)
		(layers "F.Cu" "B.Cu")
		(net "P12V_AUX")
	)
	(via
		(at 45.212 -421.513)
		(size 0.7112)
		(drill 0.4064)
		(layers "F.Cu" "B.Cu")
		(net "P12V_AUX")
	)
	(via
		(at 19.177 -421.513)
		(size 0.7112)
		(drill 0.4064)
		(layers "F.Cu" "B.Cu")
		(net "P12V_AUX")
	)
	(via
		(at 20.066 -448.691)
		(size 0.7112)
		(drill 0.4064)
		(layers "F.Cu" "B.Cu")
		(net "P12V_AUX")
	)
	(via
		(at 18.161 -447.04)
		(size 0.7112)
		(drill 0.4064)
		(layers "F.Cu" "B.Cu")
		(net "P12V_AUX")
	)
	(via
		(at 27.559 -438.658)
		(size 0.7112)
		(drill 0.4064)
		(layers "F.Cu" "B.Cu")
		(net "P12V_AUX")
	)
	(via
		(at 25.019 -430.911)
		(size 0.7112)
		(drill 0.4064)
		(layers "F.Cu" "B.Cu")
		(net "P12V_AUX")
	)
	(via
		(at 18.542 -460.502)
		(size 0.7112)
		(drill 0.4064)
		(layers "F.Cu" "B.Cu")
		(net "P12V_AUX")
	)
	(via
		(at 17.526 -427.863)
		(size 0.7112)
		(drill 0.4064)
		(layers "F.Cu" "B.Cu")
		(net "P12V_AUX")
	)
	(via
		(at 16.383 -462.661)
		(size 0.7112)
		(drill 0.4064)
		(layers "F.Cu" "B.Cu")
		(net "P12V_AUX")
	)
	(via
		(at 27.305 -426.466)
		(size 0.7112)
		(drill 0.4064)
		(layers "F.Cu" "B.Cu")
		(net "P12V_AUX")
	)
	(via
		(at 25.146 -433.578)
		(size 0.7112)
		(drill 0.4064)
		(layers "F.Cu" "B.Cu")
		(net "P12V_AUX")
	)
	(via
		(at 24.892 -453.644)
		(size 0.7112)
		(drill 0.4064)
		(layers "F.Cu" "B.Cu")
		(net "P12V_AUX")
	)
	(via
		(at 27.813 -431.546)
		(size 0.7112)
		(drill 0.4064)
		(layers "F.Cu" "B.Cu")
		(net "P12V_AUX")
	)
	(via
		(at 15.875 -434.086)
		(size 0.7112)
		(drill 0.4064)
		(layers "F.Cu" "B.Cu")
		(net "P12V_AUX")
	)
	(via
		(at 14.224 -430.53)
		(size 0.7112)
		(drill 0.4064)
		(layers "F.Cu" "B.Cu")
		(net "P12V_AUX")
	)
	(via
		(at 16.51 -444.246)
		(size 0.7112)
		(drill 0.4064)
		(layers "F.Cu" "B.Cu")
		(net "P12V_AUX")
	)
	(via
		(at 32.385 -414.782)
		(size 0.7112)
		(drill 0.4064)
		(layers "F.Cu" "B.Cu")
		(net "P12V_AUX")
	)
	(via
		(at 30.48 -460.121)
		(size 0.7112)
		(drill 0.4064)
		(layers "F.Cu" "B.Cu")
		(net "P12V_AUX")
	)
	(via
		(at 30.353 -443.76594)
		(size 0.7112)
		(drill 0.4064)
		(layers "F.Cu" "B.Cu")
		(net "P12V_AUX")
	)
	(via
		(at 21.844 -418.084)
		(size 0.7112)
		(drill 0.4064)
		(layers "F.Cu" "B.Cu")
		(net "P12V_AUX")
	)
	(via
		(at 44.704 -414.528)
		(size 0.7112)
		(drill 0.4064)
		(layers "F.Cu" "B.Cu")
		(net "P12V_AUX")
	)
	(via
		(at 38.735 -369.824)
		(size 0.7112)
		(drill 0.4064)
		(layers "F.Cu" "B.Cu")
		(net "P12V_AUX")
	)
	(via
		(at 18.034 -473.583)
		(size 0.7112)
		(drill 0.3556)
		(layers "F.Cu" "B.Cu")
		(net "P12V_AUX")
	)
	(via
		(at 28.956 -468.249)
		(size 0.7112)
		(drill 0.4064)
		(layers "F.Cu" "B.Cu")
		(net "P12V_AUX")
	)
	(via
		(at 18.415 -464.82)
		(size 0.7112)
		(drill 0.4064)
		(layers "F.Cu" "B.Cu")
		(net "P12V_AUX")
	)
	(via
		(at 21.844 -423.926)
		(size 0.7112)
		(drill 0.4064)
		(layers "F.Cu" "B.Cu")
		(net "P12V_AUX")
	)
	(via
		(at 15.113 -423.418)
		(size 0.7112)
		(drill 0.4064)
		(layers "F.Cu" "B.Cu")
		(net "P12V_AUX")
	)
	(via
		(at 21.844 -421.513)
		(size 0.7112)
		(drill 0.4064)
		(layers "F.Cu" "B.Cu")
		(net "P12V_AUX")
	)
	(via
		(at 27.178 -421.513)
		(size 0.7112)
		(drill 0.4064)
		(layers "F.Cu" "B.Cu")
		(net "P12V_AUX")
	)
	(via
		(at 29.845 -439.928)
		(size 0.7112)
		(drill 0.4064)
		(layers "F.Cu" "B.Cu")
		(net "P12V_AUX")
	)
	(via
		(at 16.129 -473.202)
		(size 0.7112)
		(drill 0.4064)
		(layers "F.Cu" "B.Cu")
		(net "P12V_AUX")
	)
	(via
		(at 14.224 -432.943)
		(size 0.7112)
		(drill 0.4064)
		(layers "F.Cu" "B.Cu")
		(net "P12V_AUX")
	)
	(via
		(at 18.415 -440.182)
		(size 0.7112)
		(drill 0.4064)
		(layers "F.Cu" "B.Cu")
		(net "P12V_AUX")
	)
	(via
		(at 21.7678 -470.4842)
		(size 0.7112)
		(drill 0.4064)
		(layers "F.Cu" "B.Cu")
		(net "P12V_AUX")
	)
	(via
		(at 40.132 -418.084)
		(size 0.7112)
		(drill 0.4064)
		(layers "F.Cu" "B.Cu")
		(net "P12V_AUX")
	)
	(via
		(at 31.75 -426.466)
		(size 0.7112)
		(drill 0.4064)
		(layers "F.Cu" "B.Cu")
		(net "P12V_AUX")
	)
	(via
		(at 16.51 -449.072)
		(size 0.7112)
		(drill 0.4064)
		(layers "F.Cu" "B.Cu")
		(net "P12V_AUX")
	)
	(via
		(at 21.336 -474.8784)
		(size 0.7112)
		(drill 0.3556)
		(layers "F.Cu" "B.Cu")
		(net "P12V_AUX")
	)
	(via
		(at 34.671 -419.354)
		(size 0.7112)
		(drill 0.3556)
		(layers "F.Cu" "B.Cu")
		(net "P12V_AUX")
	)
	(via
		(at 23.114 -427.99)
		(size 0.7112)
		(drill 0.4064)
		(layers "F.Cu" "B.Cu")
		(net "P12V_AUX")
	)
	(via
		(at 32.258 -418.084)
		(size 0.7112)
		(drill 0.4064)
		(layers "F.Cu" "B.Cu")
		(net "P12V_AUX")
	)
	(via
		(at 28.575 -427.99)
		(size 0.7112)
		(drill 0.4064)
		(layers "F.Cu" "B.Cu")
		(net "P12V_AUX")
	)
	(via
		(at 21.59 -378.46)
		(size 0.7112)
		(drill 0.4064)
		(layers "F.Cu" "B.Cu")
		(net "P12V_AUX")
	)
	(via
		(at 37.846 -414.655)
		(size 0.7112)
		(drill 0.4064)
		(layers "F.Cu" "B.Cu")
		(net "P12V_AUX")
	)
	(via
		(at 13.97 -415.036)
		(size 0.7112)
		(drill 0.4064)
		(layers "F.Cu" "B.Cu")
		(net "P12V_AUX")
	)
	(via
		(at 42.545 -414.655)
		(size 0.7112)
		(drill 0.4064)
		(layers "F.Cu" "B.Cu")
		(net "P12V_AUX")
	)
	(via
		(at 21.971 -431.82794)
		(size 0.7112)
		(drill 0.4064)
		(layers "F.Cu" "B.Cu")
		(net "P12V_AUX")
	)
	(via
		(at 28.321 -449.199)
		(size 0.7112)
		(drill 0.4064)
		(layers "F.Cu" "B.Cu")
		(net "P12V_AUX")
	)
	(via
		(at 26.924 -415.036)
		(size 0.7112)
		(drill 0.4064)
		(layers "F.Cu" "B.Cu")
		(net "P12V_AUX")
	)
	(via
		(at 18.288 -456.692)
		(size 0.7112)
		(drill 0.4064)
		(layers "F.Cu" "B.Cu")
		(net "P12V_AUX")
	)
	(via
		(at 27.500072 -451.4342)
		(size 0.7112)
		(drill 0.4064)
		(layers "F.Cu" "B.Cu")
		(net "P12V_AUX")
	)
	(via
		(at 16.51 -454.66)
		(size 0.7112)
		(drill 0.4064)
		(layers "F.Cu" "B.Cu")
		(net "P12V_AUX")
	)
	(via
		(at 27.373072 -454.43394)
		(size 0.7112)
		(drill 0.4064)
		(layers "F.Cu" "B.Cu")
		(net "P12V_AUX")
	)
	(via
		(at 16.383 -421.259)
		(size 0.7112)
		(drill 0.4064)
		(layers "F.Cu" "B.Cu")
		(net "P12V_AUX")
	)
	(via
		(at 15.113 -413.385)
		(size 0.7112)
		(drill 0.3556)
		(layers "F.Cu" "B.Cu")
		(net "P12V_AUX")
	)
	(via
		(at 30.353 -434.36794)
		(size 0.7112)
		(drill 0.4064)
		(layers "F.Cu" "B.Cu")
		(net "P12V_AUX")
	)
	(via
		(at 29.083 -473.075)
		(size 0.7112)
		(drill 0.4064)
		(layers "F.Cu" "B.Cu")
		(net "P12V_AUX")
	)
	(via
		(at 29.845 -423.926)
		(size 0.7112)
		(drill 0.4064)
		(layers "F.Cu" "B.Cu")
		(net "P12V_AUX")
	)
	(via
		(at 15.8242 -416.8902)
		(size 0.7112)
		(drill 0.3556)
		(layers "F.Cu" "B.Cu")
		(net "P12V_AUX")
	)
	(via
		(at 29.845 -426.466)
		(size 0.7112)
		(drill 0.4064)
		(layers "F.Cu" "B.Cu")
		(net "P12V_AUX")
	)
	(via
		(at 16.51 -437.896)
		(size 0.7112)
		(drill 0.4064)
		(layers "F.Cu" "B.Cu")
		(net "P12V_AUX")
	)
	(via
		(at 42.164 -418.084)
		(size 0.7112)
		(drill 0.4064)
		(layers "F.Cu" "B.Cu")
		(net "P12V_AUX")
	)
	(via
		(at 14.224 -434.975)
		(size 0.7112)
		(drill 0.4064)
		(layers "F.Cu" "B.Cu")
		(net "P12V_AUX")
	)
	(via
		(at 24.765 -450.977)
		(size 0.7112)
		(drill 0.4064)
		(layers "F.Cu" "B.Cu")
		(net "P12V_AUX")
	)
	(via
		(at 20.447 -427.863)
		(size 0.7112)
		(drill 0.4064)
		(layers "F.Cu" "B.Cu")
		(net "P12V_AUX")
	)
	(via
		(at 27.178 -423.926)
		(size 0.7112)
		(drill 0.4064)
		(layers "F.Cu" "B.Cu")
		(net "P12V_AUX")
	)
	(via
		(at 18.542 -469.138)
		(size 0.7112)
		(drill 0.4064)
		(layers "F.Cu" "B.Cu")
		(net "P12V_AUX")
	)
	(via
		(at 19.304 -415.036)
		(size 0.7112)
		(drill 0.4064)
		(layers "F.Cu" "B.Cu")
		(net "P12V_AUX")
	)
	(via
		(at 37.592 -418.084)
		(size 0.7112)
		(drill 0.4064)
		(layers "F.Cu" "B.Cu")
		(net "P12V_AUX")
	)
	(via
		(at 16.129 -471.424)
		(size 0.7112)
		(drill 0.4064)
		(layers "F.Cu" "B.Cu")
		(net "P12V_AUX")
	)
	(via
		(at 21.844 -426.466)
		(size 0.7112)
		(drill 0.4064)
		(layers "F.Cu" "B.Cu")
		(net "P12V_AUX")
	)
	(via
		(at 40.386 -421.513)
		(size 0.7112)
		(drill 0.4064)
		(layers "F.Cu" "B.Cu")
		(net "P12V_AUX")
	)
	(via
		(at 21.209 -373.253)
		(size 0.7112)
		(drill 0.4064)
		(layers "F.Cu" "B.Cu")
		(net "P12V_AUX")
	)
	(via
		(at 30.988 -428.117)
		(size 0.7112)
		(drill 0.4064)
		(layers "F.Cu" "B.Cu")
		(net "P12V_AUX")
	)
	(via
		(at 24.765 -456.184)
		(size 0.7112)
		(drill 0.4064)
		(layers "F.Cu" "B.Cu")
		(net "P12V_AUX")
	)
	(via
		(at 43.18 -421.513)
		(size 0.7112)
		(drill 0.4064)
		(layers "F.Cu" "B.Cu")
		(net "P12V_AUX")
	)
	(via
		(at 18.415 -436.118)
		(size 0.7112)
		(drill 0.4064)
		(layers "F.Cu" "B.Cu")
		(net "P12V_AUX")
	)
	(via
		(at 15.875 -429.641)
		(size 0.7112)
		(drill 0.4064)
		(layers "F.Cu" "B.Cu")
		(net "P12V_AUX")
	)
	(via
		(at 16.51 -440.69)
		(size 0.7112)
		(drill 0.4064)
		(layers "F.Cu" "B.Cu")
		(net "P12V_AUX")
	)
	(via
		(at 22.098 -450.62394)
		(size 0.7112)
		(drill 0.4064)
		(layers "F.Cu" "B.Cu")
		(net "P12V_AUX")
	)
	(via
		(at 16.256 -465.836)
		(size 0.7112)
		(drill 0.4064)
		(layers "F.Cu" "B.Cu")
		(net "P12V_AUX")
	)
	(via
		(at 30.353 -447.04)
		(size 0.7112)
		(drill 0.4064)
		(layers "F.Cu" "B.Cu")
		(net "P12V_AUX")
	)
	(via
		(at 21.971 -435.25694)
		(size 0.7112)
		(drill 0.4064)
		(layers "F.Cu" "B.Cu")
		(net "P12V_AUX")
	)
	(via
		(at 32.385 -423.926)
		(size 0.7112)
		(drill 0.4064)
		(layers "F.Cu" "B.Cu")
		(net "P12V_AUX")
	)
	(via
		(at 31.115 -473.075)
		(size 0.7112)
		(drill 0.4064)
		(layers "F.Cu" "B.Cu")
		(net "P12V_AUX")
	)
	(via
		(at 16.51 -442.595)
		(size 0.7112)
		(drill 0.4064)
		(layers "F.Cu" "B.Cu")
		(net "P12V_AUX")
	)
	(via
		(at 18.415 -431.546)
		(size 0.7112)
		(drill 0.4064)
		(layers "F.Cu" "B.Cu")
		(net "P12V_AUX")
	)
	(segment
		(start 36.7538 -370.84)
		(end 36.7538 -370.840508)
		(width 0.508)
		(layer "B.Cu")
		(net "P12V_AUX")
	)
	(segment
		(start 28.816808 -378.7775)
		(end 28.6385 -378.7775)
		(width 0.508)
		(layer "B.Cu")
		(net "P12V_AUX")
	)
	(segment
		(start 40.2844 -191.1604)
		(end 40.2844 -187.2742)
		(width 0.508)
		(layer "B.Cu")
		(net "P12V_AUX")
	)
	(segment
		(start 40.2844 -187.2742)
		(end 41.275 -186.2836)
		(width 0.508)
		(layer "B.Cu")
		(net "P12V_AUX")
	)
	(segment
		(start 24.500078 -443.95009)
		(end 24.500078 -449.068698)
		(width 0.635)
		(layer "B.Cu")
		(net "P12V_AUX")
	)
	(segment
		(start 21.4122 -373.4562)
		(end 21.209 -373.253)
		(width 1.016)
		(layer "B.Cu")
		(net "P12V_AUX")
	)
	(segment
		(start 21.4122 -378.2822)
		(end 21.4122 -373.4562)
		(width 1.016)
		(layer "B.Cu")
		(net "P12V_AUX")
	)
	(segment
		(start 38.735 -370.560092)
		(end 40.259 -372.084092)
		(width 0.508)
		(layer "B.Cu")
		(net "P12V_AUX")
	)
	(segment
		(start 41.275 -186.2836)
		(end 41.275 -178.1048)
		(width 0.508)
		(layer "B.Cu")
		(net "P12V_AUX")
	)
	(segment
		(start 40.2844 -209.9818)
		(end 40.2844 -191.1604)
		(width 0.508)
		(layer "B.Cu")
		(net "P12V_AUX")
	)
	(segment
		(start 38.735 -369.824)
		(end 37.7698 -369.824)
		(width 0.508)
		(layer "B.Cu")
		(net "P12V_AUX")
	)
	(segment
		(start 24.500078 -438.831482)
		(end 24.500078 -443.95009)
		(width 0.635)
		(layer "B.Cu")
		(net "P12V_AUX")
	)
	(segment
		(start 19.38147 -443.95009)
		(end 24.500078 -443.95009)
		(width 0.635)
		(layer "B.Cu")
		(net "P12V_AUX")
	)
	(segment
		(start 19.38147 -463.049874)
		(end 24.500078 -463.049874)
		(width 0.635)
		(layer "B.Cu")
		(net "P12V_AUX")
	)
	(segment
		(start 21.59 -378.46)
		(end 19.431 -380.619)
		(width 1.016)
		(layer "B.Cu")
		(net "P12V_AUX")
	)
	(segment
		(start 38.735 -369.564412)
		(end 38.735 -369.824)
		(width 0.508)
		(layer "B.Cu")
		(net "P12V_AUX")
	)
	(segment
		(start 40.259 -372.084092)
		(end 40.259 -372.491)
		(width 0.508)
		(layer "B.Cu")
		(net "P12V_AUX")
	)
	(segment
		(start 35.306 -359.2068)
		(end 35.306 -279.527)
		(width 0.508)
		(layer "B.Cu")
		(net "P12V_AUX")
	)
	(segment
		(start 38.735 -369.824)
		(end 38.735 -370.560092)
		(width 0.508)
		(layer "B.Cu")
		(net "P12V_AUX")
	)
	(segment
		(start 35.306 -279.527)
		(end 37.211 -277.622)
		(width 0.508)
		(layer "B.Cu")
		(net "P12V_AUX")
	)
	(segment
		(start 43.9674 -175.4124)
		(end 43.9674 -159.840168)
		(width 0.508)
		(layer "B.Cu")
		(net "P12V_AUX")
	)
	(segment
		(start 37.211 -277.622)
		(end 37.211 -260.883908)
		(width 0.508)
		(layer "B.Cu")
		(net "P12V_AUX")
	)
	(segment
		(start 24.500078 -457.931266)
		(end 24.500078 -463.049874)
		(width 0.635)
		(layer "B.Cu")
		(net "P12V_AUX")
	)
	(segment
		(start 44.87545 -253.219458)
		(end 44.87545 -214.57285)
		(width 0.508)
		(layer "B.Cu")
		(net "P12V_AUX")
	)
	(segment
		(start 24.500078 -443.95009)
		(end 29.618686 -443.95009)
		(width 0.635)
		(layer "B.Cu")
		(net "P12V_AUX")
	)
	(segment
		(start 43.9674 -159.840168)
		(end 44.245784 -159.561784)
		(width 0.508)
		(layer "B.Cu")
		(net "P12V_AUX")
	)
	(segment
		(start 21.59 -378.46)
		(end 21.4122 -378.2822)
		(width 1.016)
		(layer "B.Cu")
		(net "P12V_AUX")
	)
	(segment
		(start 35.5346 -366.364012)
		(end 38.735 -369.564412)
		(width 0.508)
		(layer "B.Cu")
		(net "P12V_AUX")
	)
	(segment
		(start 16.1036 -383.9464)
		(end 16.1036 -412.9024)
		(width 1.016)
		(layer "B.Cu")
		(net "P12V_AUX")
	)
	(segment
		(start 35.5346 -359.4354)
		(end 35.306 -359.2068)
		(width 0.508)
		(layer "B.Cu")
		(net "P12V_AUX")
	)
	(segment
		(start 41.275 -178.1048)
		(end 43.9674 -175.4124)
		(width 0.508)
		(layer "B.Cu")
		(net "P12V_AUX")
	)
	(segment
		(start 35.5346 -359.4354)
		(end 35.5346 -366.364012)
		(width 0.508)
		(layer "B.Cu")
		(net "P12V_AUX")
	)
	(segment
		(start 24.500078 -463.049874)
		(end 24.500078 -468.168482)
		(width 0.635)
		(layer "B.Cu")
		(net "P12V_AUX")
	)
	(segment
		(start 44.87545 -214.57285)
		(end 40.2844 -209.9818)
		(width 0.508)
		(layer "B.Cu")
		(net "P12V_AUX")
	)
	(segment
		(start 37.7698 -369.824)
		(end 36.7538 -370.84)
		(width 0.508)
		(layer "B.Cu")
		(net "P12V_AUX")
	)
	(segment
		(start 24.500078 -463.049874)
		(end 29.618686 -463.049874)
		(width 0.635)
		(layer "B.Cu")
		(net "P12V_AUX")
	)
	(segment
		(start 37.211 -260.883908)
		(end 44.87545 -253.219458)
		(width 0.508)
		(layer "B.Cu")
		(net "P12V_AUX")
	)
	(segment
		(start 19.431 -380.619)
		(end 16.1036 -383.9464)
		(width 1.016)
		(layer "B.Cu")
		(net "P12V_AUX")
	)
	(segment
		(start 16.1036 -412.9024)
		(end 13.97 -415.036)
		(width 1.016)
		(layer "B.Cu")
		(net "P12V_AUX")
	)
	(segment
		(start 36.7538 -370.840508)
		(end 28.816808 -378.7775)
		(width 0.508)
		(layer "B.Cu")
		(net "P12V_AUX")
	)
	(segment
		(start 24.8666 -363.601)
		(end 24.0665 -363.601)
		(width 0.254)
		(layer "F.Cu")
		(net "ADM1276_TIMER")
	)
	(segment
		(start 25.4508 -364.1852)
		(end 24.8666 -363.601)
		(width 0.254)
		(layer "F.Cu")
		(net "ADM1276_TIMER")
	)
	(segment
		(start 27.2796 -366.7506)
		(end 25.4508 -364.9218)
		(width 0.254)
		(layer "F.Cu")
		(net "ADM1276_TIMER")
	)
	(segment
		(start 27.2796 -367.508028)
		(end 27.2796 -366.7506)
		(width 0.254)
		(layer "F.Cu")
		(net "ADM1276_TIMER")
	)
	(segment
		(start 25.4508 -364.9218)
		(end 25.4508 -364.1852)
		(width 0.254)
		(layer "F.Cu")
		(net "ADM1276_TIMER")
	)
	(via
		(at 25.4508 -364.1852)
		(size 0.7112)
		(drill 0.3556)
		(layers "F.Cu" "B.Cu")
		(net "ADM1276_TIMER")
	)
	(segment
		(start 33.5026 -370.1034)
		(end 33.5026 -369.8494)
		(width 0.381)
		(layer "F.Cu")
		(net "ADM1276_VOUT")
	)
	(segment
		(start 34.5694 -371.8306)
		(end 34.5694 -371.1702)
		(width 0.508)
		(layer "F.Cu")
		(net "ADM1276_VOUT")
	)
	(segment
		(start 35.6743 -372.4656)
		(end 35.2044 -372.4656)
		(width 0.508)
		(layer "F.Cu")
		(net "ADM1276_VOUT")
	)
	(segment
		(start 34.5694 -371.1702)
		(end 33.5026 -370.1034)
		(width 0.508)
		(layer "F.Cu")
		(net "ADM1276_VOUT")
	)
	(segment
		(start 33.111186 -369.457986)
		(end 32.1564 -369.457986)
		(width 0.381)
		(layer "F.Cu")
		(net "ADM1276_VOUT")
	)
	(segment
		(start 33.5026 -369.8494)
		(end 33.111186 -369.457986)
		(width 0.381)
		(layer "F.Cu")
		(net "ADM1276_VOUT")
	)
	(segment
		(start 35.2044 -372.4656)
		(end 34.5694 -371.8306)
		(width 0.508)
		(layer "F.Cu")
		(net "ADM1276_VOUT")
	)
	(via
		(at 34.5694 -371.8306)
		(size 0.7112)
		(drill 0.3556)
		(layers "F.Cu" "B.Cu")
		(net "ADM1276_VOUT")
	)
	(segment
		(start 21.85924 -176.08677)
		(end 22.0726 -175.87341)
		(width 0.1397)
		(layer "F.Cu")
		(net "NCT7368S_SEL")
	)
	(segment
		(start 22.0726 -175.87341)
		(end 23.674324 -175.87341)
		(width 0.1397)
		(layer "F.Cu")
		(net "NCT7368S_SEL")
	)
	(segment
		(start 20.829524 -175.37811)
		(end 20.826476 -175.381158)
		(width 0.1397)
		(layer "F.Cu")
		(net "NCT7368S_SEL")
	)
	(segment
		(start 20.826476 -176.43729)
		(end 21.71573 -176.43729)
		(width 0.1397)
		(layer "F.Cu")
		(net "NCT7368S_SEL")
	)
	(segment
		(start 20.826476 -175.381158)
		(end 20.826476 -176.43729)
		(width 0.1397)
		(layer "F.Cu")
		(net "NCT7368S_SEL")
	)
	(segment
		(start 21.71573 -176.43729)
		(end 21.85924 -176.5808)
		(width 0.1397)
		(layer "F.Cu")
		(net "NCT7368S_SEL")
	)
	(segment
		(start 21.85924 -176.5808)
		(end 21.85924 -176.08677)
		(width 0.1397)
		(layer "F.Cu")
		(net "NCT7368S_SEL")
	)
	(via
		(at 21.85924 -176.5808)
		(size 0.7112)
		(drill 0.3556)
		(layers "F.Cu" "B.Cu")
		(net "NCT7368S_SEL")
	)
	(segment
		(start 25.68067 -153.237692)
		(end 25.68067 -151.856694)
		(width 0.1397)
		(layer "F.Cu")
		(net "NCT7904_3VSB")
	)
	(segment
		(start 41.17975 -155.20035)
		(end 41.17975 -155.200096)
		(width 0.1397)
		(layer "F.Cu")
		(net "NCT7904_3VSB")
	)
	(segment
		(start 41.547796 -154.83205)
		(end 41.54805 -154.83205)
		(width 0.1397)
		(layer "F.Cu")
		(net "NCT7904_3VSB")
	)
	(segment
		(start 26.12009 -157.100016)
		(end 27.306016 -157.100016)
		(width 0.1397)
		(layer "F.Cu")
		(net "NCT7904_3VSB")
	)
	(segment
		(start 28.80487 -158.599886)
		(end 34.60369 -158.599886)
		(width 0.1397)
		(layer "F.Cu")
		(net "NCT7904_3VSB")
	)
	(segment
		(start 38.105842 -155.533344)
		(end 40.846756 -155.533344)
		(width 0.1397)
		(layer "F.Cu")
		(net "NCT7904_3VSB")
	)
	(segment
		(start 43.2054 -154.3304)
		(end 42.0497 -154.3304)
		(width 0.1397)
		(layer "F.Cu")
		(net "NCT7904_3VSB")
	)
	(segment
		(start 43.2054 -154.3304)
		(end 44.51731 -154.3304)
		(width 0.1397)
		(layer "F.Cu")
		(net "NCT7904_3VSB")
	)
	(segment
		(start 37.1348 -157.20949)
		(end 37.1348 -156.504386)
		(width 0.1397)
		(layer "F.Cu")
		(net "NCT7904_3VSB")
	)
	(segment
		(start 25.68067 -151.856694)
		(end 24.70531 -150.881334)
		(width 0.1397)
		(layer "F.Cu")
		(net "NCT7904_3VSB")
	)
	(segment
		(start 27.94889 -157.74289)
		(end 27.94889 -157.768544)
		(width 0.1397)
		(layer "F.Cu")
		(net "NCT7904_3VSB")
	)
	(segment
		(start 28.779724 -158.599378)
		(end 28.804362 -158.599378)
		(width 0.1397)
		(layer "F.Cu")
		(net "NCT7904_3VSB")
	)
	(segment
		(start 40.846756 -155.533344)
		(end 41.17975 -155.20035)
		(width 0.1397)
		(layer "F.Cu")
		(net "NCT7904_3VSB")
	)
	(segment
		(start 26.12009 -157.100016)
		(end 26.12009 -153.677112)
		(width 0.1397)
		(layer "F.Cu")
		(net "NCT7904_3VSB")
	)
	(segment
		(start 44.760134 -154.613356)
		(end 44.7802 -154.59329)
		(width 0.1397)
		(layer "F.Cu")
		(net "NCT7904_3VSB")
	)
	(segment
		(start 27.306016 -157.100016)
		(end 27.94889 -157.74289)
		(width 0.1397)
		(layer "F.Cu")
		(net "NCT7904_3VSB")
	)
	(segment
		(start 41.54805 -154.83205)
		(end 41.8084 -154.5717)
		(width 0.1397)
		(layer "F.Cu")
		(net "NCT7904_3VSB")
	)
	(segment
		(start 34.60369 -158.599886)
		(end 35.744404 -158.599886)
		(width 0.1397)
		(layer "F.Cu")
		(net "NCT7904_3VSB")
	)
	(segment
		(start 42.0497 -154.3304)
		(end 41.8084 -154.5717)
		(width 0.1397)
		(layer "F.Cu")
		(net "NCT7904_3VSB")
	)
	(segment
		(start 37.1348 -156.504386)
		(end 38.105842 -155.533344)
		(width 0.1397)
		(layer "F.Cu")
		(net "NCT7904_3VSB")
	)
	(segment
		(start 26.12009 -153.677112)
		(end 25.68067 -153.237692)
		(width 0.1397)
		(layer "F.Cu")
		(net "NCT7904_3VSB")
	)
	(segment
		(start 41.17975 -155.200096)
		(end 41.547796 -154.83205)
		(width 0.1397)
		(layer "F.Cu")
		(net "NCT7904_3VSB")
	)
	(segment
		(start 27.94889 -157.768544)
		(end 28.779724 -158.599378)
		(width 0.1397)
		(layer "F.Cu")
		(net "NCT7904_3VSB")
	)
	(segment
		(start 44.51731 -154.3304)
		(end 44.7802 -154.59329)
		(width 0.1397)
		(layer "F.Cu")
		(net "NCT7904_3VSB")
	)
	(segment
		(start 28.804362 -158.599378)
		(end 28.80487 -158.599886)
		(width 0.1397)
		(layer "F.Cu")
		(net "NCT7904_3VSB")
	)
	(segment
		(start 44.760134 -155.83789)
		(end 44.760134 -154.613356)
		(width 0.1397)
		(layer "F.Cu")
		(net "NCT7904_3VSB")
	)
	(segment
		(start 35.744404 -158.599886)
		(end 37.1348 -157.20949)
		(width 0.1397)
		(layer "F.Cu")
		(net "NCT7904_3VSB")
	)
	(via
		(at 44.7802 -154.59329)
		(size 0.7112)
		(drill 0.3556)
		(layers "F.Cu" "B.Cu")
		(net "NCT7904_3VSB")
	)
	(segment
		(start 25.654 -374.142)
		(end 26.3398 -373.4562)
		(width 0.508)
		(layer "F.Cu")
		(net "GND")
	)
	(segment
		(start 13.5128 -43.5102)
		(end 13.462 -43.561)
		(width 0.508)
		(layer "F.Cu")
		(net "GND")
	)
	(segment
		(start 20.2438 -143.6878)
		(end 20.096988 -143.6878)
		(width 0.3048)
		(layer "F.Cu")
		(net "GND")
	)
	(segment
		(start 15.9004 -250.5964)
		(end 15.3162 -250.0122)
		(width 0.508)
		(layer "F.Cu")
		(net "GND")
	)
	(segment
		(start 39.56685 -354.89515)
		(end 39.5986 -354.8634)
		(width 0.508)
		(layer "F.Cu")
		(net "GND")
	)
	(segment
		(start 30.89656 -244.602)
		(end 30.89656 -244.08384)
		(width 0.4572)
		(layer "F.Cu")
		(net "GND")
	)
	(segment
		(start 45.500036 -480.000056)
		(end 45.500036 -484.356664)
		(width 0.635)
		(layer "F.Cu")
		(net "GND")
	)
	(segment
		(start 40.539924 -43.659806)
		(end 41.619932 -43.659806)
		(width 0.635)
		(layer "F.Cu")
		(net "GND")
	)
	(segment
		(start 40.999918 -457.931266)
		(end 40.999918 -463.049874)
		(width 0.635)
		(layer "F.Cu")
		(net "GND")
	)
	(segment
		(start 19.417538 -288.149538)
		(end 18.796 -287.528)
		(width 0.508)
		(layer "F.Cu")
		(net "GND")
	)
	(segment
		(start 41.4782 -176.3776)
		(end 41.4782 -176.8602)
		(width 0.508)
		(layer "F.Cu")
		(net "GND")
	)
	(segment
		(start 37.211 -360.075226)
		(end 37.211 -361.242102)
		(width 0.508)
		(layer "F.Cu")
		(net "GND")
	)
	(segment
		(start 43.079924 -40.039798)
		(end 43.079924 -41.119806)
		(width 0.635)
		(layer "F.Cu")
		(net "GND")
	)
	(segment
		(start 16.1798 -277.0124)
		(end 16.1798 -278.9428)
		(width 0.508)
		(layer "F.Cu")
		(net "GND")
	)
	(segment
		(start 9.0043 -87.3125)
		(end 9.9568 -87.3125)
		(width 0.508)
		(layer "F.Cu")
		(net "GND")
	)
	(segment
		(start 17.1831 -291.5539)
		(end 16.764 -291.973)
		(width 0.508)
		(layer "F.Cu")
		(net "GND")
	)
	(segment
		(start 37.580316 -354.457)
		(end 37.580316 -354.076)
		(width 0.508)
		(layer "F.Cu")
		(net "GND")
	)
	(segment
		(start 15.3289 -41.4782)
		(end 15.748 -41.4782)
		(width 0.508)
		(layer "F.Cu")
		(net "GND")
	)
	(segment
		(start 23.876 -362.6612)
		(end 24.2824 -362.2548)
		(width 0.508)
		(layer "F.Cu")
		(net "GND")
	)
	(segment
		(start 24.003 -248.031)
		(end 22.4028 -248.031)
		(width 0.508)
		(layer "F.Cu")
		(net "GND")
	)
	(segment
		(start 4.040124 -22.37994)
		(end 5.107432 -22.37994)
		(width 0.635)
		(layer "F.Cu")
		(net "GND")
	)
	(segment
		(start 45.499782 -144.999964)
		(end 49.85639 -144.999964)
		(width 0.635)
		(layer "F.Cu")
		(net "GND")
	)
	(segment
		(start 37.999924 -48.739806)
		(end 37.999924 -49.819814)
		(width 0.635)
		(layer "F.Cu")
		(net "GND")
	)
	(segment
		(start 13.843 -56.134)
		(end 13.7668 -56.0578)
		(width 0.508)
		(layer "F.Cu")
		(net "GND")
	)
	(segment
		(start 37.2618 -121.031)
		(end 36.576 -121.031)
		(width 0.508)
		(layer "F.Cu")
		(net "GND")
	)
	(segment
		(start 38.481 -370.713)
		(end 38.149022 -370.713)
		(width 0.508)
		(layer "F.Cu")
		(net "GND")
	)
	(segment
		(start 40.539924 -48.739806)
		(end 41.619932 -48.739806)
		(width 0.635)
		(layer "F.Cu")
		(net "GND")
	)
	(segment
		(start 26.416 -269.875)
		(end 26.797 -269.494)
		(width 0.508)
		(layer "F.Cu")
		(net "GND")
	)
	(segment
		(start 4.040124 -198.419974)
		(end 4.845558 -199.225408)
		(width 0.635)
		(layer "F.Cu")
		(net "GND")
	)
	(segment
		(start 45.619924 -48.739806)
		(end 46.699932 -48.739806)
		(width 0.635)
		(layer "F.Cu")
		(net "GND")
	)
	(segment
		(start 45.619924 -41.119806)
		(end 45.619924 -42.199814)
		(width 0.635)
		(layer "F.Cu")
		(net "GND")
	)
	(segment
		(start 16.052292 -291.261292)
		(end 16.052292 -290.081462)
		(width 0.508)
		(layer "F.Cu")
		(net "GND")
	)
	(segment
		(start 29.791914 -179.524914)
		(end 29.21 -178.943)
		(width 0.508)
		(layer "F.Cu")
		(net "GND")
	)
	(segment
		(start 9.4488 -65.833244)
		(end 9.144 -66.138044)
		(width 0.508)
		(layer "F.Cu")
		(net "GND")
	)
	(segment
		(start 8.636 -429.641)
		(end 8.219186 -429.224186)
		(width 0.508)
		(layer "F.Cu")
		(net "GND")
	)
	(segment
		(start 14.1351 -262.7249)
		(end 13.843 -263.017)
		(width 0.508)
		(layer "F.Cu")
		(net "GND")
	)
	(segment
		(start 37.4015 -178.4985)
		(end 37.338 -178.562)
		(width 0.508)
		(layer "F.Cu")
		(net "GND")
	)
	(segment
		(start 6.92404 -278.627332)
		(end 6.913372 -278.638)
		(width 0.508)
		(layer "F.Cu")
		(net "GND")
	)
	(segment
		(start 8.89 -148.5519)
		(end 7.9121 -148.5519)
		(width 0.508)
		(layer "F.Cu")
		(net "GND")
	)
	(segment
		(start 37.338 -187.198)
		(end 37.084 -187.452)
		(width 0.508)
		(layer "F.Cu")
		(net "GND")
	)
	(segment
		(start 29.464 -194.0814)
		(end 29.7688 -194.0814)
		(width 0.508)
		(layer "F.Cu")
		(net "GND")
	)
	(segment
		(start 40.5638 -165.608)
		(end 40.5892 -165.5826)
		(width 0.508)
		(layer "F.Cu")
		(net "GND")
	)
	(segment
		(start 13.7668 -52.7939)
		(end 14.5796 -52.7939)
		(width 0.508)
		(layer "F.Cu")
		(net "GND")
	)
	(segment
		(start 28.9052 -354.87356)
		(end 28.9052 -354.7872)
		(width 0.4064)
		(layer "F.Cu")
		(net "GND")
	)
	(segment
		(start 7.7597 -418.8587)
		(end 7.01675 -418.8587)
		(width 0.508)
		(layer "F.Cu")
		(net "GND")
	)
	(segment
		(start 23.622 -235.077)
		(end 24.384 -235.839)
		(width 0.508)
		(layer "F.Cu")
		(net "GND")
	)
	(segment
		(start 13.7922 -232.0036)
		(end 12.939268 -231.150668)
		(width 0.508)
		(layer "F.Cu")
		(net "GND")
	)
	(segment
		(start 6.999986 -159.999934)
		(end 6.999986 -164.356542)
		(width 0.635)
		(layer "F.Cu")
		(net "GND")
	)
	(segment
		(start 19.558 -185.6359)
		(end 18.9611 -185.6359)
		(width 0.508)
		(layer "F.Cu")
		(net "GND")
	)
	(segment
		(start 42.037 -175.818546)
		(end 41.786556 -176.06899)
		(width 0.508)
		(layer "F.Cu")
		(net "GND")
	)
	(segment
		(start 2.643378 -459.999842)
		(end 6.999986 -459.999842)
		(width 0.635)
		(layer "F.Cu")
		(net "GND")
	)
	(segment
		(start 13.7922 -232.537)
		(end 13.7922 -232.0036)
		(width 0.508)
		(layer "F.Cu")
		(net "GND")
	)
	(segment
		(start 12.4079 -232.7656)
		(end 13.5636 -232.7656)
		(width 0.508)
		(layer "F.Cu")
		(net "GND")
	)
	(segment
		(start 32.843724 -174.76851)
		(end 32.843724 -175.65751)
		(width 0.508)
		(layer "F.Cu")
		(net "GND")
	)
	(segment
		(start 24.384 -235.839)
		(end 24.384 -236.474)
		(width 0.508)
		(layer "F.Cu")
		(net "GND")
	)
	(segment
		(start 32.869124 -176.887124)
		(end 32.9692 -176.9872)
		(width 0.508)
		(layer "F.Cu")
		(net "GND")
	)
	(segment
		(start 45.619924 -43.659806)
		(end 45.619924 -44.739814)
		(width 0.635)
		(layer "F.Cu")
		(net "GND")
	)
	(segment
		(start 4.499864 -335.643474)
		(end 4.499864 -340.000082)
		(width 0.635)
		(layer "F.Cu")
		(net "GND")
	)
	(segment
		(start 35.6616 -145.3896)
		(end 35.6616 -145.4404)
		(width 0.508)
		(layer "F.Cu")
		(net "GND")
	)
	(segment
		(start 29.50845 -214.961216)
		(end 29.50845 -214.17915)
		(width 0.254)
		(layer "F.Cu")
		(net "GND")
	)
	(segment
		(start 38.227 -151.384)
		(end 38.67531 -151.83231)
		(width 0.508)
		(layer "F.Cu")
		(net "GND")
	)
	(segment
		(start 4.040124 -311.740042)
		(end 5.107432 -311.740042)
		(width 0.635)
		(layer "F.Cu")
		(net "GND")
	)
	(segment
		(start 2.643378 -39.99992)
		(end 6.999986 -39.99992)
		(width 0.635)
		(layer "F.Cu")
		(net "GND")
	)
	(segment
		(start 44.003976 -365.117126)
		(end 44.03725 -365.083852)
		(width 0.508)
		(layer "F.Cu")
		(net "GND")
	)
	(segment
		(start 20.69211 -143.23949)
		(end 20.2438 -143.6878)
		(width 0.3048)
		(layer "F.Cu")
		(net "GND")
	)
	(segment
		(start 43.47845 -180.366416)
		(end 44.448984 -180.366416)
		(width 0.3048)
		(layer "F.Cu")
		(net "GND")
	)
	(segment
		(start 6.5786 -437.2991)
		(end 7.366 -437.2991)
		(width 0.508)
		(layer "F.Cu")
		(net "GND")
	)
	(segment
		(start 4.963668 -435.576472)
		(end 4.963668 -434.471572)
		(width 0.508)
		(layer "F.Cu")
		(net "GND")
	)
	(segment
		(start 26.289 -149.352)
		(end 26.1874 -149.2504)
		(width 0.508)
		(layer "F.Cu")
		(net "GND")
	)
	(segment
		(start 30.4292 -195.3514)
		(end 30.734 -195.0466)
		(width 0.508)
		(layer "F.Cu")
		(net "GND")
	)
	(segment
		(start 25.9461 -140.5382)
		(end 26.9748 -140.5382)
		(width 0.508)
		(layer "F.Cu")
		(net "GND")
	)
	(segment
		(start 23.9268 -373.2022)
		(end 24.257 -372.872)
		(width 0.508)
		(layer "F.Cu")
		(net "GND")
	)
	(segment
		(start 37.999924 -40.039798)
		(end 37.999924 -41.119806)
		(width 0.635)
		(layer "F.Cu")
		(net "GND")
	)
	(segment
		(start 27.0256 -356.17404)
		(end 25.61844 -356.17404)
		(width 0.4064)
		(layer "F.Cu")
		(net "GND")
	)
	(segment
		(start 36.919916 -41.119806)
		(end 37.999924 -41.119806)
		(width 0.635)
		(layer "F.Cu")
		(net "GND")
	)
	(segment
		(start 41.143428 -19.99996)
		(end 45.500036 -19.99996)
		(width 0.635)
		(layer "F.Cu")
		(net "GND")
	)
	(segment
		(start 40.539924 -43.659806)
		(end 40.539924 -44.739814)
		(width 0.635)
		(layer "F.Cu")
		(net "GND")
	)
	(segment
		(start 13.8557 -145.6563)
		(end 13.8684 -145.6436)
		(width 0.508)
		(layer "F.Cu")
		(net "GND")
	)
	(segment
		(start 27.94 -360.172)
		(end 27.8511 -360.2609)
		(width 0.508)
		(layer "F.Cu")
		(net "GND")
	)
	(segment
		(start 39.459916 -41.119806)
		(end 40.539924 -41.119806)
		(width 0.635)
		(layer "F.Cu")
		(net "GND")
	)
	(segment
		(start 22.1488 -363.7026)
		(end 22.2504 -363.601)
		(width 0.508)
		(layer "F.Cu")
		(net "GND")
	)
	(segment
		(start 32.78251 -170.915076)
		(end 33.653476 -170.915076)
		(width 0.508)
		(layer "F.Cu")
		(net "GND")
	)
	(segment
		(start 7.9121 -148.5519)
		(end 7.493 -148.971)
		(width 0.508)
		(layer "F.Cu")
		(net "GND")
	)
	(segment
		(start 33.653476 -170.915076)
		(end 34.0614 -171.323)
		(width 0.508)
		(layer "F.Cu")
		(net "GND")
	)
	(segment
		(start 8.219186 -429.224186)
		(end 8.219186 -426.847)
		(width 0.508)
		(layer "F.Cu")
		(net "GND")
	)
	(segment
		(start 38.149022 -370.713)
		(end 38.020244 -370.841778)
		(width 0.508)
		(layer "F.Cu")
		(net "GND")
	)
	(segment
		(start 17.5514 -176.911)
		(end 17.5514 -177.293524)
		(width 0.508)
		(layer "F.Cu")
		(net "GND")
	)
	(segment
		(start 21.1963 -290.322)
		(end 20.359624 -290.322)
		(width 0.508)
		(layer "F.Cu")
		(net "GND")
	)
	(segment
		(start 18.415 -186.817)
		(end 19.0373 -187.4393)
		(width 0.508)
		(layer "F.Cu")
		(net "GND")
	)
	(segment
		(start 24.257 -372.872)
		(end 24.257 -371.9195)
		(width 0.508)
		(layer "F.Cu")
		(net "GND")
	)
	(segment
		(start 4.7117 -416.6108)
		(end 1.905 -416.6108)
		(width 0.508)
		(layer "F.Cu")
		(net "GND")
	)
	(segment
		(start 37.999924 -41.119806)
		(end 37.999924 -42.199814)
		(width 0.635)
		(layer "F.Cu")
		(net "GND")
	)
	(segment
		(start 31.75 -355.219)
		(end 31.877 -355.092)
		(width 0.508)
		(layer "F.Cu")
		(net "GND")
	)
	(segment
		(start 38.67531 -151.83231)
		(end 38.67531 -152.748234)
		(width 0.508)
		(layer "F.Cu")
		(net "GND")
	)
	(segment
		(start 37.999924 -41.119806)
		(end 39.079932 -41.119806)
		(width 0.635)
		(layer "F.Cu")
		(net "GND")
	)
	(segment
		(start 39.243 -371.475)
		(end 38.481 -370.713)
		(width 0.508)
		(layer "F.Cu")
		(net "GND")
	)
	(segment
		(start 8.5217 -275.2344)
		(end 8.5217 -274.3454)
		(width 0.508)
		(layer "F.Cu")
		(net "GND")
	)
	(segment
		(start 13.5636 -232.7656)
		(end 13.7922 -232.537)
		(width 0.508)
		(layer "F.Cu")
		(net "GND")
	)
	(segment
		(start 45.847 -159.639)
		(end 45.847 -159.453834)
		(width 0.508)
		(layer "F.Cu")
		(net "GND")
	)
	(segment
		(start 24.4602 -141.605)
		(end 24.3586 -141.605)
		(width 0.508)
		(layer "F.Cu")
		(net "GND")
	)
	(segment
		(start 37.211 -361.242102)
		(end 37.196776 -361.256326)
		(width 0.508)
		(layer "F.Cu")
		(net "GND")
	)
	(segment
		(start 26.7081 -121.3231)
		(end 26.3906 -121.0056)
		(width 0.508)
		(layer "F.Cu")
		(net "GND")
	)
	(segment
		(start 37.999924 -47.659798)
		(end 37.999924 -48.739806)
		(width 0.635)
		(layer "F.Cu")
		(net "GND")
	)
	(segment
		(start 22.1996 -146.7231)
		(end 22.1996 -147.57527)
		(width 0.508)
		(layer "F.Cu")
		(net "GND")
	)
	(segment
		(start 40.539924 -46.199806)
		(end 40.539924 -47.279814)
		(width 0.635)
		(layer "F.Cu")
		(net "GND")
	)
	(segment
		(start 17.91589 -176.302924)
		(end 17.91589 -176.54651)
		(width 0.508)
		(layer "F.Cu")
		(net "GND")
	)
	(segment
		(start 6.999986 -39.99992)
		(end 6.999986 -44.356528)
		(width 0.635)
		(layer "F.Cu")
		(net "GND")
	)
	(segment
		(start 16.2052 -250.5964)
		(end 15.9004 -250.5964)
		(width 0.508)
		(layer "F.Cu")
		(net "GND")
	)
	(segment
		(start 22.352 -247.9802)
		(end 21.209 -247.9802)
		(width 0.508)
		(layer "F.Cu")
		(net "GND")
	)
	(segment
		(start 6.999986 -39.99992)
		(end 11.356594 -39.99992)
		(width 0.635)
		(layer "F.Cu")
		(net "GND")
	)
	(segment
		(start 37.999924 -43.659806)
		(end 39.079932 -43.659806)
		(width 0.635)
		(layer "F.Cu")
		(net "GND")
	)
	(segment
		(start 40.6146 -140.5382)
		(end 40.005 -140.5382)
		(width 0.508)
		(layer "F.Cu")
		(net "GND")
	)
	(segment
		(start 41.85031 -160.088326)
		(end 41.3385 -159.576516)
		(width 0.508)
		(layer "F.Cu")
		(net "GND")
	)
	(segment
		(start 35.6616 -146.3802)
		(end 35.7378 -146.4564)
		(width 0.508)
		(layer "F.Cu")
		(net "GND")
	)
	(segment
		(start 29.791914 -180.467)
		(end 29.791914 -179.524914)
		(width 0.508)
		(layer "F.Cu")
		(net "GND")
	)
	(segment
		(start 15.3289 -39.4462)
		(end 15.3289 -38.5953)
		(width 0.508)
		(layer "F.Cu")
		(net "GND")
	)
	(segment
		(start 42.019982 -175.862488)
		(end 42.037 -175.862488)
		(width 0.508)
		(layer "F.Cu")
		(net "GND")
	)
	(segment
		(start 4.040124 -487.780076)
		(end 5.107432 -487.780076)
		(width 0.635)
		(layer "F.Cu")
		(net "GND")
	)
	(segment
		(start 16.764 -291.973)
		(end 16.052292 -291.261292)
		(width 0.508)
		(layer "F.Cu")
		(net "GND")
	)
	(segment
		(start 37.592 -353.695)
		(end 37.592 -354.064316)
		(width 0.508)
		(layer "F.Cu")
		(net "GND")
	)
	(segment
		(start 33.5788 -361.8992)
		(end 33.5788 -361.944412)
		(width 0.508)
		(layer "F.Cu")
		(net "GND")
	)
	(segment
		(start 41.8084 -156.2989)
		(end 41.8973 -156.3878)
		(width 0.508)
		(layer "F.Cu")
		(net "GND")
	)
	(segment
		(start 4.499864 -340.000082)
		(end 4.499864 -344.35669)
		(width 0.635)
		(layer "F.Cu")
		(net "GND")
	)
	(segment
		(start 45.499782 -140.643356)
		(end 45.499782 -144.999964)
		(width 0.635)
		(layer "F.Cu")
		(net "GND")
	)
	(segment
		(start 15.3289 -45.5422)
		(end 16.129 -45.5422)
		(width 0.508)
		(layer "F.Cu")
		(net "GND")
	)
	(segment
		(start 45.619924 -40.039798)
		(end 45.619924 -41.119806)
		(width 0.635)
		(layer "F.Cu")
		(net "GND")
	)
	(segment
		(start 41.999916 -43.659806)
		(end 43.079924 -43.659806)
		(width 0.635)
		(layer "F.Cu")
		(net "GND")
	)
	(segment
		(start 22.2504 -363.601)
		(end 23.1775 -363.601)
		(width 0.508)
		(layer "F.Cu")
		(net "GND")
	)
	(segment
		(start 31.672784 -355.141784)
		(end 31.75 -355.219)
		(width 0.508)
		(layer "F.Cu")
		(net "GND")
	)
	(segment
		(start 45.83811 -160.368234)
		(end 45.83811 -159.64789)
		(width 0.508)
		(layer "F.Cu")
		(net "GND")
	)
	(segment
		(start 4.040124 -377.73991)
		(end 5.107432 -377.73991)
		(width 0.635)
		(layer "F.Cu")
		(net "GND")
	)
	(segment
		(start 28.9052 -354.7872)
		(end 28.194 -354.076)
		(width 0.4064)
		(layer "F.Cu")
		(net "GND")
	)
	(segment
		(start 4.040124 -377.73991)
		(end 4.040124 -378.807218)
		(width 0.635)
		(layer "F.Cu")
		(net "GND")
	)
	(segment
		(start 22.733 -373.2022)
		(end 23.9268 -373.2022)
		(width 0.508)
		(layer "F.Cu")
		(net "GND")
	)
	(segment
		(start 40.999918 -463.049874)
		(end 46.118526 -463.049874)
		(width 0.635)
		(layer "F.Cu")
		(net "GND")
	)
	(segment
		(start 15.4813 -145.542)
		(end 13.97 -145.542)
		(width 0.508)
		(layer "F.Cu")
		(net "GND")
	)
	(segment
		(start 43.079924 -47.659798)
		(end 43.079924 -48.739806)
		(width 0.635)
		(layer "F.Cu")
		(net "GND")
	)
	(segment
		(start 31.7246 -148.629116)
		(end 31.7246 -147.828)
		(width 0.508)
		(layer "F.Cu")
		(net "GND")
	)
	(segment
		(start 20.32 -373.888)
		(end 20.3708 -373.9388)
		(width 0.508)
		(layer "F.Cu")
		(net "GND")
	)
	(segment
		(start 40.539924 -40.039798)
		(end 40.539924 -41.119806)
		(width 0.635)
		(layer "F.Cu")
		(net "GND")
	)
	(segment
		(start 40.539924 -46.199806)
		(end 41.619932 -46.199806)
		(width 0.635)
		(layer "F.Cu")
		(net "GND")
	)
	(segment
		(start 42.037 -175.862488)
		(end 42.037 -175.818546)
		(width 0.508)
		(layer "F.Cu")
		(net "GND")
	)
	(segment
		(start 45.619924 -45.119798)
		(end 45.619924 -46.199806)
		(width 0.635)
		(layer "F.Cu")
		(net "GND")
	)
	(segment
		(start 41.143428 -480.000056)
		(end 45.500036 -480.000056)
		(width 0.635)
		(layer "F.Cu")
		(net "GND")
	)
	(segment
		(start 43.079924 -46.199806)
		(end 43.079924 -47.279814)
		(width 0.635)
		(layer "F.Cu")
		(net "GND")
	)
	(segment
		(start 22.71649 -163.227766)
		(end 21.700744 -163.227766)
		(width 0.508)
		(layer "F.Cu")
		(net "GND")
	)
	(segment
		(start 19.937476 -176.43729)
		(end 19.937476 -177.25009)
		(width 0.508)
		(layer "F.Cu")
		(net "GND")
	)
	(segment
		(start 45.500036 -19.99996)
		(end 45.500036 -24.356568)
		(width 0.635)
		(layer "F.Cu")
		(net "GND")
	)
	(segment
		(start 45.619924 -46.199806)
		(end 45.619924 -47.279814)
		(width 0.635)
		(layer "F.Cu")
		(net "GND")
	)
	(segment
		(start 35.88131 -443.95009)
		(end 40.999918 -443.95009)
		(width 0.635)
		(layer "F.Cu")
		(net "GND")
	)
	(segment
		(start 40.539924 -45.119798)
		(end 40.539924 -46.199806)
		(width 0.635)
		(layer "F.Cu")
		(net "GND")
	)
	(segment
		(start 6.999986 -459.999842)
		(end 11.356594 -459.999842)
		(width 0.635)
		(layer "F.Cu")
		(net "GND")
	)
	(segment
		(start 37.211 -354.8634)
		(end 37.211 -354.826316)
		(width 0.508)
		(layer "F.Cu")
		(net "GND")
	)
	(segment
		(start 44.448984 -180.366416)
		(end 44.4754 -180.34)
		(width 0.3048)
		(layer "F.Cu")
		(net "GND")
	)
	(segment
		(start 40.999918 -443.95009)
		(end 46.118526 -443.95009)
		(width 0.635)
		(layer "F.Cu")
		(net "GND")
	)
	(segment
		(start 20.359624 -290.322)
		(end 20.077176 -290.604448)
		(width 0.508)
		(layer "F.Cu")
		(net "GND")
	)
	(segment
		(start 29.1592 -254.3429)
		(end 29.1592 -255.27)
		(width 0.508)
		(layer "F.Cu")
		(net "GND")
	)
	(segment
		(start 35.6616 -145.4404)
		(end 35.6616 -146.3802)
		(width 0.508)
		(layer "F.Cu")
		(net "GND")
	)
	(segment
		(start 40.5892 -165.5826)
		(end 40.5892 -164.043106)
		(width 0.508)
		(layer "F.Cu")
		(net "GND")
	)
	(segment
		(start 36.5633 -370.4336)
		(end 37.5666 -370.4336)
		(width 0.508)
		(layer "F.Cu")
		(net "GND")
	)
	(segment
		(start 36.576 -121.031)
		(end 36.068 -121.539)
		(width 0.508)
		(layer "F.Cu")
		(net "GND")
	)
	(segment
		(start 37.974778 -370.841778)
		(end 38.020244 -370.841778)
		(width 0.508)
		(layer "F.Cu")
		(net "GND")
	)
	(segment
		(start 39.56685 -355.969316)
		(end 39.56685 -354.89515)
		(width 0.508)
		(layer "F.Cu")
		(net "GND")
	)
	(segment
		(start 39.459916 -46.199806)
		(end 40.539924 -46.199806)
		(width 0.635)
		(layer "F.Cu")
		(net "GND")
	)
	(segment
		(start 15.494 -64.57315)
		(end 15.494 -64.516)
		(width 0.508)
		(layer "F.Cu")
		(net "GND")
	)
	(segment
		(start 23.1775 -367.411)
		(end 22.2758 -367.411)
		(width 0.508)
		(layer "F.Cu")
		(net "GND")
	)
	(segment
		(start 39.459916 -48.739806)
		(end 40.539924 -48.739806)
		(width 0.635)
		(layer "F.Cu")
		(net "GND")
	)
	(segment
		(start 32.1564 -370.107972)
		(end 32.1564 -371.221)
		(width 0.4064)
		(layer "F.Cu")
		(net "GND")
	)
	(segment
		(start 32.869124 -175.80991)
		(end 32.869124 -176.887124)
		(width 0.508)
		(layer "F.Cu")
		(net "GND")
	)
	(segment
		(start 42.0624 -160.088326)
		(end 41.85031 -160.088326)
		(width 0.508)
		(layer "F.Cu")
		(net "GND")
	)
	(segment
		(start 29.50845 -214.17915)
		(end 30.1498 -213.5378)
		(width 0.254)
		(layer "F.Cu")
		(net "GND")
	)
	(segment
		(start 41.786556 -176.06899)
		(end 41.786556 -176.069244)
		(width 0.508)
		(layer "F.Cu")
		(net "GND")
	)
	(segment
		(start 25.654 -374.523)
		(end 25.654 -374.142)
		(width 0.508)
		(layer "F.Cu")
		(net "GND")
	)
	(segment
		(start 45.619924 -41.119806)
		(end 46.699932 -41.119806)
		(width 0.635)
		(layer "F.Cu")
		(net "GND")
	)
	(segment
		(start 19.9644 -145.9357)
		(end 19.9644 -146.7866)
		(width 0.508)
		(layer "F.Cu")
		(net "GND")
	)
	(segment
		(start 26.289 -150.8633)
		(end 26.289 -149.352)
		(width 0.508)
		(layer "F.Cu")
		(net "GND")
	)
	(segment
		(start 41.999916 -41.119806)
		(end 43.079924 -41.119806)
		(width 0.635)
		(layer "F.Cu")
		(net "GND")
	)
	(segment
		(start 43.079924 -48.739806)
		(end 44.159932 -48.739806)
		(width 0.635)
		(layer "F.Cu")
		(net "GND")
	)
	(segment
		(start 45.499782 -144.999964)
		(end 45.499782 -149.356572)
		(width 0.635)
		(layer "F.Cu")
		(net "GND")
	)
	(segment
		(start 15.748 -41.4782)
		(end 16.51 -42.2402)
		(width 0.508)
		(layer "F.Cu")
		(net "GND")
	)
	(segment
		(start 18.161 -186.817)
		(end 18.415 -186.817)
		(width 0.508)
		(layer "F.Cu")
		(net "GND")
	)
	(segment
		(start 45.500036 -19.99996)
		(end 49.856644 -19.99996)
		(width 0.635)
		(layer "F.Cu")
		(net "GND")
	)
	(segment
		(start 28.582366 -241.882676)
		(end 28.582366 -241.815366)
		(width 0.508)
		(layer "F.Cu")
		(net "GND")
	)
	(segment
		(start 16.256 -166.5478)
		(end 16.8148 -165.989)
		(width 0.508)
		(layer "F.Cu")
		(net "GND")
	)
	(segment
		(start 4.040124 -311.740042)
		(end 4.040124 -312.80735)
		(width 0.635)
		(layer "F.Cu")
		(net "GND")
	)
	(segment
		(start 43.079924 -43.659806)
		(end 43.079924 -44.739814)
		(width 0.635)
		(layer "F.Cu")
		(net "GND")
	)
	(segment
		(start 31.877 -355.092)
		(end 33.565084 -355.092)
		(width 0.508)
		(layer "F.Cu")
		(net "GND")
	)
	(segment
		(start 6.999986 -459.999842)
		(end 6.999986 -464.35645)
		(width 0.635)
		(layer "F.Cu")
		(net "GND")
	)
	(segment
		(start 30.6832 -147.7518)
		(end 30.734 -147.701)
		(width 0.508)
		(layer "F.Cu")
		(net "GND")
	)
	(segment
		(start 6.999986 -155.643326)
		(end 6.999986 -159.999934)
		(width 0.635)
		(layer "F.Cu")
		(net "GND")
	)
	(segment
		(start 6.7945 -454.1012)
		(end 6.7945 -454.9394)
		(width 0.508)
		(layer "F.Cu")
		(net "GND")
	)
	(segment
		(start 29.464 -195.3514)
		(end 30.4292 -195.3514)
		(width 0.508)
		(layer "F.Cu")
		(net "GND")
	)
	(segment
		(start 26.797 -269.494)
		(end 26.797 -268.8336)
		(width 0.508)
		(layer "F.Cu")
		(net "GND")
	)
	(segment
		(start 20.69211 -142.5067)
		(end 20.69211 -143.23949)
		(width 0.3048)
		(layer "F.Cu")
		(net "GND")
	)
	(segment
		(start 6.999986 -35.643312)
		(end 6.999986 -39.99992)
		(width 0.635)
		(layer "F.Cu")
		(net "GND")
	)
	(segment
		(start 44.539916 -43.659806)
		(end 45.619924 -43.659806)
		(width 0.635)
		(layer "F.Cu")
		(net "GND")
	)
	(segment
		(start 36.3093 -147.8915)
		(end 36.9062 -147.8915)
		(width 0.508)
		(layer "F.Cu")
		(net "GND")
	)
	(segment
		(start 19.0373 -187.4393)
		(end 19.1008 -187.4393)
		(width 0.508)
		(layer "F.Cu")
		(net "GND")
	)
	(segment
		(start 44.539916 -41.119806)
		(end 45.619924 -41.119806)
		(width 0.635)
		(layer "F.Cu")
		(net "GND")
	)
	(segment
		(start 36.0934 -147.6756)
		(end 36.3093 -147.8915)
		(width 0.508)
		(layer "F.Cu")
		(net "GND")
	)
	(segment
		(start 22.24913 -147.6248)
		(end 22.24913 -147.6502)
		(width 0.508)
		(layer "F.Cu")
		(net "GND")
	)
	(segment
		(start 7.366 -437.2991)
		(end 7.3914 -437.2737)
		(width 0.508)
		(layer "F.Cu")
		(net "GND")
	)
	(segment
		(start 21.700744 -163.227766)
		(end 21.3868 -163.54171)
		(width 0.508)
		(layer "F.Cu")
		(net "GND")
	)
	(segment
		(start 45.500036 -475.643448)
		(end 45.500036 -480.000056)
		(width 0.635)
		(layer "F.Cu")
		(net "GND")
	)
	(segment
		(start 24.2824 -362.2548)
		(end 24.2824 -361.6325)
		(width 0.508)
		(layer "F.Cu")
		(net "GND")
	)
	(segment
		(start 40.539924 -47.659798)
		(end 40.539924 -48.739806)
		(width 0.635)
		(layer "F.Cu")
		(net "GND")
	)
	(segment
		(start 40.539924 -48.739806)
		(end 40.539924 -49.819814)
		(width 0.635)
		(layer "F.Cu")
		(net "GND")
	)
	(segment
		(start 4.040124 -198.419974)
		(end 5.107432 -198.419974)
		(width 0.635)
		(layer "F.Cu")
		(net "GND")
	)
	(segment
		(start 44.03725 -365.083852)
		(end 44.03725 -363.855)
		(width 0.508)
		(layer "F.Cu")
		(net "GND")
	)
	(segment
		(start 41.3385 -159.576516)
		(end 41.3385 -159.2072)
		(width 0.508)
		(layer "F.Cu")
		(net "GND")
	)
	(segment
		(start 37.999924 -46.199806)
		(end 39.079932 -46.199806)
		(width 0.635)
		(layer "F.Cu")
		(net "GND")
	)
	(segment
		(start 41.8084 -155.4607)
		(end 41.8084 -156.2989)
		(width 0.508)
		(layer "F.Cu")
		(net "GND")
	)
	(segment
		(start 37.592 -354.064316)
		(end 37.580316 -354.076)
		(width 0.508)
		(layer "F.Cu")
		(net "GND")
	)
	(segment
		(start 26.9748 -140.5382)
		(end 27.0002 -140.5128)
		(width 0.508)
		(layer "F.Cu")
		(net "GND")
	)
	(segment
		(start 39.2684 -282.194)
		(end 39.231062 -282.231338)
		(width 0.508)
		(layer "F.Cu")
		(net "GND")
	)
	(segment
		(start 26.416 -266.573)
		(end 26.797 -266.954)
		(width 0.508)
		(layer "F.Cu")
		(net "GND")
	)
	(segment
		(start 4.499864 -340.000082)
		(end 8.856472 -340.000082)
		(width 0.635)
		(layer "F.Cu")
		(net "GND")
	)
	(segment
		(start 44.539916 -46.199806)
		(end 45.619924 -46.199806)
		(width 0.635)
		(layer "F.Cu")
		(net "GND")
	)
	(segment
		(start 18.8214 -146.4056)
		(end 18.288 -146.4056)
		(width 0.508)
		(layer "F.Cu")
		(net "GND")
	)
	(segment
		(start 31.672784 -353.6442)
		(end 31.672784 -355.141784)
		(width 0.508)
		(layer "F.Cu")
		(net "GND")
	)
	(segment
		(start 24.3586 -141.605)
		(end 23.4188 -140.6652)
		(width 0.508)
		(layer "F.Cu")
		(net "GND")
	)
	(segment
		(start 27.4574 -121.3231)
		(end 26.7081 -121.3231)
		(width 0.508)
		(layer "F.Cu")
		(net "GND")
	)
	(segment
		(start 33.5788 -361.944412)
		(end 32.9565 -362.566712)
		(width 0.508)
		(layer "F.Cu")
		(net "GND")
	)
	(segment
		(start 39.459916 -43.659806)
		(end 40.539924 -43.659806)
		(width 0.635)
		(layer "F.Cu")
		(net "GND")
	)
	(segment
		(start 15.3162 -250.0122)
		(end 14.605 -250.0122)
		(width 0.508)
		(layer "F.Cu")
		(net "GND")
	)
	(segment
		(start 36.919916 -46.199806)
		(end 37.999924 -46.199806)
		(width 0.635)
		(layer "F.Cu")
		(net "GND")
	)
	(segment
		(start 41.786556 -176.069244)
		(end 41.4782 -176.3776)
		(width 0.508)
		(layer "F.Cu")
		(net "GND")
	)
	(segment
		(start 29.7688 -194.0814)
		(end 30.734 -195.0466)
		(width 0.508)
		(layer "F.Cu")
		(net "GND")
	)
	(segment
		(start 34.1884 -169.0624)
		(end 33.91789 -168.79189)
		(width 0.508)
		(layer "F.Cu")
		(net "GND")
	)
	(segment
		(start 32.843724 -173.65091)
		(end 32.843724 -174.76851)
		(width 0.508)
		(layer "F.Cu")
		(net "GND")
	)
	(segment
		(start 8.094472 -278.627332)
		(end 6.92404 -278.627332)
		(width 0.508)
		(layer "F.Cu")
		(net "GND")
	)
	(segment
		(start 2.972816 -487.780076)
		(end 4.040124 -487.780076)
		(width 0.635)
		(layer "F.Cu")
		(net "GND")
	)
	(segment
		(start 33.91789 -168.79189)
		(end 33.91789 -168.168066)
		(width 0.508)
		(layer "F.Cu")
		(net "GND")
	)
	(segment
		(start 40.005 -140.5382)
		(end 39.7002 -140.2334)
		(width 0.508)
		(layer "F.Cu")
		(net "GND")
	)
	(segment
		(start 19.558508 -288.149538)
		(end 19.417538 -288.149538)
		(width 0.508)
		(layer "F.Cu")
		(net "GND")
	)
	(segment
		(start 37.999924 -43.659806)
		(end 37.999924 -44.739814)
		(width 0.635)
		(layer "F.Cu")
		(net "GND")
	)
	(segment
		(start 4.040124 -487.780076)
		(end 4.040124 -488.847384)
		(width 0.635)
		(layer "F.Cu")
		(net "GND")
	)
	(segment
		(start 37.338 -185.928)
		(end 37.338 -187.198)
		(width 0.508)
		(layer "F.Cu")
		(net "GND")
	)
	(segment
		(start 12.5984 -145.6563)
		(end 13.8557 -145.6563)
		(width 0.508)
		(layer "F.Cu")
		(net "GND")
	)
	(segment
		(start 41.999916 -48.739806)
		(end 43.079924 -48.739806)
		(width 0.635)
		(layer "F.Cu")
		(net "GND")
	)
	(segment
		(start 7.9756 -418.6428)
		(end 7.7597 -418.8587)
		(width 0.508)
		(layer "F.Cu")
		(net "GND")
	)
	(segment
		(start 40.6019 -139.5222)
		(end 40.6019 -140.5255)
		(width 0.508)
		(layer "F.Cu")
		(net "GND")
	)
	(segment
		(start 30.329124 -170.915076)
		(end 30.226 -171.0182)
		(width 0.508)
		(layer "F.Cu")
		(net "GND")
	)
	(segment
		(start 35.88131 -463.049874)
		(end 40.999918 -463.049874)
		(width 0.635)
		(layer "F.Cu")
		(net "GND")
	)
	(segment
		(start 37.999924 -45.119798)
		(end 37.999924 -46.199806)
		(width 0.635)
		(layer "F.Cu")
		(net "GND")
	)
	(segment
		(start 43.079924 -46.199806)
		(end 44.159932 -46.199806)
		(width 0.635)
		(layer "F.Cu")
		(net "GND")
	)
	(segment
		(start 41.3385 -159.2072)
		(end 41.3131 -159.1818)
		(width 0.508)
		(layer "F.Cu")
		(net "GND")
	)
	(segment
		(start 33.909 -373.634)
		(end 33.909 -372.6434)
		(width 0.508)
		(layer "F.Cu")
		(net "GND")
	)
	(segment
		(start 37.211 -354.826316)
		(end 37.580316 -354.457)
		(width 0.508)
		(layer "F.Cu")
		(net "GND")
	)
	(segment
		(start 40.999918 -438.831482)
		(end 40.999918 -443.95009)
		(width 0.635)
		(layer "F.Cu")
		(net "GND")
	)
	(segment
		(start 32.73425 -356.096316)
		(end 31.914084 -356.096316)
		(width 0.508)
		(layer "F.Cu")
		(net "GND")
	)
	(segment
		(start 45.500036 -15.643352)
		(end 45.500036 -19.99996)
		(width 0.635)
		(layer "F.Cu")
		(net "GND")
	)
	(segment
		(start 16.256 -168.2242)
		(end 16.256 -169.3164)
		(width 0.508)
		(layer "F.Cu")
		(net "GND")
	)
	(segment
		(start 38.862 -352.425)
		(end 37.592 -353.695)
		(width 0.508)
		(layer "F.Cu")
		(net "GND")
	)
	(segment
		(start 31.36011 -170.915076)
		(end 30.329124 -170.915076)
		(width 0.508)
		(layer "F.Cu")
		(net "GND")
	)
	(segment
		(start 45.619924 -46.199806)
		(end 46.699932 -46.199806)
		(width 0.635)
		(layer "F.Cu")
		(net "GND")
	)
	(segment
		(start 32.843724 -175.65751)
		(end 32.869124 -175.68291)
		(width 0.508)
		(layer "F.Cu")
		(net "GND")
	)
	(segment
		(start 8.29945 -77.5589)
		(end 8.29945 -76.073)
		(width 0.508)
		(layer "F.Cu")
		(net "GND")
	)
	(segment
		(start 43.079924 -45.119798)
		(end 43.079924 -46.199806)
		(width 0.635)
		(layer "F.Cu")
		(net "GND")
	)
	(segment
		(start 44.539916 -48.739806)
		(end 45.619924 -48.739806)
		(width 0.635)
		(layer "F.Cu")
		(net "GND")
	)
	(segment
		(start 37.5666 -370.4336)
		(end 37.974778 -370.841778)
		(width 0.508)
		(layer "F.Cu")
		(net "GND")
	)
	(segment
		(start 27.8511 -360.2609)
		(end 27.8511 -361.0864)
		(width 0.508)
		(layer "F.Cu")
		(net "GND")
	)
	(segment
		(start 18.7706 -141.9479)
		(end 17.8689 -141.9479)
		(width 0.508)
		(layer "F.Cu")
		(net "GND")
	)
	(segment
		(start 45.619924 -43.659806)
		(end 46.699932 -43.659806)
		(width 0.635)
		(layer "F.Cu")
		(net "GND")
	)
	(segment
		(start 43.82389 -156.87929)
		(end 43.2054 -156.2608)
		(width 0.508)
		(layer "F.Cu")
		(net "GND")
	)
	(segment
		(start 37.999924 -48.739806)
		(end 39.079932 -48.739806)
		(width 0.635)
		(layer "F.Cu")
		(net "GND")
	)
	(segment
		(start 17.1831 -290.703)
		(end 17.1831 -291.5539)
		(width 0.508)
		(layer "F.Cu")
		(net "GND")
	)
	(segment
		(start 14.4526 -259.2324)
		(end 14.224 -259.461)
		(width 0.508)
		(layer "F.Cu")
		(net "GND")
	)
	(segment
		(start 43.079924 -41.119806)
		(end 44.159932 -41.119806)
		(width 0.635)
		(layer "F.Cu")
		(net "GND")
	)
	(segment
		(start 36.919916 -43.659806)
		(end 37.999924 -43.659806)
		(width 0.635)
		(layer "F.Cu")
		(net "GND")
	)
	(segment
		(start 45.619924 -42.579798)
		(end 45.619924 -43.659806)
		(width 0.635)
		(layer "F.Cu")
		(net "GND")
	)
	(segment
		(start 26.797 -266.954)
		(end 26.797 -267.6398)
		(width 0.508)
		(layer "F.Cu")
		(net "GND")
	)
	(segment
		(start 31.332424 -243.647976)
		(end 31.652972 -243.647976)
		(width 0.4572)
		(layer "F.Cu")
		(net "GND")
	)
	(segment
		(start 22.1996 -147.57527)
		(end 22.24913 -147.6248)
		(width 0.508)
		(layer "F.Cu")
		(net "GND")
	)
	(segment
		(start 40.999918 -463.049874)
		(end 40.999918 -468.168482)
		(width 0.635)
		(layer "F.Cu")
		(net "GND")
	)
	(segment
		(start 45.619924 -47.659798)
		(end 45.619924 -48.739806)
		(width 0.635)
		(layer "F.Cu")
		(net "GND")
	)
	(segment
		(start 23.1902 -145.6055)
		(end 23.1902 -146.558)
		(width 0.508)
		(layer "F.Cu")
		(net "GND")
	)
	(segment
		(start 14.6685 -56.134)
		(end 13.843 -56.134)
		(width 0.508)
		(layer "F.Cu")
		(net "GND")
	)
	(segment
		(start 16.256 -167.0304)
		(end 16.256 -166.5478)
		(width 0.508)
		(layer "F.Cu")
		(net "GND")
	)
	(segment
		(start 39.231062 -282.231338)
		(end 37.846508 -282.231338)
		(width 0.508)
		(layer "F.Cu")
		(net "GND")
	)
	(segment
		(start 36.919916 -48.739806)
		(end 37.999924 -48.739806)
		(width 0.635)
		(layer "F.Cu")
		(net "GND")
	)
	(segment
		(start 37.999924 -42.579798)
		(end 37.999924 -43.659806)
		(width 0.635)
		(layer "F.Cu")
		(net "GND")
	)
	(segment
		(start 40.539924 -41.119806)
		(end 41.619932 -41.119806)
		(width 0.635)
		(layer "F.Cu")
		(net "GND")
	)
	(segment
		(start 23.749 -375.7295)
		(end 23.749 -376.6058)
		(width 0.508)
		(layer "F.Cu")
		(net "GND")
	)
	(segment
		(start 45.619924 -48.739806)
		(end 45.619924 -49.819814)
		(width 0.635)
		(layer "F.Cu")
		(net "GND")
	)
	(segment
		(start 16.1798 -278.9428)
		(end 16.383 -279.146)
		(width 0.508)
		(layer "F.Cu")
		(net "GND")
	)
	(segment
		(start 2.972816 -377.73991)
		(end 4.040124 -377.73991)
		(width 0.635)
		(layer "F.Cu")
		(net "GND")
	)
	(segment
		(start 37.17671 -154.373834)
		(end 37.17671 -153.63571)
		(width 0.508)
		(layer "F.Cu")
		(net "GND")
	)
	(segment
		(start 2.972816 -311.740042)
		(end 4.040124 -311.740042)
		(width 0.635)
		(layer "F.Cu")
		(net "GND")
	)
	(segment
		(start 25.7302 -250.444)
		(end 25.7302 -251.6632)
		(width 0.508)
		(layer "F.Cu")
		(net "GND")
	)
	(segment
		(start 40.999918 -443.95009)
		(end 40.999918 -449.068698)
		(width 0.635)
		(layer "F.Cu")
		(net "GND")
	)
	(segment
		(start 20.3708 -373.9388)
		(end 20.3708 -375.285)
		(width 0.508)
		(layer "F.Cu")
		(net "GND")
	)
	(segment
		(start 30.6832 -148.629116)
		(end 30.6832 -147.7518)
		(width 0.508)
		(layer "F.Cu")
		(net "GND")
	)
	(segment
		(start 37.94125 -173.2915)
		(end 37.94125 -172.05325)
		(width 0.508)
		(layer "F.Cu")
		(net "GND")
	)
	(segment
		(start 40.539924 -41.119806)
		(end 40.539924 -42.199814)
		(width 0.635)
		(layer "F.Cu")
		(net "GND")
	)
	(segment
		(start 26.227024 -175.415194)
		(end 25.146254 -176.495964)
		(width 0.508)
		(layer "F.Cu")
		(net "GND")
	)
	(segment
		(start 38.989 -144.7927)
		(end 38.989 -145.887186)
		(width 0.508)
		(layer "F.Cu")
		(net "GND")
	)
	(segment
		(start 12.939268 -231.150668)
		(end 12.939268 -231.106472)
		(width 0.508)
		(layer "F.Cu")
		(net "GND")
	)
	(segment
		(start 32.869124 -175.68291)
		(end 32.869124 -175.80991)
		(width 0.508)
		(layer "F.Cu")
		(net "GND")
	)
	(segment
		(start 15.1257 -259.2324)
		(end 14.4526 -259.2324)
		(width 0.508)
		(layer "F.Cu")
		(net "GND")
	)
	(segment
		(start 9.4488 -65.2653)
		(end 9.4488 -65.833244)
		(width 0.508)
		(layer "F.Cu")
		(net "GND")
	)
	(segment
		(start 43.079924 -43.659806)
		(end 44.159932 -43.659806)
		(width 0.635)
		(layer "F.Cu")
		(net "GND")
	)
	(segment
		(start 39.116 -352.425)
		(end 38.862 -352.425)
		(width 0.508)
		(layer "F.Cu")
		(net "GND")
	)
	(segment
		(start 14.4399 -43.5102)
		(end 13.5128 -43.5102)
		(width 0.508)
		(layer "F.Cu")
		(net "GND")
	)
	(segment
		(start 38.227 -178.4985)
		(end 37.4015 -178.4985)
		(width 0.508)
		(layer "F.Cu")
		(net "GND")
	)
	(segment
		(start 37.17671 -153.63571)
		(end 36.957 -153.416)
		(width 0.508)
		(layer "F.Cu")
		(net "GND")
	)
	(segment
		(start 14.969744 -65.097406)
		(end 15.494 -64.57315)
		(width 0.508)
		(layer "F.Cu")
		(net "GND")
	)
	(segment
		(start 13.6652 -256.4257)
		(end 13.6652 -255.5748)
		(width 0.508)
		(layer "F.Cu")
		(net "GND")
	)
	(segment
		(start 41.999916 -46.199806)
		(end 43.079924 -46.199806)
		(width 0.635)
		(layer "F.Cu")
		(net "GND")
	)
	(segment
		(start 43.079924 -41.119806)
		(end 43.079924 -42.199814)
		(width 0.635)
		(layer "F.Cu")
		(net "GND")
	)
	(segment
		(start 30.89656 -244.08384)
		(end 31.332424 -243.647976)
		(width 0.4572)
		(layer "F.Cu")
		(net "GND")
	)
	(segment
		(start 19.9644 -146.7866)
		(end 20.182332 -147.004532)
		(width 0.508)
		(layer "F.Cu")
		(net "GND")
	)
	(segment
		(start 19.9136 -149.2377)
		(end 19.9136 -148.2598)
		(width 0.508)
		(layer "F.Cu")
		(net "GND")
	)
	(segment
		(start 42.0116 -362.3945)
		(end 42.926 -362.3945)
		(width 0.508)
		(layer "F.Cu")
		(net "GND")
	)
	(segment
		(start 33.565084 -355.092)
		(end 34.2138 -355.740716)
		(width 0.508)
		(layer "F.Cu")
		(net "GND")
	)
	(segment
		(start 2.643378 -159.999934)
		(end 6.999986 -159.999934)
		(width 0.635)
		(layer "F.Cu")
		(net "GND")
	)
	(segment
		(start 37.999924 -46.199806)
		(end 37.999924 -47.279814)
		(width 0.635)
		(layer "F.Cu")
		(net "GND")
	)
	(segment
		(start 25.18918 -376.08256)
		(end 25.18918 -377.39066)
		(width 0.508)
		(layer "F.Cu")
		(net "GND")
	)
	(segment
		(start 18.288 -146.4056)
		(end 17.7292 -145.8468)
		(width 0.508)
		(layer "F.Cu")
		(net "GND")
	)
	(segment
		(start 40.539924 -42.579798)
		(end 40.539924 -43.659806)
		(width 0.635)
		(layer "F.Cu")
		(net "GND")
	)
	(segment
		(start 43.079924 -42.579798)
		(end 43.079924 -43.659806)
		(width 0.635)
		(layer "F.Cu")
		(net "GND")
	)
	(segment
		(start 25.7302 -251.6632)
		(end 24.7142 -251.6632)
		(width 0.508)
		(layer "F.Cu")
		(net "GND")
	)
	(segment
		(start 29.852366 -241.882676)
		(end 29.852366 -241.006376)
		(width 0.508)
		(layer "F.Cu")
		(net "GND")
	)
	(segment
		(start 4.040124 -22.37994)
		(end 4.040124 -23.447248)
		(width 0.635)
		(layer "F.Cu")
		(net "GND")
	)
	(segment
		(start 32.9565 -362.566712)
		(end 32.9565 -362.7882)
		(width 0.508)
		(layer "F.Cu")
		(net "GND")
	)
	(segment
		(start 45.500036 -480.000056)
		(end 49.856644 -480.000056)
		(width 0.635)
		(layer "F.Cu")
		(net "GND")
	)
	(segment
		(start 45.83811 -159.64789)
		(end 45.847 -159.639)
		(width 0.508)
		(layer "F.Cu")
		(net "GND")
	)
	(segment
		(start 40.6019 -140.5255)
		(end 40.6146 -140.5382)
		(width 0.508)
		(layer "F.Cu")
		(net "GND")
	)
	(segment
		(start 32.9565 -363.728)
		(end 32.9565 -362.7882)
		(width 0.508)
		(layer "F.Cu")
		(net "GND")
	)
	(segment
		(start 37.94125 -172.05325)
		(end 37.846 -171.958)
		(width 0.508)
		(layer "F.Cu")
		(net "GND")
	)
	(segment
		(start 31.914084 -356.096316)
		(end 31.7754 -356.235)
		(width 0.508)
		(layer "F.Cu")
		(net "GND")
	)
	(segment
		(start 15.494 -64.516)
		(end 15.9258 -64.516)
		(width 0.508)
		(layer "F.Cu")
		(net "GND")
	)
	(segment
		(start 44.6532 -156.87929)
		(end 43.82389 -156.87929)
		(width 0.508)
		(layer "F.Cu")
		(net "GND")
	)
	(segment
		(start 43.079924 -48.739806)
		(end 43.079924 -49.819814)
		(width 0.635)
		(layer "F.Cu")
		(net "GND")
	)
	(segment
		(start 28.582366 -241.815366)
		(end 27.94 -241.173)
		(width 0.508)
		(layer "F.Cu")
		(net "GND")
	)
	(segment
		(start 14.7574 -262.7249)
		(end 14.1351 -262.7249)
		(width 0.508)
		(layer "F.Cu")
		(net "GND")
	)
	(segment
		(start 13.97 -145.542)
		(end 13.8684 -145.6436)
		(width 0.508)
		(layer "F.Cu")
		(net "GND")
	)
	(segment
		(start 5.009134 -66.688462)
		(end 5.009134 -67.869562)
		(width 0.508)
		(layer "F.Cu")
		(net "GND")
	)
	(segment
		(start 2.972816 -22.37994)
		(end 4.040124 -22.37994)
		(width 0.635)
		(layer "F.Cu")
		(net "GND")
	)
	(segment
		(start 18.9611 -185.6359)
		(end 18.669 -185.928)
		(width 0.508)
		(layer "F.Cu")
		(net "GND")
	)
	(segment
		(start 17.91589 -176.54651)
		(end 17.5514 -176.911)
		(width 0.508)
		(layer "F.Cu")
		(net "GND")
	)
	(segment
		(start 26.227024 -173.96841)
		(end 26.227024 -175.415194)
		(width 0.508)
		(layer "F.Cu")
		(net "GND")
	)
	(segment
		(start 41.143174 -144.999964)
		(end 45.499782 -144.999964)
		(width 0.635)
		(layer "F.Cu")
		(net "GND")
	)
	(segment
		(start 22.4028 -248.031)
		(end 22.352 -247.9802)
		(width 0.508)
		(layer "F.Cu")
		(net "GND")
	)
	(via
		(at 51.308 -188.087)
		(size 0.7112)
		(drill 0.4064)
		(layers "F.Cu" "B.Cu")
		(net "GND")
	)
	(via
		(at 3.2512 -473.3798)
		(size 0.7112)
		(drill 0.4064)
		(layers "F.Cu" "B.Cu")
		(net "GND")
	)
	(via
		(at 22.098 -150.114)
		(size 0.5588)
		(drill 0.3048)
		(layers "F.Cu" "B.Cu")
		(net "GND")
	)
	(via
		(at 48.9331 -416.941)
		(size 0.5588)
		(drill 0.3048)
		(layers "F.Cu" "B.Cu")
		(net "GND")
	)
	(via
		(at 30.3022 -309.7276)
		(size 0.7112)
		(drill 0.4064)
		(layers "F.Cu" "B.Cu")
		(net "GND")
	)
	(via
		(at 23.622 -235.077)
		(size 0.7112)
		(drill 0.4064)
		(layers "F.Cu" "B.Cu")
		(net "GND")
	)
	(via
		(at 25.654 -148.082)
		(size 0.5588)
		(drill 0.3048)
		(layers "F.Cu" "B.Cu")
		(net "GND")
	)
	(via
		(at 4.064 -257.556)
		(size 0.7112)
		(drill 0.4064)
		(layers "F.Cu" "B.Cu")
		(net "GND")
	)
	(via
		(at 46.609 -270.637)
		(size 0.7112)
		(drill 0.4064)
		(layers "F.Cu" "B.Cu")
		(net "GND")
	)
	(via
		(at 4.064 -217.424)
		(size 0.7112)
		(drill 0.4064)
		(layers "F.Cu" "B.Cu")
		(net "GND")
	)
	(via
		(at 23.241 -304.8)
		(size 0.7112)
		(drill 0.4064)
		(layers "F.Cu" "B.Cu")
		(net "GND")
	)
	(via
		(at 37.4904 -38.3286)
		(size 0.7112)
		(drill 0.4064)
		(layers "F.Cu" "B.Cu")
		(net "GND")
	)
	(via
		(at 3.43154 -151.88946)
		(size 0.7112)
		(drill 0.4064)
		(layers "F.Cu" "B.Cu")
		(net "GND")
	)
	(via
		(at 51.054 -277.622)
		(size 0.7112)
		(drill 0.4064)
		(layers "F.Cu" "B.Cu")
		(net "GND")
	)
	(via
		(at 14.1986 -477.901)
		(size 0.5588)
		(drill 0.3048)
		(layers "F.Cu" "B.Cu")
		(net "GND")
	)
	(via
		(at 33.02 -194.056)
		(size 0.5588)
		(drill 0.3048)
		(layers "F.Cu" "B.Cu")
		(net "GND")
	)
	(via
		(at 46.863 -430.911)
		(size 0.7112)
		(drill 0.4064)
		(layers "F.Cu" "B.Cu")
		(net "GND")
	)
	(via
		(at 38.5826 -480.4156)
		(size 0.5588)
		(drill 0.3048)
		(layers "F.Cu" "B.Cu")
		(net "GND")
	)
	(via
		(at 41.021 -189.865)
		(size 0.5588)
		(drill 0.3048)
		(layers "F.Cu" "B.Cu")
		(net "GND")
	)
	(via
		(at 8.128 -214.376)
		(size 0.7112)
		(drill 0.4064)
		(layers "F.Cu" "B.Cu")
		(net "GND")
	)
	(via
		(at 12.446 -358.9782)
		(size 0.7112)
		(drill 0.4064)
		(layers "F.Cu" "B.Cu")
		(net "GND")
	)
	(via
		(at 40.767 -232.791)
		(size 0.7112)
		(drill 0.3556)
		(layers "F.Cu" "B.Cu")
		(net "GND")
	)
	(via
		(at 25.146254 -176.495964)
		(size 0.7112)
		(drill 0.4064)
		(layers "F.Cu" "B.Cu")
		(net "GND")
	)
	(via
		(at 14.1224 -350.9518)
		(size 0.7112)
		(drill 0.4064)
		(layers "F.Cu" "B.Cu")
		(net "GND")
	)
	(via
		(at 29.083 -177.927)
		(size 0.5588)
		(drill 0.3048)
		(layers "F.Cu" "B.Cu")
		(net "GND")
	)
	(via
		(at 9.7536 -405.5618)
		(size 0.5588)
		(drill 0.3048)
		(layers "F.Cu" "B.Cu")
		(net "GND")
	)
	(via
		(at 1.2446 -433.832)
		(size 0.7112)
		(drill 0.4064)
		(layers "F.Cu" "B.Cu")
		(net "GND")
	)
	(via
		(at 9.144 -140.716)
		(size 0.7112)
		(drill 0.4064)
		(layers "F.Cu" "B.Cu")
		(net "GND")
	)
	(via
		(at 4.064 -291.592)
		(size 0.7112)
		(drill 0.4064)
		(layers "F.Cu" "B.Cu")
		(net "GND")
	)
	(via
		(at 39.2938 -231.0638)
		(size 0.7112)
		(drill 0.4064)
		(layers "F.Cu" "B.Cu")
		(net "GND")
	)
	(via
		(at 50.165 -472.44)
		(size 0.7112)
		(drill 0.4064)
		(layers "F.Cu" "B.Cu")
		(net "GND")
	)
	(via
		(at 4.064 -298.704)
		(size 0.7112)
		(drill 0.4064)
		(layers "F.Cu" "B.Cu")
		(net "GND")
	)
	(via
		(at 51.076606 -80.137)
		(size 0.7112)
		(drill 0.4064)
		(layers "F.Cu" "B.Cu")
		(net "GND")
	)
	(via
		(at 22.352 -262.763)
		(size 0.7112)
		(drill 0.3556)
		(layers "F.Cu" "B.Cu")
		(net "GND")
	)
	(via
		(at 20.182332 -147.004532)
		(size 0.7112)
		(drill 0.4064)
		(layers "F.Cu" "B.Cu")
		(net "GND")
	)
	(via
		(at 10.668 -315.468)
		(size 0.7112)
		(drill 0.4064)
		(layers "F.Cu" "B.Cu")
		(net "GND")
	)
	(via
		(at 38.862 -22.987)
		(size 0.7112)
		(drill 0.4064)
		(layers "F.Cu" "B.Cu")
		(net "GND")
	)
	(via
		(at 29.083 -204.597)
		(size 0.7112)
		(drill 0.4064)
		(layers "F.Cu" "B.Cu")
		(net "GND")
	)
	(via
		(at 24.257 -253.746)
		(size 0.7112)
		(drill 0.4064)
		(layers "F.Cu" "B.Cu")
		(net "GND")
	)
	(via
		(at 17.399 -369.4684)
		(size 0.7112)
		(drill 0.4064)
		(layers "F.Cu" "B.Cu")
		(net "GND")
	)
	(via
		(at 12.9032 -67.6656)
		(size 0.5588)
		(drill 0.3048)
		(layers "F.Cu" "B.Cu")
		(net "GND")
	)
	(via
		(at 6.7818 -388.5692)
		(size 0.5588)
		(drill 0.3048)
		(layers "F.Cu" "B.Cu")
		(net "GND")
	)
	(via
		(at 9.525 -284.2006)
		(size 0.7112)
		(drill 0.4064)
		(layers "F.Cu" "B.Cu")
		(net "GND")
	)
	(via
		(at 3.048 -323.596)
		(size 0.7112)
		(drill 0.4064)
		(layers "F.Cu" "B.Cu")
		(net "GND")
	)
	(via
		(at 1.293876 -487.934)
		(size 0.7112)
		(drill 0.4064)
		(layers "F.Cu" "B.Cu")
		(net "GND")
	)
	(via
		(at 32.766 -40.6654)
		(size 0.7112)
		(drill 0.4064)
		(layers "F.Cu" "B.Cu")
		(net "GND")
	)
	(via
		(at 3.2004 -445.4652)
		(size 0.7112)
		(drill 0.4064)
		(layers "F.Cu" "B.Cu")
		(net "GND")
	)
	(via
		(at 1.143 -43.307)
		(size 0.7112)
		(drill 0.4064)
		(layers "F.Cu" "B.Cu")
		(net "GND")
	)
	(via
		(at 1.143 -231.902)
		(size 0.7112)
		(drill 0.4064)
		(layers "F.Cu" "B.Cu")
		(net "GND")
	)
	(via
		(at 51.308 -307.848)
		(size 0.5588)
		(drill 0.3048)
		(layers "F.Cu" "B.Cu")
		(net "GND")
	)
	(via
		(at 31.7754 -356.235)
		(size 0.5588)
		(drill 0.3048)
		(layers "F.Cu" "B.Cu")
		(net "GND")
	)
	(via
		(at 8.001 -1.397)
		(size 0.7112)
		(drill 0.4064)
		(layers "F.Cu" "B.Cu")
		(net "GND")
	)
	(via
		(at 9.9822 -45.9994)
		(size 0.5588)
		(drill 0.3048)
		(layers "F.Cu" "B.Cu")
		(net "GND")
	)
	(via
		(at 10.16 -293.624)
		(size 0.7112)
		(drill 0.4064)
		(layers "F.Cu" "B.Cu")
		(net "GND")
	)
	(via
		(at 3.3274 -442.6204)
		(size 0.7112)
		(drill 0.4064)
		(layers "F.Cu" "B.Cu")
		(net "GND")
	)
	(via
		(at 39.37 -11.43)
		(size 0.7112)
		(drill 0.4064)
		(layers "F.Cu" "B.Cu")
		(net "GND")
	)
	(via
		(at 28.829 -185.166)
		(size 0.5588)
		(drill 0.3048)
		(layers "F.Cu" "B.Cu")
		(net "GND")
	)
	(via
		(at 11.4554 -491.0836)
		(size 0.7112)
		(drill 0.4064)
		(layers "F.Cu" "B.Cu")
		(net "GND")
	)
	(via
		(at 6.617462 -238.314738)
		(size 0.7112)
		(drill 0.4064)
		(layers "F.Cu" "B.Cu")
		(net "GND")
	)
	(via
		(at 50.165 -445.516)
		(size 0.7112)
		(drill 0.4064)
		(layers "F.Cu" "B.Cu")
		(net "GND")
	)
	(via
		(at 17.4752 -360.1212)
		(size 0.7112)
		(drill 0.4064)
		(layers "F.Cu" "B.Cu")
		(net "GND")
	)
	(via
		(at 37.338 -134.5946)
		(size 0.5588)
		(drill 0.3048)
		(layers "F.Cu" "B.Cu")
		(net "GND")
	)
	(via
		(at 48.641 -175.895)
		(size 0.7112)
		(drill 0.4064)
		(layers "F.Cu" "B.Cu")
		(net "GND")
	)
	(via
		(at 14.732 -333.248)
		(size 0.7112)
		(drill 0.4064)
		(layers "F.Cu" "B.Cu")
		(net "GND")
	)
	(via
		(at 18.161 -186.817)
		(size 0.5588)
		(drill 0.3048)
		(layers "F.Cu" "B.Cu")
		(net "GND")
	)
	(via
		(at 45.9359 -88.5952)
		(size 0.7112)
		(drill 0.4064)
		(layers "F.Cu" "B.Cu")
		(net "GND")
	)
	(via
		(at 3.556 -272.796)
		(size 0.7112)
		(drill 0.4064)
		(layers "F.Cu" "B.Cu")
		(net "GND")
	)
	(via
		(at 1.651 -330.708)
		(size 0.7112)
		(drill 0.4064)
		(layers "F.Cu" "B.Cu")
		(net "GND")
	)
	(via
		(at 1.2192 -90.4748)
		(size 0.7112)
		(drill 0.4064)
		(layers "F.Cu" "B.Cu")
		(net "GND")
	)
	(via
		(at 6.0198 -92.4306)
		(size 0.7112)
		(drill 0.4064)
		(layers "F.Cu" "B.Cu")
		(net "GND")
	)
	(via
		(at 45.085 -206.248)
		(size 0.7112)
		(drill 0.4064)
		(layers "F.Cu" "B.Cu")
		(net "GND")
	)
	(via
		(at 12.7 -190.246)
		(size 0.7112)
		(drill 0.4064)
		(layers "F.Cu" "B.Cu")
		(net "GND")
	)
	(via
		(at 45.974 -279.019)
		(size 0.7112)
		(drill 0.4064)
		(layers "F.Cu" "B.Cu")
		(net "GND")
	)
	(via
		(at 7.9756 -418.6428)
		(size 0.5588)
		(drill 0.3048)
		(layers "F.Cu" "B.Cu")
		(net "GND")
	)
	(via
		(at 42.545 -435.864)
		(size 0.7112)
		(drill 0.4064)
		(layers "F.Cu" "B.Cu")
		(net "GND")
	)
	(via
		(at 51.435 -240.157)
		(size 0.5588)
		(drill 0.3048)
		(layers "F.Cu" "B.Cu")
		(net "GND")
	)
	(via
		(at 49.3776 -148.844)
		(size 0.7112)
		(drill 0.4064)
		(layers "F.Cu" "B.Cu")
		(net "GND")
	)
	(via
		(at 24.384 -149.352)
		(size 0.5588)
		(drill 0.3048)
		(layers "F.Cu" "B.Cu")
		(net "GND")
	)
	(via
		(at 30.226 -322.326)
		(size 0.7112)
		(drill 0.4064)
		(layers "F.Cu" "B.Cu")
		(net "GND")
	)
	(via
		(at 38.020244 -370.841778)
		(size 0.7112)
		(drill 0.4064)
		(layers "F.Cu" "B.Cu")
		(net "GND")
	)
	(via
		(at 1.166876 -106.934)
		(size 0.7112)
		(drill 0.4064)
		(layers "F.Cu" "B.Cu")
		(net "GND")
	)
	(via
		(at 49.403 -195.326)
		(size 0.7112)
		(drill 0.4064)
		(layers "F.Cu" "B.Cu")
		(net "GND")
	)
	(via
		(at 39.878 -279.781)
		(size 0.7112)
		(drill 0.4064)
		(layers "F.Cu" "B.Cu")
		(net "GND")
	)
	(via
		(at 24.892 -177.419)
		(size 0.5588)
		(drill 0.3048)
		(layers "F.Cu" "B.Cu")
		(net "GND")
	)
	(via
		(at 34.29 -17.78)
		(size 0.7112)
		(drill 0.4064)
		(layers "F.Cu" "B.Cu")
		(net "GND")
	)
	(via
		(at 50.8 -25.4)
		(size 0.7112)
		(drill 0.4064)
		(layers "F.Cu" "B.Cu")
		(net "GND")
	)
	(via
		(at 1.166876 -477.139)
		(size 0.7112)
		(drill 0.4064)
		(layers "F.Cu" "B.Cu")
		(net "GND")
	)
	(via
		(at 1.27 -103.759)
		(size 0.7112)
		(drill 0.4064)
		(layers "F.Cu" "B.Cu")
		(net "GND")
	)
	(via
		(at 23.495 -18.542)
		(size 0.5588)
		(drill 0.3048)
		(layers "F.Cu" "B.Cu")
		(net "GND")
	)
	(via
		(at 25.527 -351.663)
		(size 0.7112)
		(drill 0.4064)
		(layers "F.Cu" "B.Cu")
		(net "GND")
	)
	(via
		(at 1.524 -164.084)
		(size 0.7112)
		(drill 0.4064)
		(layers "F.Cu" "B.Cu")
		(net "GND")
	)
	(via
		(at 13.335 -173.355)
		(size 0.5588)
		(drill 0.3048)
		(layers "F.Cu" "B.Cu")
		(net "GND")
	)
	(via
		(at 26.416 -266.573)
		(size 0.5588)
		(drill 0.3048)
		(layers "F.Cu" "B.Cu")
		(net "GND")
	)
	(via
		(at 26.035 -226.949)
		(size 0.7112)
		(drill 0.4064)
		(layers "F.Cu" "B.Cu")
		(net "GND")
	)
	(via
		(at 38.989 -145.887186)
		(size 0.7112)
		(drill 0.4064)
		(layers "F.Cu" "B.Cu")
		(net "GND")
	)
	(via
		(at 11.049 -411.6578)
		(size 0.5588)
		(drill 0.3048)
		(layers "F.Cu" "B.Cu")
		(net "GND")
	)
	(via
		(at 18.8214 -170.027092)
		(size 0.7112)
		(drill 0.4064)
		(layers "F.Cu" "B.Cu")
		(net "GND")
	)
	(via
		(at 8.128 -217.932)
		(size 0.7112)
		(drill 0.4064)
		(layers "F.Cu" "B.Cu")
		(net "GND")
	)
	(via
		(at 29.76753 -369.84178)
		(size 0.7112)
		(drill 0.4064)
		(layers "F.Cu" "B.Cu")
		(net "GND")
	)
	(via
		(at 9.525 -231.648)
		(size 0.7112)
		(drill 0.4064)
		(layers "F.Cu" "B.Cu")
		(net "GND")
	)
	(via
		(at 2.182876 -1.651)
		(size 0.7112)
		(drill 0.4064)
		(layers "F.Cu" "B.Cu")
		(net "GND")
	)
	(via
		(at 37.465 -347.091)
		(size 0.7112)
		(drill 0.4064)
		(layers "F.Cu" "B.Cu")
		(net "GND")
	)
	(via
		(at 11.176 -336.804)
		(size 0.7112)
		(drill 0.4064)
		(layers "F.Cu" "B.Cu")
		(net "GND")
	)
	(via
		(at 22.1742 -364.744)
		(size 0.7112)
		(drill 0.4064)
		(layers "F.Cu" "B.Cu")
		(net "GND")
	)
	(via
		(at 51.308 -180.34)
		(size 0.7112)
		(drill 0.4064)
		(layers "F.Cu" "B.Cu")
		(net "GND")
	)
	(via
		(at 23.876 -302.006)
		(size 0.7112)
		(drill 0.4064)
		(layers "F.Cu" "B.Cu")
		(net "GND")
	)
	(via
		(at 19.632422 -286.951166)
		(size 0.7112)
		(drill 0.4064)
		(layers "F.Cu" "B.Cu")
		(net "GND")
	)
	(via
		(at 7.62 -314.96)
		(size 0.7112)
		(drill 0.4064)
		(layers "F.Cu" "B.Cu")
		(net "GND")
	)
	(via
		(at 26.67 -243.332)
		(size 0.7112)
		(drill 0.4064)
		(layers "F.Cu" "B.Cu")
		(net "GND")
	)
	(via
		(at 7.874 -189.738)
		(size 0.7112)
		(drill 0.4064)
		(layers "F.Cu" "B.Cu")
		(net "GND")
	)
	(via
		(at 36.322 -231.267)
		(size 0.7112)
		(drill 0.4064)
		(layers "F.Cu" "B.Cu")
		(net "GND")
	)
	(via
		(at 34.29 -247.777)
		(size 0.7112)
		(drill 0.4064)
		(layers "F.Cu" "B.Cu")
		(net "GND")
	)
	(via
		(at 38.227 -151.384)
		(size 0.7112)
		(drill 0.4064)
		(layers "F.Cu" "B.Cu")
		(net "GND")
	)
	(via
		(at 50.165 -173.99)
		(size 0.7112)
		(drill 0.4064)
		(layers "F.Cu" "B.Cu")
		(net "GND")
	)
	(via
		(at 48.7172 -59.6646)
		(size 0.7112)
		(drill 0.4064)
		(layers "F.Cu" "B.Cu")
		(net "GND")
	)
	(via
		(at 3.048 -328.676)
		(size 0.7112)
		(drill 0.4064)
		(layers "F.Cu" "B.Cu")
		(net "GND")
	)
	(via
		(at 3.302 -61.976)
		(size 0.7112)
		(drill 0.4064)
		(layers "F.Cu" "B.Cu")
		(net "GND")
	)
	(via
		(at 30.353 -192.405)
		(size 0.5588)
		(drill 0.3048)
		(layers "F.Cu" "B.Cu")
		(net "GND")
	)
	(via
		(at 51.308 -165.227)
		(size 0.7112)
		(drill 0.4064)
		(layers "F.Cu" "B.Cu")
		(net "GND")
	)
	(via
		(at 42.926 -452.501)
		(size 0.7112)
		(drill 0.4064)
		(layers "F.Cu" "B.Cu")
		(net "GND")
	)
	(via
		(at 48.895 -163.83)
		(size 0.7112)
		(drill 0.4064)
		(layers "F.Cu" "B.Cu")
		(net "GND")
	)
	(via
		(at 51.308 -226.06)
		(size 0.5588)
		(drill 0.3048)
		(layers "F.Cu" "B.Cu")
		(net "GND")
	)
	(via
		(at 7.747 -208.153)
		(size 0.7112)
		(drill 0.4064)
		(layers "F.Cu" "B.Cu")
		(net "GND")
	)
	(via
		(at 45.466 -255.27)
		(size 0.5588)
		(drill 0.3048)
		(layers "F.Cu" "B.Cu")
		(net "GND")
	)
	(via
		(at 1.347216 -111.887)
		(size 0.7112)
		(drill 0.4064)
		(layers "F.Cu" "B.Cu")
		(net "GND")
	)
	(via
		(at 10.8458 -381)
		(size 0.7112)
		(drill 0.4064)
		(layers "F.Cu" "B.Cu")
		(net "GND")
	)
	(via
		(at 17.526 -38.862)
		(size 0.7112)
		(drill 0.4064)
		(layers "F.Cu" "B.Cu")
		(net "GND")
	)
	(via
		(at 45.466 -456.819)
		(size 0.7112)
		(drill 0.4064)
		(layers "F.Cu" "B.Cu")
		(net "GND")
	)
	(via
		(at 29.972 -39.243)
		(size 0.7112)
		(drill 0.4064)
		(layers "F.Cu" "B.Cu")
		(net "GND")
	)
	(via
		(at 31.4452 -346.9386)
		(size 0.7112)
		(drill 0.4064)
		(layers "F.Cu" "B.Cu")
		(net "GND")
	)
	(via
		(at 41.021 -192.786)
		(size 0.5588)
		(drill 0.3048)
		(layers "F.Cu" "B.Cu")
		(net "GND")
	)
	(via
		(at 43.18 -487.807)
		(size 0.5588)
		(drill 0.3048)
		(layers "F.Cu" "B.Cu")
		(net "GND")
	)
	(via
		(at 44.196 -211.963)
		(size 0.5588)
		(drill 0.3048)
		(layers "F.Cu" "B.Cu")
		(net "GND")
	)
	(via
		(at 47.625 -280.289)
		(size 0.7112)
		(drill 0.4064)
		(layers "F.Cu" "B.Cu")
		(net "GND")
	)
	(via
		(at 48.895 -213.233)
		(size 0.7112)
		(drill 0.4064)
		(layers "F.Cu" "B.Cu")
		(net "GND")
	)
	(via
		(at 41.402 -264.795)
		(size 0.5588)
		(drill 0.3048)
		(layers "F.Cu" "B.Cu")
		(net "GND")
	)
	(via
		(at 1.166876 -59.436)
		(size 0.7112)
		(drill 0.4064)
		(layers "F.Cu" "B.Cu")
		(net "GND")
	)
	(via
		(at 49.657 -257.683)
		(size 0.7112)
		(drill 0.4064)
		(layers "F.Cu" "B.Cu")
		(net "GND")
	)
	(via
		(at 8.89 -491.109)
		(size 0.7112)
		(drill 0.4064)
		(layers "F.Cu" "B.Cu")
		(net "GND")
	)
	(via
		(at 51.076606 -46.1518)
		(size 0.7112)
		(drill 0.4064)
		(layers "F.Cu" "B.Cu")
		(net "GND")
	)
	(via
		(at 15.748 -476.758)
		(size 0.5588)
		(drill 0.3048)
		(layers "F.Cu" "B.Cu")
		(net "GND")
	)
	(via
		(at 3.429 -70.866)
		(size 0.7112)
		(drill 0.4064)
		(layers "F.Cu" "B.Cu")
		(net "GND")
	)
	(via
		(at 45.974 -282.575)
		(size 0.7112)
		(drill 0.4064)
		(layers "F.Cu" "B.Cu")
		(net "GND")
	)
	(via
		(at 22.2758 -367.411)
		(size 0.7112)
		(drill 0.4064)
		(layers "F.Cu" "B.Cu")
		(net "GND")
	)
	(via
		(at 4.064 -265.684)
		(size 0.7112)
		(drill 0.4064)
		(layers "F.Cu" "B.Cu")
		(net "GND")
	)
	(via
		(at 47.879 -92.4814)
		(size 0.7112)
		(drill 0.4064)
		(layers "F.Cu" "B.Cu")
		(net "GND")
	)
	(via
		(at 44.069 -188.087)
		(size 0.7112)
		(drill 0.3556)
		(layers "F.Cu" "B.Cu")
		(net "GND")
	)
	(via
		(at 15.3162 -480.6442)
		(size 0.5588)
		(drill 0.3048)
		(layers "F.Cu" "B.Cu")
		(net "GND")
	)
	(via
		(at 28.067 -270.383)
		(size 0.7112)
		(drill 0.4064)
		(layers "F.Cu" "B.Cu")
		(net "GND")
	)
	(via
		(at 49.53 -272.923)
		(size 0.7112)
		(drill 0.4064)
		(layers "F.Cu" "B.Cu")
		(net "GND")
	)
	(via
		(at 49.403 -279.527)
		(size 0.7112)
		(drill 0.4064)
		(layers "F.Cu" "B.Cu")
		(net "GND")
	)
	(via
		(at 45.72 -243.9416)
		(size 0.5588)
		(drill 0.3048)
		(layers "F.Cu" "B.Cu")
		(net "GND")
	)
	(via
		(at 4.064 -288.036)
		(size 0.7112)
		(drill 0.4064)
		(layers "F.Cu" "B.Cu")
		(net "GND")
	)
	(via
		(at 11.3284 -437.9976)
		(size 0.7112)
		(drill 0.4064)
		(layers "F.Cu" "B.Cu")
		(net "GND")
	)
	(via
		(at 23.8252 -343.8906)
		(size 0.7112)
		(drill 0.4064)
		(layers "F.Cu" "B.Cu")
		(net "GND")
	)
	(via
		(at 47.244 -454.66)
		(size 0.7112)
		(drill 0.4064)
		(layers "F.Cu" "B.Cu")
		(net "GND")
	)
	(via
		(at 39.2684 -282.194)
		(size 0.7112)
		(drill 0.4064)
		(layers "F.Cu" "B.Cu")
		(net "GND")
	)
	(via
		(at 17.653 -238.506)
		(size 0.7112)
		(drill 0.4064)
		(layers "F.Cu" "B.Cu")
		(net "GND")
	)
	(via
		(at 41.402 -431.038)
		(size 0.7112)
		(drill 0.4064)
		(layers "F.Cu" "B.Cu")
		(net "GND")
	)
	(via
		(at 30.4292 -144.3482)
		(size 0.5588)
		(drill 0.3048)
		(layers "F.Cu" "B.Cu")
		(net "GND")
	)
	(via
		(at 49.3776 -476.6818)
		(size 0.7112)
		(drill 0.4064)
		(layers "F.Cu" "B.Cu")
		(net "GND")
	)
	(via
		(at 41.2242 -167.4114)
		(size 0.7112)
		(drill 0.4064)
		(layers "F.Cu" "B.Cu")
		(net "GND")
	)
	(via
		(at 16.2814 -379.8316)
		(size 0.7112)
		(drill 0.4064)
		(layers "F.Cu" "B.Cu")
		(net "GND")
	)
	(via
		(at 42.164 -193.04)
		(size 0.5588)
		(drill 0.3048)
		(layers "F.Cu" "B.Cu")
		(net "GND")
	)
	(via
		(at 8.636 -239.776)
		(size 0.7112)
		(drill 0.4064)
		(layers "F.Cu" "B.Cu")
		(net "GND")
	)
	(via
		(at 31.75 -11.43)
		(size 0.7112)
		(drill 0.4064)
		(layers "F.Cu" "B.Cu")
		(net "GND")
	)
	(via
		(at 51.308 -205.105)
		(size 0.7112)
		(drill 0.4064)
		(layers "F.Cu" "B.Cu")
		(net "GND")
	)
	(via
		(at 10.922 -6.858)
		(size 0.7112)
		(drill 0.4064)
		(layers "F.Cu" "B.Cu")
		(net "GND")
	)
	(via
		(at 16.152876 -1.778)
		(size 0.7112)
		(drill 0.4064)
		(layers "F.Cu" "B.Cu")
		(net "GND")
	)
	(via
		(at 29.21 -233.68)
		(size 0.7112)
		(drill 0.4064)
		(layers "F.Cu" "B.Cu")
		(net "GND")
	)
	(via
		(at 11.8364 -391.4394)
		(size 0.7112)
		(drill 0.4064)
		(layers "F.Cu" "B.Cu")
		(net "GND")
	)
	(via
		(at 33.02 -177.927)
		(size 0.5588)
		(drill 0.3048)
		(layers "F.Cu" "B.Cu")
		(net "GND")
	)
	(via
		(at 49.911 -420.624)
		(size 0.7112)
		(drill 0.4064)
		(layers "F.Cu" "B.Cu")
		(net "GND")
	)
	(via
		(at 34.925 -229.362)
		(size 0.7112)
		(drill 0.4064)
		(layers "F.Cu" "B.Cu")
		(net "GND")
	)
	(via
		(at 6.985 -476.123)
		(size 0.7112)
		(drill 0.4064)
		(layers "F.Cu" "B.Cu")
		(net "GND")
	)
	(via
		(at 49.657 -388.747)
		(size 0.7112)
		(drill 0.4064)
		(layers "F.Cu" "B.Cu")
		(net "GND")
	)
	(via
		(at 48.26 -411.988)
		(size 0.7112)
		(drill 0.4064)
		(layers "F.Cu" "B.Cu")
		(net "GND")
	)
	(via
		(at 41.021 -470.535)
		(size 0.7112)
		(drill 0.4064)
		(layers "F.Cu" "B.Cu")
		(net "GND")
	)
	(via
		(at 41.91 -278.638)
		(size 0.7112)
		(drill 0.4064)
		(layers "F.Cu" "B.Cu")
		(net "GND")
	)
	(via
		(at 50.165 -451.231)
		(size 0.7112)
		(drill 0.4064)
		(layers "F.Cu" "B.Cu")
		(net "GND")
	)
	(via
		(at 51.435 -169.164)
		(size 0.5588)
		(drill 0.3048)
		(layers "F.Cu" "B.Cu")
		(net "GND")
	)
	(via
		(at 46.609 -177.292)
		(size 0.7112)
		(drill 0.4064)
		(layers "F.Cu" "B.Cu")
		(net "GND")
	)
	(via
		(at 7.874 -177.927)
		(size 0.7112)
		(drill 0.4064)
		(layers "F.Cu" "B.Cu")
		(net "GND")
	)
	(via
		(at 17.6276 -356.3366)
		(size 0.7112)
		(drill 0.4064)
		(layers "F.Cu" "B.Cu")
		(net "GND")
	)
	(via
		(at 6.35 -498.475)
		(size 0.7112)
		(drill 0.4064)
		(layers "F.Cu" "B.Cu")
		(net "GND")
	)
	(via
		(at 51.152806 -271.018)
		(size 0.5588)
		(drill 0.3048)
		(layers "F.Cu" "B.Cu")
		(net "GND")
	)
	(via
		(at 7.112 -405.5872)
		(size 0.5588)
		(drill 0.3048)
		(layers "F.Cu" "B.Cu")
		(net "GND")
	)
	(via
		(at 9.144 -466.217)
		(size 0.7112)
		(drill 0.4064)
		(layers "F.Cu" "B.Cu")
		(net "GND")
	)
	(via
		(at 45.212 -202.565)
		(size 0.7112)
		(drill 0.4064)
		(layers "F.Cu" "B.Cu")
		(net "GND")
	)
	(via
		(at 29.972 -31.623)
		(size 0.7112)
		(drill 0.4064)
		(layers "F.Cu" "B.Cu")
		(net "GND")
	)
	(via
		(at 25.273 -328.676)
		(size 0.7112)
		(drill 0.4064)
		(layers "F.Cu" "B.Cu")
		(net "GND")
	)
	(via
		(at 18.288 -345.44)
		(size 0.7112)
		(drill 0.4064)
		(layers "F.Cu" "B.Cu")
		(net "GND")
	)
	(via
		(at 1.293876 -493.903)
		(size 0.7112)
		(drill 0.4064)
		(layers "F.Cu" "B.Cu")
		(net "GND")
	)
	(via
		(at 50.927 -59.69)
		(size 0.7112)
		(drill 0.4064)
		(layers "F.Cu" "B.Cu")
		(net "GND")
	)
	(via
		(at 14.9352 -358.7496)
		(size 0.7112)
		(drill 0.4064)
		(layers "F.Cu" "B.Cu")
		(net "GND")
	)
	(via
		(at 4.064 -285.496)
		(size 0.7112)
		(drill 0.4064)
		(layers "F.Cu" "B.Cu")
		(net "GND")
	)
	(via
		(at 51.308 -233.172)
		(size 0.5588)
		(drill 0.3048)
		(layers "F.Cu" "B.Cu")
		(net "GND")
	)
	(via
		(at 43.561 -26.797)
		(size 0.7112)
		(drill 0.4064)
		(layers "F.Cu" "B.Cu")
		(net "GND")
	)
	(via
		(at 44.03725 -363.855)
		(size 0.7112)
		(drill 0.4064)
		(layers "F.Cu" "B.Cu")
		(net "GND")
	)
	(via
		(at 10.0076 -350.8502)
		(size 0.5588)
		(drill 0.3048)
		(layers "F.Cu" "B.Cu")
		(net "GND")
	)
	(via
		(at 29.083 -348.107)
		(size 0.7112)
		(drill 0.4064)
		(layers "F.Cu" "B.Cu")
		(net "GND")
	)
	(via
		(at 35.0266 -43.5356)
		(size 0.7112)
		(drill 0.4064)
		(layers "F.Cu" "B.Cu")
		(net "GND")
	)
	(via
		(at 50.165 -191.262)
		(size 0.7112)
		(drill 0.4064)
		(layers "F.Cu" "B.Cu")
		(net "GND")
	)
	(via
		(at 46.1518 -195.1736)
		(size 0.7112)
		(drill 0.4064)
		(layers "F.Cu" "B.Cu")
		(net "GND")
	)
	(via
		(at 27.559 -246.634)
		(size 0.7112)
		(drill 0.4064)
		(layers "F.Cu" "B.Cu")
		(net "GND")
	)
	(via
		(at 27.051 -256.159)
		(size 0.7112)
		(drill 0.4064)
		(layers "F.Cu" "B.Cu")
		(net "GND")
	)
	(via
		(at 10.310876 -1.524)
		(size 0.7112)
		(drill 0.4064)
		(layers "F.Cu" "B.Cu")
		(net "GND")
	)
	(via
		(at 23.8252 -350.4946)
		(size 0.7112)
		(drill 0.4064)
		(layers "F.Cu" "B.Cu")
		(net "GND")
	)
	(via
		(at 24.257 -213.741)
		(size 0.7112)
		(drill 0.4064)
		(layers "F.Cu" "B.Cu")
		(net "GND")
	)
	(via
		(at 11.049 -494.03)
		(size 0.7112)
		(drill 0.4064)
		(layers "F.Cu" "B.Cu")
		(net "GND")
	)
	(via
		(at 44.45 -268.986)
		(size 0.7112)
		(drill 0.4064)
		(layers "F.Cu" "B.Cu")
		(net "GND")
	)
	(via
		(at 12.573 -382.27)
		(size 0.7112)
		(drill 0.4064)
		(layers "F.Cu" "B.Cu")
		(net "GND")
	)
	(via
		(at 31.7246 -147.828)
		(size 0.5588)
		(drill 0.3048)
		(layers "F.Cu" "B.Cu")
		(net "GND")
	)
	(via
		(at 19.685 -230.378)
		(size 0.7112)
		(drill 0.4064)
		(layers "F.Cu" "B.Cu")
		(net "GND")
	)
	(via
		(at 11.5062 -397.1544)
		(size 0.7112)
		(drill 0.4064)
		(layers "F.Cu" "B.Cu")
		(net "GND")
	)
	(via
		(at 11.0744 -423.7482)
		(size 0.5588)
		(drill 0.3048)
		(layers "F.Cu" "B.Cu")
		(net "GND")
	)
	(via
		(at 4.0894 -201.8284)
		(size 0.7112)
		(drill 0.4064)
		(layers "F.Cu" "B.Cu")
		(net "GND")
	)
	(via
		(at 29.21 -11.43)
		(size 0.7112)
		(drill 0.4064)
		(layers "F.Cu" "B.Cu")
		(net "GND")
	)
	(via
		(at 40.513 -276.225)
		(size 0.7112)
		(drill 0.4064)
		(layers "F.Cu" "B.Cu")
		(net "GND")
	)
	(via
		(at 41.148 -260.858)
		(size 0.7112)
		(drill 0.3556)
		(layers "F.Cu" "B.Cu")
		(net "GND")
	)
	(via
		(at 46.355 -264.541)
		(size 0.7112)
		(drill 0.4064)
		(layers "F.Cu" "B.Cu")
		(net "GND")
	)
	(via
		(at 6.7564 -287.6296)
		(size 0.7112)
		(drill 0.4064)
		(layers "F.Cu" "B.Cu")
		(net "GND")
	)
	(via
		(at 48.6664 -52.5526)
		(size 0.7112)
		(drill 0.4064)
		(layers "F.Cu" "B.Cu")
		(net "GND")
	)
	(via
		(at 26.139902 -171.189142)
		(size 0.7112)
		(drill 0.4064)
		(layers "F.Cu" "B.Cu")
		(net "GND")
	)
	(via
		(at 2.413 -204.216)
		(size 0.7112)
		(drill 0.4064)
		(layers "F.Cu" "B.Cu")
		(net "GND")
	)
	(via
		(at 30.734 -287.782)
		(size 0.7112)
		(drill 0.3556)
		(layers "F.Cu" "B.Cu")
		(net "GND")
	)
	(via
		(at 25.781 -103.251)
		(size 0.7112)
		(drill 0.4064)
		(layers "F.Cu" "B.Cu")
		(net "GND")
	)
	(via
		(at 36.957 -224.79)
		(size 0.7112)
		(drill 0.4064)
		(layers "F.Cu" "B.Cu")
		(net "GND")
	)
	(via
		(at 1.347216 -112.903)
		(size 0.7112)
		(drill 0.4064)
		(layers "F.Cu" "B.Cu")
		(net "GND")
	)
	(via
		(at 18.5166 -353.9744)
		(size 0.7112)
		(drill 0.4064)
		(layers "F.Cu" "B.Cu")
		(net "GND")
	)
	(via
		(at 22.098 -253.365)
		(size 0.7112)
		(drill 0.4064)
		(layers "F.Cu" "B.Cu")
		(net "GND")
	)
	(via
		(at 37.211 -206.248)
		(size 0.5588)
		(drill 0.3048)
		(layers "F.Cu" "B.Cu")
		(net "GND")
	)
	(via
		(at 13.335 -63.119)
		(size 0.5588)
		(drill 0.3048)
		(layers "F.Cu" "B.Cu")
		(net "GND")
	)
	(via
		(at 8.636 -113.792)
		(size 0.5588)
		(drill 0.3048)
		(layers "F.Cu" "B.Cu")
		(net "GND")
	)
	(via
		(at 51.181 -482.727)
		(size 0.7112)
		(drill 0.4064)
		(layers "F.Cu" "B.Cu")
		(net "GND")
	)
	(via
		(at 1.420876 -214.503)
		(size 0.7112)
		(drill 0.4064)
		(layers "F.Cu" "B.Cu")
		(net "GND")
	)
	(via
		(at 49.276 -159.639)
		(size 0.7112)
		(drill 0.4064)
		(layers "F.Cu" "B.Cu")
		(net "GND")
	)
	(via
		(at 35.7378 -146.4564)
		(size 0.7112)
		(drill 0.4064)
		(layers "F.Cu" "B.Cu")
		(net "GND")
	)
	(via
		(at 46.228 -258.064)
		(size 0.7112)
		(drill 0.4064)
		(layers "F.Cu" "B.Cu")
		(net "GND")
	)
	(via
		(at 48.895 -250.317)
		(size 0.7112)
		(drill 0.4064)
		(layers "F.Cu" "B.Cu")
		(net "GND")
	)
	(via
		(at 21.2852 -346.9386)
		(size 0.7112)
		(drill 0.4064)
		(layers "F.Cu" "B.Cu")
		(net "GND")
	)
	(via
		(at 43.434 -357.505)
		(size 0.7112)
		(drill 0.3556)
		(layers "F.Cu" "B.Cu")
		(net "GND")
	)
	(via
		(at 43.18 -189.357)
		(size 0.5588)
		(drill 0.3048)
		(layers "F.Cu" "B.Cu")
		(net "GND")
	)
	(via
		(at 10.668 -200.152)
		(size 0.7112)
		(drill 0.4064)
		(layers "F.Cu" "B.Cu")
		(net "GND")
	)
	(via
		(at 31.75 -220.599)
		(size 0.7112)
		(drill 0.4064)
		(layers "F.Cu" "B.Cu")
		(net "GND")
	)
	(via
		(at 24.892 -178.562)
		(size 0.5588)
		(drill 0.3048)
		(layers "F.Cu" "B.Cu")
		(net "GND")
	)
	(via
		(at 16.51 -42.2402)
		(size 0.5588)
		(drill 0.3048)
		(layers "F.Cu" "B.Cu")
		(net "GND")
	)
	(via
		(at 16.256 -4.318)
		(size 0.7112)
		(drill 0.4064)
		(layers "F.Cu" "B.Cu")
		(net "GND")
	)
	(via
		(at 24.13 -31.75)
		(size 0.7112)
		(drill 0.4064)
		(layers "F.Cu" "B.Cu")
		(net "GND")
	)
	(via
		(at 50.8 -19.05)
		(size 0.7112)
		(drill 0.4064)
		(layers "F.Cu" "B.Cu")
		(net "GND")
	)
	(via
		(at 44.8818 -488.6706)
		(size 0.5588)
		(drill 0.3048)
		(layers "F.Cu" "B.Cu")
		(net "GND")
	)
	(via
		(at 34.29 -142.621)
		(size 0.5588)
		(drill 0.3048)
		(layers "F.Cu" "B.Cu")
		(net "GND")
	)
	(via
		(at 26.0858 -137.414)
		(size 0.5588)
		(drill 0.3048)
		(layers "F.Cu" "B.Cu")
		(net "GND")
	)
	(via
		(at 46.609 -315.341)
		(size 0.7112)
		(drill 0.4064)
		(layers "F.Cu" "B.Cu")
		(net "GND")
	)
	(via
		(at 7.366 -50.927)
		(size 0.7112)
		(drill 0.4064)
		(layers "F.Cu" "B.Cu")
		(net "GND")
	)
	(via
		(at 15.3289 -38.5953)
		(size 0.5588)
		(drill 0.3048)
		(layers "F.Cu" "B.Cu")
		(net "GND")
	)
	(via
		(at 1.166876 -257.429)
		(size 0.7112)
		(drill 0.4064)
		(layers "F.Cu" "B.Cu")
		(net "GND")
	)
	(via
		(at 19.431 -235.458)
		(size 0.7112)
		(drill 0.4064)
		(layers "F.Cu" "B.Cu")
		(net "GND")
	)
	(via
		(at 47.7266 -397.9164)
		(size 0.7112)
		(drill 0.4064)
		(layers "F.Cu" "B.Cu")
		(net "GND")
	)
	(via
		(at 42.4942 -166.0652)
		(size 0.7112)
		(drill 0.4064)
		(layers "F.Cu" "B.Cu")
		(net "GND")
	)
	(via
		(at 34.036 -251.587)
		(size 0.7112)
		(drill 0.4064)
		(layers "F.Cu" "B.Cu")
		(net "GND")
	)
	(via
		(at 1.293876 -70.612)
		(size 0.7112)
		(drill 0.4064)
		(layers "F.Cu" "B.Cu")
		(net "GND")
	)
	(via
		(at 7.112 -251.968)
		(size 0.7112)
		(drill 0.4064)
		(layers "F.Cu" "B.Cu")
		(net "GND")
	)
	(via
		(at 7.493 -13.462)
		(size 0.7112)
		(drill 0.4064)
		(layers "F.Cu" "B.Cu")
		(net "GND")
	)
	(via
		(at 48.9204 -99.7204)
		(size 0.7112)
		(drill 0.4064)
		(layers "F.Cu" "B.Cu")
		(net "GND")
	)
	(via
		(at 8.128 -225.044)
		(size 0.7112)
		(drill 0.4064)
		(layers "F.Cu" "B.Cu")
		(net "GND")
	)
	(via
		(at 3.429 -346.71)
		(size 0.7112)
		(drill 0.4064)
		(layers "F.Cu" "B.Cu")
		(net "GND")
	)
	(via
		(at 50.165 -38.481)
		(size 0.7112)
		(drill 0.4064)
		(layers "F.Cu" "B.Cu")
		(net "GND")
	)
	(via
		(at 27.178 -229.362)
		(size 0.7112)
		(drill 0.4064)
		(layers "F.Cu" "B.Cu")
		(net "GND")
	)
	(via
		(at 39.116 -26.797)
		(size 0.7112)
		(drill 0.4064)
		(layers "F.Cu" "B.Cu")
		(net "GND")
	)
	(via
		(at 45.974 -181.737)
		(size 0.7112)
		(drill 0.4064)
		(layers "F.Cu" "B.Cu")
		(net "GND")
	)
	(via
		(at 6.0452 -104.3178)
		(size 0.7112)
		(drill 0.4064)
		(layers "F.Cu" "B.Cu")
		(net "GND")
	)
	(via
		(at 47.498 -226.314)
		(size 0.7112)
		(drill 0.4064)
		(layers "F.Cu" "B.Cu")
		(net "GND")
	)
	(via
		(at 51.308 -64.516)
		(size 0.7112)
		(drill 0.4064)
		(layers "F.Cu" "B.Cu")
		(net "GND")
	)
	(via
		(at 37.338 -178.562)
		(size 0.5588)
		(drill 0.3048)
		(layers "F.Cu" "B.Cu")
		(net "GND")
	)
	(via
		(at 49.53 -269.494)
		(size 0.7112)
		(drill 0.4064)
		(layers "F.Cu" "B.Cu")
		(net "GND")
	)
	(via
		(at 16.129 -498.602)
		(size 0.7112)
		(drill 0.4064)
		(layers "F.Cu" "B.Cu")
		(net "GND")
	)
	(via
		(at 45.9994 -92.4687)
		(size 0.7112)
		(drill 0.4064)
		(layers "F.Cu" "B.Cu")
		(net "GND")
	)
	(via
		(at 46.228 -261.493)
		(size 0.7112)
		(drill 0.4064)
		(layers "F.Cu" "B.Cu")
		(net "GND")
	)
	(via
		(at 29.2608 -199.1868)
		(size 0.7112)
		(drill 0.4064)
		(layers "F.Cu" "B.Cu")
		(net "GND")
	)
	(via
		(at 4.064 -295.148)
		(size 0.7112)
		(drill 0.4064)
		(layers "F.Cu" "B.Cu")
		(net "GND")
	)
	(via
		(at 13.843 -479.933)
		(size 0.7112)
		(drill 0.4064)
		(layers "F.Cu" "B.Cu")
		(net "GND")
	)
	(via
		(at 39.116 -90.297)
		(size 0.7112)
		(drill 0.3556)
		(layers "F.Cu" "B.Cu")
		(net "GND")
	)
	(via
		(at 11.557 -473.71)
		(size 0.7112)
		(drill 0.4064)
		(layers "F.Cu" "B.Cu")
		(net "GND")
	)
	(via
		(at 45.847 -159.453834)
		(size 0.7112)
		(drill 0.4064)
		(layers "F.Cu" "B.Cu")
		(net "GND")
	)
	(via
		(at 19.05 -17.145)
		(size 0.5588)
		(drill 0.3048)
		(layers "F.Cu" "B.Cu")
		(net "GND")
	)
	(via
		(at 3.81 -33.401)
		(size 0.7112)
		(drill 0.4064)
		(layers "F.Cu" "B.Cu")
		(net "GND")
	)
	(via
		(at 15.875 -234.823)
		(size 0.7112)
		(drill 0.4064)
		(layers "F.Cu" "B.Cu")
		(net "GND")
	)
	(via
		(at 13.335 -347.599)
		(size 0.7112)
		(drill 0.4064)
		(layers "F.Cu" "B.Cu")
		(net "GND")
	)
	(via
		(at 37.211 -33.492186)
		(size 0.7112)
		(drill 0.4064)
		(layers "F.Cu" "B.Cu")
		(net "GND")
	)
	(via
		(at 18.796 -287.528)
		(size 0.7112)
		(drill 0.4064)
		(layers "F.Cu" "B.Cu")
		(net "GND")
	)
	(via
		(at 1.166876 -351.028)
		(size 0.7112)
		(drill 0.4064)
		(layers "F.Cu" "B.Cu")
		(net "GND")
	)
	(via
		(at 37.465 -327.152)
		(size 0.7112)
		(drill 0.4064)
		(layers "F.Cu" "B.Cu")
		(net "GND")
	)
	(via
		(at 10.795 -424.942)
		(size 0.5588)
		(drill 0.3048)
		(layers "F.Cu" "B.Cu")
		(net "GND")
	)
	(via
		(at 1.524 -179.451)
		(size 0.7112)
		(drill 0.4064)
		(layers "F.Cu" "B.Cu")
		(net "GND")
	)
	(via
		(at 19.8882 -211.4804)
		(size 0.7112)
		(drill 0.4064)
		(layers "F.Cu" "B.Cu")
		(net "GND")
	)
	(via
		(at 28.321 -99.06)
		(size 0.7112)
		(drill 0.4064)
		(layers "F.Cu" "B.Cu")
		(net "GND")
	)
	(via
		(at 28.067 -266.954)
		(size 0.7112)
		(drill 0.4064)
		(layers "F.Cu" "B.Cu")
		(net "GND")
	)
	(via
		(at 13.208 -329.2602)
		(size 0.7112)
		(drill 0.4064)
		(layers "F.Cu" "B.Cu")
		(net "GND")
	)
	(via
		(at 39.116 -19.177)
		(size 0.7112)
		(drill 0.4064)
		(layers "F.Cu" "B.Cu")
		(net "GND")
	)
	(via
		(at 51.181 -143.256)
		(size 0.7112)
		(drill 0.4064)
		(layers "F.Cu" "B.Cu")
		(net "GND")
	)
	(via
		(at 12.7 -334.772)
		(size 0.7112)
		(drill 0.4064)
		(layers "F.Cu" "B.Cu")
		(net "GND")
	)
	(via
		(at 24.638 -381.7874)
		(size 0.7112)
		(drill 0.4064)
		(layers "F.Cu" "B.Cu")
		(net "GND")
	)
	(via
		(at 1.420876 -13.589)
		(size 0.7112)
		(drill 0.4064)
		(layers "F.Cu" "B.Cu")
		(net "GND")
	)
	(via
		(at 48.387 -488.696)
		(size 0.7112)
		(drill 0.4064)
		(layers "F.Cu" "B.Cu")
		(net "GND")
	)
	(via
		(at 28.708096 -368.828066)
		(size 0.7112)
		(drill 0.4064)
		(layers "F.Cu" "B.Cu")
		(net "GND")
	)
	(via
		(at 13.335 -446.024)
		(size 0.5588)
		(drill 0.3048)
		(layers "F.Cu" "B.Cu")
		(net "GND")
	)
	(via
		(at 21.717 -232.41)
		(size 0.7112)
		(drill 0.4064)
		(layers "F.Cu" "B.Cu")
		(net "GND")
	)
	(via
		(at 36.0172 -142.0495)
		(size 0.7112)
		(drill 0.4064)
		(layers "F.Cu" "B.Cu")
		(net "GND")
	)
	(via
		(at 51.308 -171.831)
		(size 0.7112)
		(drill 0.4064)
		(layers "F.Cu" "B.Cu")
		(net "GND")
	)
	(via
		(at 20.066 -364.8456)
		(size 0.7112)
		(drill 0.4064)
		(layers "F.Cu" "B.Cu")
		(net "GND")
	)
	(via
		(at 23.368 -329.057)
		(size 0.7112)
		(drill 0.4064)
		(layers "F.Cu" "B.Cu")
		(net "GND")
	)
	(via
		(at 51.076606 -144.9324)
		(size 0.7112)
		(drill 0.4064)
		(layers "F.Cu" "B.Cu")
		(net "GND")
	)
	(via
		(at 10.541 -429.768)
		(size 0.5588)
		(drill 0.3048)
		(layers "F.Cu" "B.Cu")
		(net "GND")
	)
	(via
		(at 19.8882 -227.0506)
		(size 0.7112)
		(drill 0.4064)
		(layers "F.Cu" "B.Cu")
		(net "GND")
	)
	(via
		(at 1.166876 -444.754)
		(size 0.7112)
		(drill 0.4064)
		(layers "F.Cu" "B.Cu")
		(net "GND")
	)
	(via
		(at 41.91 -321.183)
		(size 0.7112)
		(drill 0.4064)
		(layers "F.Cu" "B.Cu")
		(net "GND")
	)
	(via
		(at 8.509 -244.475)
		(size 0.7112)
		(drill 0.4064)
		(layers "F.Cu" "B.Cu")
		(net "GND")
	)
	(via
		(at 28.829 -189.738)
		(size 0.5588)
		(drill 0.3048)
		(layers "F.Cu" "B.Cu")
		(net "GND")
	)
	(via
		(at 41.8973 -156.3878)
		(size 0.7112)
		(drill 0.4064)
		(layers "F.Cu" "B.Cu")
		(net "GND")
	)
	(via
		(at 30.861 -199.009)
		(size 0.7112)
		(drill 0.4064)
		(layers "F.Cu" "B.Cu")
		(net "GND")
	)
	(via
		(at 17.78 -235.077)
		(size 0.7112)
		(drill 0.4064)
		(layers "F.Cu" "B.Cu")
		(net "GND")
	)
	(via
		(at 6.7564 -398.8054)
		(size 0.7112)
		(drill 0.4064)
		(layers "F.Cu" "B.Cu")
		(net "GND")
	)
	(via
		(at 49.911 -162.941)
		(size 0.7112)
		(drill 0.4064)
		(layers "F.Cu" "B.Cu")
		(net "GND")
	)
	(via
		(at 49.911 -202.438)
		(size 0.7112)
		(drill 0.4064)
		(layers "F.Cu" "B.Cu")
		(net "GND")
	)
	(via
		(at 45.974 -185.166)
		(size 0.7112)
		(drill 0.4064)
		(layers "F.Cu" "B.Cu")
		(net "GND")
	)
	(via
		(at 31.75 -190.754)
		(size 0.7112)
		(drill 0.4064)
		(layers "F.Cu" "B.Cu")
		(net "GND")
	)
	(via
		(at 50.8 -35.56)
		(size 0.7112)
		(drill 0.4064)
		(layers "F.Cu" "B.Cu")
		(net "GND")
	)
	(via
		(at 28.2448 -108.3056)
		(size 0.7112)
		(drill 0.4064)
		(layers "F.Cu" "B.Cu")
		(net "GND")
	)
	(via
		(at 31.496 -18.923)
		(size 0.7112)
		(drill 0.4064)
		(layers "F.Cu" "B.Cu")
		(net "GND")
	)
	(via
		(at 50.419 -402.336)
		(size 0.7112)
		(drill 0.4064)
		(layers "F.Cu" "B.Cu")
		(net "GND")
	)
	(via
		(at 33.909 -372.6434)
		(size 0.7112)
		(drill 0.4064)
		(layers "F.Cu" "B.Cu")
		(net "GND")
	)
	(via
		(at 1.166876 -429.514)
		(size 0.7112)
		(drill 0.4064)
		(layers "F.Cu" "B.Cu")
		(net "GND")
	)
	(via
		(at 42.672 -210.82)
		(size 0.5588)
		(drill 0.3048)
		(layers "F.Cu" "B.Cu")
		(net "GND")
	)
	(via
		(at 31.242 -205.359)
		(size 0.7112)
		(drill 0.4064)
		(layers "F.Cu" "B.Cu")
		(net "GND")
	)
	(via
		(at 49.53 -11.43)
		(size 0.7112)
		(drill 0.4064)
		(layers "F.Cu" "B.Cu")
		(net "GND")
	)
	(via
		(at 42.291 -456.692)
		(size 0.7112)
		(drill 0.4064)
		(layers "F.Cu" "B.Cu")
		(net "GND")
	)
	(via
		(at 10.668 -203.708)
		(size 0.7112)
		(drill 0.4064)
		(layers "F.Cu" "B.Cu")
		(net "GND")
	)
	(via
		(at 3.937 -36.449)
		(size 0.7112)
		(drill 0.4064)
		(layers "F.Cu" "B.Cu")
		(net "GND")
	)
	(via
		(at 5.969 -31.496)
		(size 0.7112)
		(drill 0.4064)
		(layers "F.Cu" "B.Cu")
		(net "GND")
	)
	(via
		(at 30.099 -296.164)
		(size 0.7112)
		(drill 0.4064)
		(layers "F.Cu" "B.Cu")
		(net "GND")
	)
	(via
		(at 7.62 -439.674)
		(size 0.7112)
		(drill 0.4064)
		(layers "F.Cu" "B.Cu")
		(net "GND")
	)
	(via
		(at 30.3022 -302.6156)
		(size 0.7112)
		(drill 0.4064)
		(layers "F.Cu" "B.Cu")
		(net "GND")
	)
	(via
		(at 48.887634 -100.92817)
		(size 0.7112)
		(drill 0.4064)
		(layers "F.Cu" "B.Cu")
		(net "GND")
	)
	(via
		(at 38.481 -470.18194)
		(size 0.7112)
		(drill 0.4064)
		(layers "F.Cu" "B.Cu")
		(net "GND")
	)
	(via
		(at 6.096 -214.884)
		(size 0.7112)
		(drill 0.4064)
		(layers "F.Cu" "B.Cu")
		(net "GND")
	)
	(via
		(at 12.4714 -367.8936)
		(size 0.7112)
		(drill 0.4064)
		(layers "F.Cu" "B.Cu")
		(net "GND")
	)
	(via
		(at 42.9514 -183.4134)
		(size 0.7112)
		(drill 0.4064)
		(layers "F.Cu" "B.Cu")
		(net "GND")
	)
	(via
		(at 31.496 -246.761)
		(size 0.7112)
		(drill 0.4064)
		(layers "F.Cu" "B.Cu")
		(net "GND")
	)
	(via
		(at 21.2852 -353.5426)
		(size 0.7112)
		(drill 0.4064)
		(layers "F.Cu" "B.Cu")
		(net "GND")
	)
	(via
		(at 51.308 -154.305)
		(size 0.7112)
		(drill 0.4064)
		(layers "F.Cu" "B.Cu")
		(net "GND")
	)
	(via
		(at 48.387 -139.827)
		(size 0.7112)
		(drill 0.4064)
		(layers "F.Cu" "B.Cu")
		(net "GND")
	)
	(via
		(at 51.308 -263.398)
		(size 0.5588)
		(drill 0.3048)
		(layers "F.Cu" "B.Cu")
		(net "GND")
	)
	(via
		(at 5.461 -61.341)
		(size 0.7112)
		(drill 0.4064)
		(layers "F.Cu" "B.Cu")
		(net "GND")
	)
	(via
		(at 26.67 -36.322)
		(size 0.7112)
		(drill 0.4064)
		(layers "F.Cu" "B.Cu")
		(net "GND")
	)
	(via
		(at 32.8168 -210.9216)
		(size 0.7112)
		(drill 0.4064)
		(layers "F.Cu" "B.Cu")
		(net "GND")
	)
	(via
		(at 8.001 -310.388)
		(size 0.7112)
		(drill 0.4064)
		(layers "F.Cu" "B.Cu")
		(net "GND")
	)
	(via
		(at 45.085 -209.931)
		(size 0.7112)
		(drill 0.4064)
		(layers "F.Cu" "B.Cu")
		(net "GND")
	)
	(via
		(at 51.181 -135.89)
		(size 0.7112)
		(drill 0.4064)
		(layers "F.Cu" "B.Cu")
		(net "GND")
	)
	(via
		(at 5.8674 -86.9696)
		(size 0.5588)
		(drill 0.3048)
		(layers "F.Cu" "B.Cu")
		(net "GND")
	)
	(via
		(at 44.264072 -431.06594)
		(size 0.7112)
		(drill 0.4064)
		(layers "F.Cu" "B.Cu")
		(net "GND")
	)
	(via
		(at 8.001 -354.965)
		(size 0.7112)
		(drill 0.4064)
		(layers "F.Cu" "B.Cu")
		(net "GND")
	)
	(via
		(at 20.2946 -488.442)
		(size 0.5588)
		(drill 0.3048)
		(layers "F.Cu" "B.Cu")
		(net "GND")
	)
	(via
		(at 6.998462 -261.428738)
		(size 0.7112)
		(drill 0.4064)
		(layers "F.Cu" "B.Cu")
		(net "GND")
	)
	(via
		(at 48.768 -402.844)
		(size 0.7112)
		(drill 0.4064)
		(layers "F.Cu" "B.Cu")
		(net "GND")
	)
	(via
		(at 28.956 -349.504)
		(size 0.7112)
		(drill 0.4064)
		(layers "F.Cu" "B.Cu")
		(net "GND")
	)
	(via
		(at 22.1488 -363.7026)
		(size 0.7112)
		(drill 0.4064)
		(layers "F.Cu" "B.Cu")
		(net "GND")
	)
	(via
		(at 29.591 -273.304)
		(size 0.7112)
		(drill 0.4064)
		(layers "F.Cu" "B.Cu")
		(net "GND")
	)
	(via
		(at 38.608 -438.30494)
		(size 0.7112)
		(drill 0.4064)
		(layers "F.Cu" "B.Cu")
		(net "GND")
	)
	(via
		(at 13.8684 -145.6436)
		(size 0.5588)
		(drill 0.3048)
		(layers "F.Cu" "B.Cu")
		(net "GND")
	)
	(via
		(at 44.010072 -451.104)
		(size 0.7112)
		(drill 0.4064)
		(layers "F.Cu" "B.Cu")
		(net "GND")
	)
	(via
		(at 3.556 -275.844)
		(size 0.7112)
		(drill 0.4064)
		(layers "F.Cu" "B.Cu")
		(net "GND")
	)
	(via
		(at 8.763 -498.6528)
		(size 0.7112)
		(drill 0.4064)
		(layers "F.Cu" "B.Cu")
		(net "GND")
	)
	(via
		(at 5.0292 -334.1116)
		(size 0.7112)
		(drill 0.4064)
		(layers "F.Cu" "B.Cu")
		(net "GND")
	)
	(via
		(at 45.847 -28.448)
		(size 0.7112)
		(drill 0.4064)
		(layers "F.Cu" "B.Cu")
		(net "GND")
	)
	(via
		(at 34.29 -226.822)
		(size 0.7112)
		(drill 0.4064)
		(layers "F.Cu" "B.Cu")
		(net "GND")
	)
	(via
		(at 46.863 -179.959)
		(size 0.7112)
		(drill 0.4064)
		(layers "F.Cu" "B.Cu")
		(net "GND")
	)
	(via
		(at 51.0794 -484.8352)
		(size 0.5588)
		(drill 0.3048)
		(layers "F.Cu" "B.Cu")
		(net "GND")
	)
	(via
		(at 6.1468 -466.5218)
		(size 0.7112)
		(drill 0.4064)
		(layers "F.Cu" "B.Cu")
		(net "GND")
	)
	(via
		(at 25.273 -332.74)
		(size 0.7112)
		(drill 0.4064)
		(layers "F.Cu" "B.Cu")
		(net "GND")
	)
	(via
		(at 28.829 -201.295)
		(size 0.7112)
		(drill 0.4064)
		(layers "F.Cu" "B.Cu")
		(net "GND")
	)
	(via
		(at 30.353 -306.197)
		(size 0.7112)
		(drill 0.4064)
		(layers "F.Cu" "B.Cu")
		(net "GND")
	)
	(via
		(at 21.082 -248.8692)
		(size 0.5588)
		(drill 0.3048)
		(layers "F.Cu" "B.Cu")
		(net "GND")
	)
	(via
		(at 32.7406 -488.5182)
		(size 0.5588)
		(drill 0.3048)
		(layers "F.Cu" "B.Cu")
		(net "GND")
	)
	(via
		(at 38.989 -262.509)
		(size 0.5588)
		(drill 0.3048)
		(layers "F.Cu" "B.Cu")
		(net "GND")
	)
	(via
		(at 32.893 -198.628)
		(size 0.7112)
		(drill 0.4064)
		(layers "F.Cu" "B.Cu")
		(net "GND")
	)
	(via
		(at 29.21 -196.3928)
		(size 0.7112)
		(drill 0.4064)
		(layers "F.Cu" "B.Cu")
		(net "GND")
	)
	(via
		(at 4.7244 -475.3356)
		(size 0.7112)
		(drill 0.4064)
		(layers "F.Cu" "B.Cu")
		(net "GND")
	)
	(via
		(at 51.435 -299.466)
		(size 0.5588)
		(drill 0.3048)
		(layers "F.Cu" "B.Cu")
		(net "GND")
	)
	(via
		(at 26.289 -312.166)
		(size 0.7112)
		(drill 0.4064)
		(layers "F.Cu" "B.Cu")
		(net "GND")
	)
	(via
		(at 16.152876 -6.477)
		(size 0.7112)
		(drill 0.4064)
		(layers "F.Cu" "B.Cu")
		(net "GND")
	)
	(via
		(at 46.228 -241.427)
		(size 0.7112)
		(drill 0.4064)
		(layers "F.Cu" "B.Cu")
		(net "GND")
	)
	(via
		(at 30.226 -247.65)
		(size 0.7112)
		(drill 0.4064)
		(layers "F.Cu" "B.Cu")
		(net "GND")
	)
	(via
		(at 51.181 -398.526)
		(size 0.5588)
		(drill 0.3048)
		(layers "F.Cu" "B.Cu")
		(net "GND")
	)
	(via
		(at 26.416 -269.875)
		(size 0.5588)
		(drill 0.3048)
		(layers "F.Cu" "B.Cu")
		(net "GND")
	)
	(via
		(at 45.6946 -228.8286)
		(size 0.5588)
		(drill 0.3048)
		(layers "F.Cu" "B.Cu")
		(net "GND")
	)
	(via
		(at 19.558 -221.361)
		(size 0.7112)
		(drill 0.4064)
		(layers "F.Cu" "B.Cu")
		(net "GND")
	)
	(via
		(at 49.657 -483.87)
		(size 0.7112)
		(drill 0.4064)
		(layers "F.Cu" "B.Cu")
		(net "GND")
	)
	(via
		(at 41.9862 -36.8808)
		(size 0.7112)
		(drill 0.4064)
		(layers "F.Cu" "B.Cu")
		(net "GND")
	)
	(via
		(at 7.5438 -48.6156)
		(size 0.7112)
		(drill 0.4064)
		(layers "F.Cu" "B.Cu")
		(net "GND")
	)
	(via
		(at 34.163 -213.487)
		(size 0.7112)
		(drill 0.4064)
		(layers "F.Cu" "B.Cu")
		(net "GND")
	)
	(via
		(at 11.8618 -471.8558)
		(size 0.7112)
		(drill 0.4064)
		(layers "F.Cu" "B.Cu")
		(net "GND")
	)
	(via
		(at 1.293876 -272.923)
		(size 0.7112)
		(drill 0.4064)
		(layers "F.Cu" "B.Cu")
		(net "GND")
	)
	(via
		(at 7.112 -179.324)
		(size 0.7112)
		(drill 0.4064)
		(layers "F.Cu" "B.Cu")
		(net "GND")
	)
	(via
		(at 1.27 -123.571)
		(size 0.7112)
		(drill 0.4064)
		(layers "F.Cu" "B.Cu")
		(net "GND")
	)
	(via
		(at 24.8412 -337.2866)
		(size 0.7112)
		(drill 0.4064)
		(layers "F.Cu" "B.Cu")
		(net "GND")
	)
	(via
		(at 44.4754 -180.34)
		(size 0.5588)
		(drill 0.3048)
		(layers "F.Cu" "B.Cu")
		(net "GND")
	)
	(via
		(at 1.347216 -357.9876)
		(size 0.7112)
		(drill 0.4064)
		(layers "F.Cu" "B.Cu")
		(net "GND")
	)
	(via
		(at 6.858 -46.228)
		(size 0.7112)
		(drill 0.4064)
		(layers "F.Cu" "B.Cu")
		(net "GND")
	)
	(via
		(at 14.351 -238.76)
		(size 0.7112)
		(drill 0.4064)
		(layers "F.Cu" "B.Cu")
		(net "GND")
	)
	(via
		(at 48.7426 -136.7028)
		(size 0.7112)
		(drill 0.4064)
		(layers "F.Cu" "B.Cu")
		(net "GND")
	)
	(via
		(at 30.353 -187.833)
		(size 0.5588)
		(drill 0.3048)
		(layers "F.Cu" "B.Cu")
		(net "GND")
	)
	(via
		(at 6.858 -98.933)
		(size 0.7112)
		(drill 0.4064)
		(layers "F.Cu" "B.Cu")
		(net "GND")
	)
	(via
		(at 41.0464 -187.9092)
		(size 0.5588)
		(drill 0.3048)
		(layers "F.Cu" "B.Cu")
		(net "GND")
	)
	(via
		(at 20.077176 -290.604448)
		(size 0.7112)
		(drill 0.4064)
		(layers "F.Cu" "B.Cu")
		(net "GND")
	)
	(via
		(at 10.4394 -497.205)
		(size 0.7112)
		(drill 0.4064)
		(layers "F.Cu" "B.Cu")
		(net "GND")
	)
	(via
		(at 3.429 -74.93)
		(size 0.7112)
		(drill 0.4064)
		(layers "F.Cu" "B.Cu")
		(net "GND")
	)
	(via
		(at 41.148 -454.66)
		(size 0.7112)
		(drill 0.4064)
		(layers "F.Cu" "B.Cu")
		(net "GND")
	)
	(via
		(at 12.7 -315.976)
		(size 0.7112)
		(drill 0.4064)
		(layers "F.Cu" "B.Cu")
		(net "GND")
	)
	(via
		(at 45.974 -266.954)
		(size 0.7112)
		(drill 0.4064)
		(layers "F.Cu" "B.Cu")
		(net "GND")
	)
	(via
		(at 6.604 -166.751)
		(size 0.7112)
		(drill 0.4064)
		(layers "F.Cu" "B.Cu")
		(net "GND")
	)
	(via
		(at 27.178 -108.331)
		(size 0.7112)
		(drill 0.4064)
		(layers "F.Cu" "B.Cu")
		(net "GND")
	)
	(via
		(at 22.098 -213.233)
		(size 0.7112)
		(drill 0.4064)
		(layers "F.Cu" "B.Cu")
		(net "GND")
	)
	(via
		(at 51.076606 -77.597)
		(size 0.7112)
		(drill 0.4064)
		(layers "F.Cu" "B.Cu")
		(net "GND")
	)
	(via
		(at 41.91 -11.43)
		(size 0.7112)
		(drill 0.4064)
		(layers "F.Cu" "B.Cu")
		(net "GND")
	)
	(via
		(at 37.084 -202.311)
		(size 0.5588)
		(drill 0.3048)
		(layers "F.Cu" "B.Cu")
		(net "GND")
	)
	(via
		(at 31.877 -239.776)
		(size 0.7112)
		(drill 0.4064)
		(layers "F.Cu" "B.Cu")
		(net "GND")
	)
	(via
		(at 1.420876 -38.989)
		(size 0.7112)
		(drill 0.4064)
		(layers "F.Cu" "B.Cu")
		(net "GND")
	)
	(via
		(at 6.6294 -276.5044)
		(size 0.7112)
		(drill 0.4064)
		(layers "F.Cu" "B.Cu")
		(net "GND")
	)
	(via
		(at 31.496 -349.631)
		(size 0.7112)
		(drill 0.4064)
		(layers "F.Cu" "B.Cu")
		(net "GND")
	)
	(via
		(at 15.4686 -353.187)
		(size 0.7112)
		(drill 0.4064)
		(layers "F.Cu" "B.Cu")
		(net "GND")
	)
	(via
		(at 44.704 -258.699)
		(size 0.7112)
		(drill 0.4064)
		(layers "F.Cu" "B.Cu")
		(net "GND")
	)
	(via
		(at 18.796 -11.43)
		(size 0.7112)
		(drill 0.4064)
		(layers "F.Cu" "B.Cu")
		(net "GND")
	)
	(via
		(at 50.546 -411.353)
		(size 0.7112)
		(drill 0.4064)
		(layers "F.Cu" "B.Cu")
		(net "GND")
	)
	(via
		(at 30.734 -147.701)
		(size 0.5588)
		(drill 0.3048)
		(layers "F.Cu" "B.Cu")
		(net "GND")
	)
	(via
		(at 4.572 -237.236)
		(size 0.7112)
		(drill 0.4064)
		(layers "F.Cu" "B.Cu")
		(net "GND")
	)
	(via
		(at 48.7426 -62.1284)
		(size 0.7112)
		(drill 0.4064)
		(layers "F.Cu" "B.Cu")
		(net "GND")
	)
	(via
		(at 48.768 -237.363)
		(size 0.7112)
		(drill 0.4064)
		(layers "F.Cu" "B.Cu")
		(net "GND")
	)
	(via
		(at 4.699 -227.711)
		(size 0.7112)
		(drill 0.4064)
		(layers "F.Cu" "B.Cu")
		(net "GND")
	)
	(via
		(at 42.418 -23.622)
		(size 0.7112)
		(drill 0.4064)
		(layers "F.Cu" "B.Cu")
		(net "GND")
	)
	(via
		(at 8.9662 -489.0262)
		(size 0.7112)
		(drill 0.4064)
		(layers "F.Cu" "B.Cu")
		(net "GND")
	)
	(via
		(at 18.669 -37.084)
		(size 0.7112)
		(drill 0.4064)
		(layers "F.Cu" "B.Cu")
		(net "GND")
	)
	(via
		(at 51.308 -86.36)
		(size 0.7112)
		(drill 0.4064)
		(layers "F.Cu" "B.Cu")
		(net "GND")
	)
	(via
		(at 46.863 -219.837)
		(size 0.7112)
		(drill 0.4064)
		(layers "F.Cu" "B.Cu")
		(net "GND")
	)
	(via
		(at 50.292 -461.899)
		(size 0.7112)
		(drill 0.4064)
		(layers "F.Cu" "B.Cu")
		(net "GND")
	)
	(via
		(at 47.625 -33.147)
		(size 0.7112)
		(drill 0.4064)
		(layers "F.Cu" "B.Cu")
		(net "GND")
	)
	(via
		(at 42.799 -433.07)
		(size 0.7112)
		(drill 0.4064)
		(layers "F.Cu" "B.Cu")
		(net "GND")
	)
	(via
		(at 39.751 -225.806)
		(size 0.7112)
		(drill 0.4064)
		(layers "F.Cu" "B.Cu")
		(net "GND")
	)
	(via
		(at 10.033 -357.6066)
		(size 0.7112)
		(drill 0.4064)
		(layers "F.Cu" "B.Cu")
		(net "GND")
	)
	(via
		(at 7.62 -198.628)
		(size 0.7112)
		(drill 0.4064)
		(layers "F.Cu" "B.Cu")
		(net "GND")
	)
	(via
		(at 40.1066 -488.4674)
		(size 0.5588)
		(drill 0.3048)
		(layers "F.Cu" "B.Cu")
		(net "GND")
	)
	(via
		(at 6.858 -97.536)
		(size 0.7112)
		(drill 0.4064)
		(layers "F.Cu" "B.Cu")
		(net "GND")
	)
	(via
		(at 3.175 -452.755)
		(size 0.7112)
		(drill 0.4064)
		(layers "F.Cu" "B.Cu")
		(net "GND")
	)
	(via
		(at 49.149 -264.795)
		(size 0.7112)
		(drill 0.4064)
		(layers "F.Cu" "B.Cu")
		(net "GND")
	)
	(via
		(at 4.064 -210.312)
		(size 0.7112)
		(drill 0.4064)
		(layers "F.Cu" "B.Cu")
		(net "GND")
	)
	(via
		(at 37.846 -171.958)
		(size 0.5588)
		(drill 0.3048)
		(layers "F.Cu" "B.Cu")
		(net "GND")
	)
	(via
		(at 8.4328 -119.1006)
		(size 0.5588)
		(drill 0.3048)
		(layers "F.Cu" "B.Cu")
		(net "GND")
	)
	(via
		(at 4.572 -220.98)
		(size 0.7112)
		(drill 0.4064)
		(layers "F.Cu" "B.Cu")
		(net "GND")
	)
	(via
		(at 1.166876 -181.356)
		(size 0.5588)
		(drill 0.3048)
		(layers "F.Cu" "B.Cu")
		(net "GND")
	)
	(via
		(at 39.497 -456.819)
		(size 0.7112)
		(drill 0.4064)
		(layers "F.Cu" "B.Cu")
		(net "GND")
	)
	(via
		(at 3.175 -67.691)
		(size 0.7112)
		(drill 0.4064)
		(layers "F.Cu" "B.Cu")
		(net "GND")
	)
	(via
		(at 31.4452 -326.1106)
		(size 0.7112)
		(drill 0.4064)
		(layers "F.Cu" "B.Cu")
		(net "GND")
	)
	(via
		(at 51.152806 -362.077)
		(size 0.5588)
		(drill 0.3048)
		(layers "F.Cu" "B.Cu")
		(net "GND")
	)
	(via
		(at 21.3868 -163.54171)
		(size 0.5588)
		(drill 0.3048)
		(layers "F.Cu" "B.Cu")
		(net "GND")
	)
	(via
		(at 48.133 -30.48)
		(size 0.7112)
		(drill 0.4064)
		(layers "F.Cu" "B.Cu")
		(net "GND")
	)
	(via
		(at 31.369 -213.995)
		(size 0.7112)
		(drill 0.4064)
		(layers "F.Cu" "B.Cu")
		(net "GND")
	)
	(via
		(at 4.064 -254)
		(size 0.7112)
		(drill 0.4064)
		(layers "F.Cu" "B.Cu")
		(net "GND")
	)
	(via
		(at 31.496 -329.692)
		(size 0.7112)
		(drill 0.4064)
		(layers "F.Cu" "B.Cu")
		(net "GND")
	)
	(via
		(at 29.972 -13.843)
		(size 0.7112)
		(drill 0.4064)
		(layers "F.Cu" "B.Cu")
		(net "GND")
	)
	(via
		(at 7.112 -330.2)
		(size 0.7112)
		(drill 0.4064)
		(layers "F.Cu" "B.Cu")
		(net "GND")
	)
	(via
		(at 13.462 -444.627)
		(size 0.7112)
		(drill 0.4064)
		(layers "F.Cu" "B.Cu")
		(net "GND")
	)
	(via
		(at 2.54 -206.121)
		(size 0.7112)
		(drill 0.4064)
		(layers "F.Cu" "B.Cu")
		(net "GND")
	)
	(via
		(at 1.651 -498.348)
		(size 0.7112)
		(drill 0.4064)
		(layers "F.Cu" "B.Cu")
		(net "GND")
	)
	(via
		(at 44.704 -169.037)
		(size 0.7112)
		(drill 0.4064)
		(layers "F.Cu" "B.Cu")
		(net "GND")
	)
	(via
		(at 25.146 -321.437)
		(size 0.7112)
		(drill 0.4064)
		(layers "F.Cu" "B.Cu")
		(net "GND")
	)
	(via
		(at 28.829 -186.944)
		(size 0.5588)
		(drill 0.3048)
		(layers "F.Cu" "B.Cu")
		(net "GND")
	)
	(via
		(at 40.259 -433.07)
		(size 0.7112)
		(drill 0.4064)
		(layers "F.Cu" "B.Cu")
		(net "GND")
	)
	(via
		(at 31.115 -201.295)
		(size 0.7112)
		(drill 0.4064)
		(layers "F.Cu" "B.Cu")
		(net "GND")
	)
	(via
		(at 45.847 -247.1928)
		(size 0.5588)
		(drill 0.3048)
		(layers "F.Cu" "B.Cu")
		(net "GND")
	)
	(via
		(at 13.081 -13.462)
		(size 0.7112)
		(drill 0.4064)
		(layers "F.Cu" "B.Cu")
		(net "GND")
	)
	(via
		(at 24.13 -11.43)
		(size 0.7112)
		(drill 0.4064)
		(layers "F.Cu" "B.Cu")
		(net "GND")
	)
	(via
		(at 23.114 -323.215)
		(size 0.7112)
		(drill 0.3556)
		(layers "F.Cu" "B.Cu")
		(net "GND")
	)
	(via
		(at 42.164 -274.32)
		(size 0.7112)
		(drill 0.4064)
		(layers "F.Cu" "B.Cu")
		(net "GND")
	)
	(via
		(at 12.4206 -353.187)
		(size 0.7112)
		(drill 0.4064)
		(layers "F.Cu" "B.Cu")
		(net "GND")
	)
	(via
		(at 4.572 -183.896)
		(size 0.7112)
		(drill 0.4064)
		(layers "F.Cu" "B.Cu")
		(net "GND")
	)
	(via
		(at 9.6266 -398.78)
		(size 0.7112)
		(drill 0.4064)
		(layers "F.Cu" "B.Cu")
		(net "GND")
	)
	(via
		(at 34.417 -230.886)
		(size 0.7112)
		(drill 0.4064)
		(layers "F.Cu" "B.Cu")
		(net "GND")
	)
	(via
		(at 12.6238 -144.5006)
		(size 0.5588)
		(drill 0.3048)
		(layers "F.Cu" "B.Cu")
		(net "GND")
	)
	(via
		(at 28.9052 -327.1266)
		(size 0.7112)
		(drill 0.4064)
		(layers "F.Cu" "B.Cu")
		(net "GND")
	)
	(via
		(at 22.24913 -147.6502)
		(size 0.7112)
		(drill 0.4064)
		(layers "F.Cu" "B.Cu")
		(net "GND")
	)
	(via
		(at 49.276 -230.378)
		(size 0.7112)
		(drill 0.4064)
		(layers "F.Cu" "B.Cu")
		(net "GND")
	)
	(via
		(at 15.621 -238.379)
		(size 0.7112)
		(drill 0.4064)
		(layers "F.Cu" "B.Cu")
		(net "GND")
	)
	(via
		(at 47.7266 -199.4662)
		(size 0.7112)
		(drill 0.4064)
		(layers "F.Cu" "B.Cu")
		(net "GND")
	)
	(via
		(at 26.67 -13.97)
		(size 0.7112)
		(drill 0.4064)
		(layers "F.Cu" "B.Cu")
		(net "GND")
	)
	(via
		(at 29.972 -488.188)
		(size 0.7112)
		(drill 0.4064)
		(layers "F.Cu" "B.Cu")
		(net "GND")
	)
	(via
		(at 7.493 -379.9332)
		(size 0.7112)
		(drill 0.4064)
		(layers "F.Cu" "B.Cu")
		(net "GND")
	)
	(via
		(at 1.397 -68.453)
		(size 0.7112)
		(drill 0.4064)
		(layers "F.Cu" "B.Cu")
		(net "GND")
	)
	(via
		(at 40.5638 -165.608)
		(size 0.7112)
		(drill 0.4064)
		(layers "F.Cu" "B.Cu")
		(net "GND")
	)
	(via
		(at 12.7 -180.975)
		(size 0.7112)
		(drill 0.4064)
		(layers "F.Cu" "B.Cu")
		(net "GND")
	)
	(via
		(at 51.36134 -394.716)
		(size 0.5588)
		(drill 0.3048)
		(layers "F.Cu" "B.Cu")
		(net "GND")
	)
	(via
		(at 37.084 -226.822)
		(size 0.7112)
		(drill 0.4064)
		(layers "F.Cu" "B.Cu")
		(net "GND")
	)
	(via
		(at 51.076606 -98.6536)
		(size 0.7112)
		(drill 0.4064)
		(layers "F.Cu" "B.Cu")
		(net "GND")
	)
	(via
		(at 9.271 -482.727)
		(size 0.7112)
		(drill 0.4064)
		(layers "F.Cu" "B.Cu")
		(net "GND")
	)
	(via
		(at 33.909 -484.251)
		(size 0.5588)
		(drill 0.3048)
		(layers "F.Cu" "B.Cu")
		(net "GND")
	)
	(via
		(at 41.4274 -248.5644)
		(size 0.5588)
		(drill 0.3048)
		(layers "F.Cu" "B.Cu")
		(net "GND")
	)
	(via
		(at 42.418 -33.147)
		(size 0.7112)
		(drill 0.4064)
		(layers "F.Cu" "B.Cu")
		(net "GND")
	)
	(via
		(at 26.1874 -149.2504)
		(size 0.7112)
		(drill 0.4064)
		(layers "F.Cu" "B.Cu")
		(net "GND")
	)
	(via
		(at 19.937476 -177.25009)
		(size 0.5588)
		(drill 0.3048)
		(layers "F.Cu" "B.Cu")
		(net "GND")
	)
	(via
		(at 6.096 -53.848)
		(size 0.7112)
		(drill 0.4064)
		(layers "F.Cu" "B.Cu")
		(net "GND")
	)
	(via
		(at 51.181 -100.965)
		(size 0.7112)
		(drill 0.4064)
		(layers "F.Cu" "B.Cu")
		(net "GND")
	)
	(via
		(at 10.668 -166.497)
		(size 0.7112)
		(drill 0.3556)
		(layers "F.Cu" "B.Cu")
		(net "GND")
	)
	(via
		(at 28.829 -231.013)
		(size 0.7112)
		(drill 0.4064)
		(layers "F.Cu" "B.Cu")
		(net "GND")
	)
	(via
		(at 46.99 -441.579)
		(size 0.7112)
		(drill 0.4064)
		(layers "F.Cu" "B.Cu")
		(net "GND")
	)
	(via
		(at 48.6918 -47.371)
		(size 0.7112)
		(drill 0.4064)
		(layers "F.Cu" "B.Cu")
		(net "GND")
	)
	(via
		(at 8.128 -221.488)
		(size 0.7112)
		(drill 0.4064)
		(layers "F.Cu" "B.Cu")
		(net "GND")
	)
	(via
		(at 44.983908 -286.9692)
		(size 0.7112)
		(drill 0.4064)
		(layers "F.Cu" "B.Cu")
		(net "GND")
	)
	(via
		(at 18.034 -33.492186)
		(size 0.7112)
		(drill 0.4064)
		(layers "F.Cu" "B.Cu")
		(net "GND")
	)
	(via
		(at 36.195 -139.7)
		(size 0.5588)
		(drill 0.3048)
		(layers "F.Cu" "B.Cu")
		(net "GND")
	)
	(via
		(at 28.067 -282.448)
		(size 0.7112)
		(drill 0.4064)
		(layers "F.Cu" "B.Cu")
		(net "GND")
	)
	(via
		(at 33.02 -203.2)
		(size 0.7112)
		(drill 0.4064)
		(layers "F.Cu" "B.Cu")
		(net "GND")
	)
	(via
		(at 27.4574 -121.3231)
		(size 0.5588)
		(drill 0.3048)
		(layers "F.Cu" "B.Cu")
		(net "GND")
	)
	(via
		(at 50.038 -394.081)
		(size 0.7112)
		(drill 0.4064)
		(layers "F.Cu" "B.Cu")
		(net "GND")
	)
	(via
		(at 3.302 -53.975)
		(size 0.7112)
		(drill 0.4064)
		(layers "F.Cu" "B.Cu")
		(net "GND")
	)
	(via
		(at 30.1498 -213.5378)
		(size 0.5588)
		(drill 0.3048)
		(layers "F.Cu" "B.Cu")
		(net "GND")
	)
	(via
		(at 37.0332 -150.9776)
		(size 0.5588)
		(drill 0.3048)
		(layers "F.Cu" "B.Cu")
		(net "GND")
	)
	(via
		(at 8.636 -375.3104)
		(size 0.7112)
		(drill 0.4064)
		(layers "F.Cu" "B.Cu")
		(net "GND")
	)
	(via
		(at 50.038 -178.816)
		(size 0.7112)
		(drill 0.4064)
		(layers "F.Cu" "B.Cu")
		(net "GND")
	)
	(via
		(at 48.895 -167.259)
		(size 0.7112)
		(drill 0.4064)
		(layers "F.Cu" "B.Cu")
		(net "GND")
	)
	(via
		(at 26.162 -316.2046)
		(size 0.7112)
		(drill 0.4064)
		(layers "F.Cu" "B.Cu")
		(net "GND")
	)
	(via
		(at 1.347216 -110.363)
		(size 0.7112)
		(drill 0.4064)
		(layers "F.Cu" "B.Cu")
		(net "GND")
	)
	(via
		(at 3.556 -46.736)
		(size 0.7112)
		(drill 0.4064)
		(layers "F.Cu" "B.Cu")
		(net "GND")
	)
	(via
		(at 28.067 -264.541)
		(size 0.7112)
		(drill 0.4064)
		(layers "F.Cu" "B.Cu")
		(net "GND")
	)
	(via
		(at 28.448 -316.103)
		(size 0.7112)
		(drill 0.4064)
		(layers "F.Cu" "B.Cu")
		(net "GND")
	)
	(via
		(at 8.636 -256.032)
		(size 0.7112)
		(drill 0.4064)
		(layers "F.Cu" "B.Cu")
		(net "GND")
	)
	(via
		(at 7.112 -326.644)
		(size 0.7112)
		(drill 0.4064)
		(layers "F.Cu" "B.Cu")
		(net "GND")
	)
	(via
		(at 27.559 -176.657)
		(size 0.7112)
		(drill 0.4064)
		(layers "F.Cu" "B.Cu")
		(net "GND")
	)
	(via
		(at 11.176 -198.628)
		(size 0.7112)
		(drill 0.4064)
		(layers "F.Cu" "B.Cu")
		(net "GND")
	)
	(via
		(at 47.8282 -93.6244)
		(size 0.7112)
		(drill 0.4064)
		(layers "F.Cu" "B.Cu")
		(net "GND")
	)
	(via
		(at 51.435 -191.897)
		(size 0.5588)
		(drill 0.3048)
		(layers "F.Cu" "B.Cu")
		(net "GND")
	)
	(via
		(at 42.926 -362.3945)
		(size 0.5588)
		(drill 0.3048)
		(layers "F.Cu" "B.Cu")
		(net "GND")
	)
	(via
		(at 5.588 -312.928)
		(size 0.7112)
		(drill 0.4064)
		(layers "F.Cu" "B.Cu")
		(net "GND")
	)
	(via
		(at 1.293876 -152.4)
		(size 0.7112)
		(drill 0.4064)
		(layers "F.Cu" "B.Cu")
		(net "GND")
	)
	(via
		(at 28.956 -203.2)
		(size 0.7112)
		(drill 0.4064)
		(layers "F.Cu" "B.Cu")
		(net "GND")
	)
	(via
		(at 40.767 -271.018)
		(size 0.7112)
		(drill 0.4064)
		(layers "F.Cu" "B.Cu")
		(net "GND")
	)
	(via
		(at 10.1092 -173.0756)
		(size 0.5588)
		(drill 0.3048)
		(layers "F.Cu" "B.Cu")
		(net "GND")
	)
	(via
		(at 47.625 -396.113)
		(size 0.5588)
		(drill 0.3048)
		(layers "F.Cu" "B.Cu")
		(net "GND")
	)
	(via
		(at 10.9982 -418.2364)
		(size 0.5588)
		(drill 0.3048)
		(layers "F.Cu" "B.Cu")
		(net "GND")
	)
	(via
		(at 18.2372 -348.9706)
		(size 0.7112)
		(drill 0.4064)
		(layers "F.Cu" "B.Cu")
		(net "GND")
	)
	(via
		(at 11.684 -184.404)
		(size 0.7112)
		(drill 0.4064)
		(layers "F.Cu" "B.Cu")
		(net "GND")
	)
	(via
		(at 12.7254 -320.421)
		(size 0.7112)
		(drill 0.4064)
		(layers "F.Cu" "B.Cu")
		(net "GND")
	)
	(via
		(at 1.1684 -377.1392)
		(size 0.7112)
		(drill 0.4064)
		(layers "F.Cu" "B.Cu")
		(net "GND")
	)
	(via
		(at 48.6918 -419.7858)
		(size 0.5588)
		(drill 0.3048)
		(layers "F.Cu" "B.Cu")
		(net "GND")
	)
	(via
		(at 27.559 -244.856)
		(size 0.7112)
		(drill 0.4064)
		(layers "F.Cu" "B.Cu")
		(net "GND")
	)
	(via
		(at 6.096 -192.024)
		(size 0.7112)
		(drill 0.4064)
		(layers "F.Cu" "B.Cu")
		(net "GND")
	)
	(via
		(at 30.353 -299.085)
		(size 0.7112)
		(drill 0.4064)
		(layers "F.Cu" "B.Cu")
		(net "GND")
	)
	(via
		(at 9.144 -66.138044)
		(size 0.5588)
		(drill 0.3048)
		(layers "F.Cu" "B.Cu")
		(net "GND")
	)
	(via
		(at 51.076606 -134.493)
		(size 0.7112)
		(drill 0.4064)
		(layers "F.Cu" "B.Cu")
		(net "GND")
	)
	(via
		(at 42.0624 -160.088326)
		(size 0.7112)
		(drill 0.4064)
		(layers "F.Cu" "B.Cu")
		(net "GND")
	)
	(via
		(at 1.347216 -139.3952)
		(size 0.5588)
		(drill 0.3048)
		(layers "F.Cu" "B.Cu")
		(net "GND")
	)
	(via
		(at 29.845 -226.822)
		(size 0.7112)
		(drill 0.4064)
		(layers "F.Cu" "B.Cu")
		(net "GND")
	)
	(via
		(at 17.907 -350.139)
		(size 0.7112)
		(drill 0.4064)
		(layers "F.Cu" "B.Cu")
		(net "GND")
	)
	(via
		(at 4.963668 -434.471572)
		(size 0.5588)
		(drill 0.3048)
		(layers "F.Cu" "B.Cu")
		(net "GND")
	)
	(via
		(at 14.969744 -65.097406)
		(size 0.5588)
		(drill 0.3048)
		(layers "F.Cu" "B.Cu")
		(net "GND")
	)
	(via
		(at 1.905 -349.631)
		(size 0.7112)
		(drill 0.4064)
		(layers "F.Cu" "B.Cu")
		(net "GND")
	)
	(via
		(at 1.166876 -364.617)
		(size 0.7112)
		(drill 0.4064)
		(layers "F.Cu" "B.Cu")
		(net "GND")
	)
	(via
		(at 31.496 -336.296)
		(size 0.7112)
		(drill 0.4064)
		(layers "F.Cu" "B.Cu")
		(net "GND")
	)
	(via
		(at 29.591 -191.008)
		(size 0.7112)
		(drill 0.4064)
		(layers "F.Cu" "B.Cu")
		(net "GND")
	)
	(via
		(at 50.8 -106.807)
		(size 0.7112)
		(drill 0.4064)
		(layers "F.Cu" "B.Cu")
		(net "GND")
	)
	(via
		(at 11.938 -479.0948)
		(size 0.5588)
		(drill 0.3048)
		(layers "F.Cu" "B.Cu")
		(net "GND")
	)
	(via
		(at 51.152806 -202.438)
		(size 0.5588)
		(drill 0.3048)
		(layers "F.Cu" "B.Cu")
		(net "GND")
	)
	(via
		(at 15.899892 -35.840162)
		(size 0.7112)
		(drill 0.4064)
		(layers "F.Cu" "B.Cu")
		(net "GND")
	)
	(via
		(at 50.165 -404.622)
		(size 0.7112)
		(drill 0.4064)
		(layers "F.Cu" "B.Cu")
		(net "GND")
	)
	(via
		(at 23.241 -277.622)
		(size 0.7112)
		(drill 0.3556)
		(layers "F.Cu" "B.Cu")
		(net "GND")
	)
	(via
		(at 49.276 -14.097)
		(size 0.7112)
		(drill 0.4064)
		(layers "F.Cu" "B.Cu")
		(net "GND")
	)
	(via
		(at 6.8326 -396.0114)
		(size 0.7112)
		(drill 0.4064)
		(layers "F.Cu" "B.Cu")
		(net "GND")
	)
	(via
		(at 40.767 -267.589)
		(size 0.7112)
		(drill 0.4064)
		(layers "F.Cu" "B.Cu")
		(net "GND")
	)
	(via
		(at 1.524 -289.052)
		(size 0.7112)
		(drill 0.4064)
		(layers "F.Cu" "B.Cu")
		(net "GND")
	)
	(via
		(at 23.1394 -488.3912)
		(size 0.5588)
		(drill 0.3048)
		(layers "F.Cu" "B.Cu")
		(net "GND")
	)
	(via
		(at 37.084 -187.452)
		(size 0.5588)
		(drill 0.3048)
		(layers "F.Cu" "B.Cu")
		(net "GND")
	)
	(via
		(at 26.67 -303.784)
		(size 0.7112)
		(drill 0.4064)
		(layers "F.Cu" "B.Cu")
		(net "GND")
	)
	(via
		(at 9.3218 -448.2338)
		(size 0.7112)
		(drill 0.4064)
		(layers "F.Cu" "B.Cu")
		(net "GND")
	)
	(via
		(at 20.828 -204.851)
		(size 0.7112)
		(drill 0.4064)
		(layers "F.Cu" "B.Cu")
		(net "GND")
	)
	(via
		(at 37.211 -354.8634)
		(size 0.5588)
		(drill 0.3048)
		(layers "F.Cu" "B.Cu")
		(net "GND")
	)
	(via
		(at 9.7282 -396.6972)
		(size 0.7112)
		(drill 0.4064)
		(layers "F.Cu" "B.Cu")
		(net "GND")
	)
	(via
		(at 51.181 -345.313)
		(size 0.5588)
		(drill 0.3048)
		(layers "F.Cu" "B.Cu")
		(net "GND")
	)
	(via
		(at 27.94 -360.172)
		(size 0.7112)
		(drill 0.4064)
		(layers "F.Cu" "B.Cu")
		(net "GND")
	)
	(via
		(at 4.064 -281.94)
		(size 0.7112)
		(drill 0.4064)
		(layers "F.Cu" "B.Cu")
		(net "GND")
	)
	(via
		(at 26.416 -257.556)
		(size 0.7112)
		(drill 0.4064)
		(layers "F.Cu" "B.Cu")
		(net "GND")
	)
	(via
		(at 35.179 -467.233)
		(size 0.7112)
		(drill 0.4064)
		(layers "F.Cu" "B.Cu")
		(net "GND")
	)
	(via
		(at 32.4358 -30.2768)
		(size 0.7112)
		(drill 0.4064)
		(layers "F.Cu" "B.Cu")
		(net "GND")
	)
	(via
		(at 10.795 -66.0908)
		(size 0.5588)
		(drill 0.3048)
		(layers "F.Cu" "B.Cu")
		(net "GND")
	)
	(via
		(at 19.7104 -215.6714)
		(size 0.7112)
		(drill 0.4064)
		(layers "F.Cu" "B.Cu")
		(net "GND")
	)
	(via
		(at 11.811 -469.9508)
		(size 0.7112)
		(drill 0.4064)
		(layers "F.Cu" "B.Cu")
		(net "GND")
	)
	(via
		(at 11.557 -429.26)
		(size 0.5588)
		(drill 0.3048)
		(layers "F.Cu" "B.Cu")
		(net "GND")
	)
	(via
		(at 5.9436 -89.789)
		(size 0.5588)
		(drill 0.3048)
		(layers "F.Cu" "B.Cu")
		(net "GND")
	)
	(via
		(at 32.639 -22.606)
		(size 0.7112)
		(drill 0.4064)
		(layers "F.Cu" "B.Cu")
		(net "GND")
	)
	(via
		(at 50.038 -466.979)
		(size 0.7112)
		(drill 0.4064)
		(layers "F.Cu" "B.Cu")
		(net "GND")
	)
	(via
		(at 34.0614 -171.323)
		(size 0.7112)
		(drill 0.4064)
		(layers "F.Cu" "B.Cu")
		(net "GND")
	)
	(via
		(at 20.701 -351.028)
		(size 0.7112)
		(drill 0.4064)
		(layers "F.Cu" "B.Cu")
		(net "GND")
	)
	(via
		(at 25.61844 -356.17404)
		(size 0.5588)
		(drill 0.3048)
		(layers "F.Cu" "B.Cu")
		(net "GND")
	)
	(via
		(at 12.954 -134.493)
		(size 0.5588)
		(drill 0.3048)
		(layers "F.Cu" "B.Cu")
		(net "GND")
	)
	(via
		(at 36.957 -217.551)
		(size 0.7112)
		(drill 0.4064)
		(layers "F.Cu" "B.Cu")
		(net "GND")
	)
	(via
		(at 50.038 -429.641)
		(size 0.7112)
		(drill 0.4064)
		(layers "F.Cu" "B.Cu")
		(net "GND")
	)
	(via
		(at 36.1696 -488.6452)
		(size 0.5588)
		(drill 0.3048)
		(layers "F.Cu" "B.Cu")
		(net "GND")
	)
	(via
		(at 10.0838 -474.9038)
		(size 0.7112)
		(drill 0.4064)
		(layers "F.Cu" "B.Cu")
		(net "GND")
	)
	(via
		(at 33.02 -189.484)
		(size 0.5588)
		(drill 0.3048)
		(layers "F.Cu" "B.Cu")
		(net "GND")
	)
	(via
		(at 41.021 -197.612)
		(size 0.5588)
		(drill 0.3048)
		(layers "F.Cu" "B.Cu")
		(net "GND")
	)
	(via
		(at 51.435 -215.011)
		(size 0.5588)
		(drill 0.3048)
		(layers "F.Cu" "B.Cu")
		(net "GND")
	)
	(via
		(at 14.605 -250.9012)
		(size 0.5588)
		(drill 0.3048)
		(layers "F.Cu" "B.Cu")
		(net "GND")
	)
	(via
		(at 44.323 -36.449)
		(size 0.7112)
		(drill 0.4064)
		(layers "F.Cu" "B.Cu")
		(net "GND")
	)
	(via
		(at 39.7002 -222.8088)
		(size 0.7112)
		(drill 0.4064)
		(layers "F.Cu" "B.Cu")
		(net "GND")
	)
	(via
		(at 40.513 -269.748)
		(size 0.5588)
		(drill 0.3048)
		(layers "F.Cu" "B.Cu")
		(net "GND")
	)
	(via
		(at 25.146 -242.062)
		(size 0.7112)
		(drill 0.4064)
		(layers "F.Cu" "B.Cu")
		(net "GND")
	)
	(via
		(at 4.572 -154.432)
		(size 0.7112)
		(drill 0.4064)
		(layers "F.Cu" "B.Cu")
		(net "GND")
	)
	(via
		(at 23.241 -333.883)
		(size 0.7112)
		(drill 0.4064)
		(layers "F.Cu" "B.Cu")
		(net "GND")
	)
	(via
		(at 20.701 -212.725)
		(size 0.7112)
		(drill 0.4064)
		(layers "F.Cu" "B.Cu")
		(net "GND")
	)
	(via
		(at 45.6946 -235.1278)
		(size 0.5588)
		(drill 0.3048)
		(layers "F.Cu" "B.Cu")
		(net "GND")
	)
	(via
		(at 1.166876 -297.053)
		(size 0.7112)
		(drill 0.4064)
		(layers "F.Cu" "B.Cu")
		(net "GND")
	)
	(via
		(at 46.355 -192.659)
		(size 0.7112)
		(drill 0.4064)
		(layers "F.Cu" "B.Cu")
		(net "GND")
	)
	(via
		(at 11.2776 -462.6356)
		(size 0.7112)
		(drill 0.4064)
		(layers "F.Cu" "B.Cu")
		(net "GND")
	)
	(via
		(at 28.448 -317.627)
		(size 0.7112)
		(drill 0.4064)
		(layers "F.Cu" "B.Cu")
		(net "GND")
	)
	(via
		(at 14.732 -310.388)
		(size 0.7112)
		(drill 0.4064)
		(layers "F.Cu" "B.Cu")
		(net "GND")
	)
	(via
		(at 29.21 -178.943)
		(size 0.7112)
		(drill 0.4064)
		(layers "F.Cu" "B.Cu")
		(net "GND")
	)
	(via
		(at 50.292 -418.465)
		(size 0.7112)
		(drill 0.4064)
		(layers "F.Cu" "B.Cu")
		(net "GND")
	)
	(via
		(at 32.9692 -206.629)
		(size 0.7112)
		(drill 0.4064)
		(layers "F.Cu" "B.Cu")
		(net "GND")
	)
	(via
		(at 51.181 -175.641)
		(size 0.5588)
		(drill 0.3048)
		(layers "F.Cu" "B.Cu")
		(net "GND")
	)
	(via
		(at 49.022 -396.875)
		(size 0.7112)
		(drill 0.4064)
		(layers "F.Cu" "B.Cu")
		(net "GND")
	)
	(via
		(at 35.306 -457.327)
		(size 0.7112)
		(drill 0.4064)
		(layers "F.Cu" "B.Cu")
		(net "GND")
	)
	(via
		(at 35.814 -238.379)
		(size 0.7112)
		(drill 0.4064)
		(layers "F.Cu" "B.Cu")
		(net "GND")
	)
	(via
		(at 28.321 -261.62)
		(size 0.7112)
		(drill 0.4064)
		(layers "F.Cu" "B.Cu")
		(net "GND")
	)
	(via
		(at 31.623 -217.932)
		(size 0.7112)
		(drill 0.4064)
		(layers "F.Cu" "B.Cu")
		(net "GND")
	)
	(via
		(at 50.927 -49.7586)
		(size 0.7112)
		(drill 0.4064)
		(layers "F.Cu" "B.Cu")
		(net "GND")
	)
	(via
		(at 48.8696 -102.0826)
		(size 0.7112)
		(drill 0.4064)
		(layers "F.Cu" "B.Cu")
		(net "GND")
	)
	(via
		(at 16.764 -139.827)
		(size 0.5588)
		(drill 0.3048)
		(layers "F.Cu" "B.Cu")
		(net "GND")
	)
	(via
		(at 12.446 -4.699)
		(size 0.7112)
		(drill 0.4064)
		(layers "F.Cu" "B.Cu")
		(net "GND")
	)
	(via
		(at 4.572 -186.055)
		(size 0.7112)
		(drill 0.4064)
		(layers "F.Cu" "B.Cu")
		(net "GND")
	)
	(via
		(at 43.942 -274.828)
		(size 0.7112)
		(drill 0.4064)
		(layers "F.Cu" "B.Cu")
		(net "GND")
	)
	(via
		(at 13.7668 -56.0578)
		(size 0.5588)
		(drill 0.3048)
		(layers "F.Cu" "B.Cu")
		(net "GND")
	)
	(via
		(at 51.308 -146.812)
		(size 0.7112)
		(drill 0.4064)
		(layers "F.Cu" "B.Cu")
		(net "GND")
	)
	(via
		(at 51.36134 -229.489)
		(size 0.5588)
		(drill 0.3048)
		(layers "F.Cu" "B.Cu")
		(net "GND")
	)
	(via
		(at 44.196 -14.097)
		(size 0.7112)
		(drill 0.4064)
		(layers "F.Cu" "B.Cu")
		(net "GND")
	)
	(via
		(at 49.657 -187.706)
		(size 0.7112)
		(drill 0.4064)
		(layers "F.Cu" "B.Cu")
		(net "GND")
	)
	(via
		(at 10.2362 -432.7906)
		(size 0.5588)
		(drill 0.3048)
		(layers "F.Cu" "B.Cu")
		(net "GND")
	)
	(via
		(at 1.166876 -469.9)
		(size 0.7112)
		(drill 0.4064)
		(layers "F.Cu" "B.Cu")
		(net "GND")
	)
	(via
		(at 14.732 -328.168)
		(size 0.7112)
		(drill 0.4064)
		(layers "F.Cu" "B.Cu")
		(net "GND")
	)
	(via
		(at 27.6606 -137.4902)
		(size 0.5588)
		(drill 0.3048)
		(layers "F.Cu" "B.Cu")
		(net "GND")
	)
	(via
		(at 33.147 -245.364)
		(size 0.7112)
		(drill 0.4064)
		(layers "F.Cu" "B.Cu")
		(net "GND")
	)
	(via
		(at 48.26 -267.208)
		(size 0.7112)
		(drill 0.4064)
		(layers "F.Cu" "B.Cu")
		(net "GND")
	)
	(via
		(at 48.26 -209.169)
		(size 0.7112)
		(drill 0.4064)
		(layers "F.Cu" "B.Cu")
		(net "GND")
	)
	(via
		(at 7.8232 -33.0962)
		(size 0.7112)
		(drill 0.4064)
		(layers "F.Cu" "B.Cu")
		(net "GND")
	)
	(via
		(at 4.0894 -495.4778)
		(size 0.7112)
		(drill 0.4064)
		(layers "F.Cu" "B.Cu")
		(net "GND")
	)
	(via
		(at 29.852366 -241.006376)
		(size 0.7112)
		(drill 0.4064)
		(layers "F.Cu" "B.Cu")
		(net "GND")
	)
	(via
		(at 7.366 -424.434)
		(size 0.7112)
		(drill 0.4064)
		(layers "F.Cu" "B.Cu")
		(net "GND")
	)
	(via
		(at 4.4958 -325.882)
		(size 0.7112)
		(drill 0.4064)
		(layers "F.Cu" "B.Cu")
		(net "GND")
	)
	(via
		(at 6.858 -95.885)
		(size 0.7112)
		(drill 0.4064)
		(layers "F.Cu" "B.Cu")
		(net "GND")
	)
	(via
		(at 46.355 -189.23)
		(size 0.7112)
		(drill 0.4064)
		(layers "F.Cu" "B.Cu")
		(net "GND")
	)
	(via
		(at 50.8 -16.51)
		(size 0.7112)
		(drill 0.4064)
		(layers "F.Cu" "B.Cu")
		(net "GND")
	)
	(via
		(at 31.652972 -243.647976)
		(size 0.7112)
		(drill 0.4064)
		(layers "F.Cu" "B.Cu")
		(net "GND")
	)
	(via
		(at 15.621 -488.315)
		(size 0.7112)
		(drill 0.4064)
		(layers "F.Cu" "B.Cu")
		(net "GND")
	)
	(via
		(at 50.8 -13.97)
		(size 0.7112)
		(drill 0.4064)
		(layers "F.Cu" "B.Cu")
		(net "GND")
	)
	(via
		(at 1.651 -202.946)
		(size 0.7112)
		(drill 0.4064)
		(layers "F.Cu" "B.Cu")
		(net "GND")
	)
	(via
		(at 39.751 -452.628)
		(size 0.7112)
		(drill 0.4064)
		(layers "F.Cu" "B.Cu")
		(net "GND")
	)
	(via
		(at 8.6614 -143.9164)
		(size 0.7112)
		(drill 0.4064)
		(layers "F.Cu" "B.Cu")
		(net "GND")
	)
	(via
		(at 10.16 -324.612)
		(size 0.7112)
		(drill 0.4064)
		(layers "F.Cu" "B.Cu")
		(net "GND")
	)
	(via
		(at 1.524 -155.448)
		(size 0.7112)
		(drill 0.4064)
		(layers "F.Cu" "B.Cu")
		(net "GND")
	)
	(via
		(at 28.9052 -338.3026)
		(size 0.7112)
		(drill 0.4064)
		(layers "F.Cu" "B.Cu")
		(net "GND")
	)
	(via
		(at 50.8 -21.59)
		(size 0.7112)
		(drill 0.4064)
		(layers "F.Cu" "B.Cu")
		(net "GND")
	)
	(via
		(at 37.465 -296.037)
		(size 0.7112)
		(drill 0.4064)
		(layers "F.Cu" "B.Cu")
		(net "GND")
	)
	(via
		(at 48.895 -418.592)
		(size 0.5588)
		(drill 0.3048)
		(layers "F.Cu" "B.Cu")
		(net "GND")
	)
	(via
		(at 5.855462 -218.756738)
		(size 0.7112)
		(drill 0.4064)
		(layers "F.Cu" "B.Cu")
		(net "GND")
	)
	(via
		(at 31.496 -230.886)
		(size 0.7112)
		(drill 0.4064)
		(layers "F.Cu" "B.Cu")
		(net "GND")
	)
	(via
		(at 48.768 -233.934)
		(size 0.7112)
		(drill 0.4064)
		(layers "F.Cu" "B.Cu")
		(net "GND")
	)
	(via
		(at 26.289 -176.657)
		(size 0.7112)
		(drill 0.4064)
		(layers "F.Cu" "B.Cu")
		(net "GND")
	)
	(via
		(at 11.176 -331.724)
		(size 0.7112)
		(drill 0.4064)
		(layers "F.Cu" "B.Cu")
		(net "GND")
	)
	(via
		(at 1.524 -334.772)
		(size 0.7112)
		(drill 0.4064)
		(layers "F.Cu" "B.Cu")
		(net "GND")
	)
	(via
		(at 38.481 -261.747)
		(size 0.5588)
		(drill 0.3048)
		(layers "F.Cu" "B.Cu")
		(net "GND")
	)
	(via
		(at 11.684 -211.836)
		(size 0.7112)
		(drill 0.4064)
		(layers "F.Cu" "B.Cu")
		(net "GND")
	)
	(via
		(at 35.941 -424.942)
		(size 0.7112)
		(drill 0.4064)
		(layers "F.Cu" "B.Cu")
		(net "GND")
	)
	(via
		(at 41.021 -195.072)
		(size 0.5588)
		(drill 0.3048)
		(layers "F.Cu" "B.Cu")
		(net "GND")
	)
	(via
		(at 48.768 -223.266)
		(size 0.7112)
		(drill 0.4064)
		(layers "F.Cu" "B.Cu")
		(net "GND")
	)
	(via
		(at 3.302 -81.534)
		(size 0.7112)
		(drill 0.4064)
		(layers "F.Cu" "B.Cu")
		(net "GND")
	)
	(via
		(at 9.017 -424.307)
		(size 0.5588)
		(drill 0.3048)
		(layers "F.Cu" "B.Cu")
		(net "GND")
	)
	(via
		(at 34.1884 -169.0624)
		(size 0.5588)
		(drill 0.3048)
		(layers "F.Cu" "B.Cu")
		(net "GND")
	)
	(via
		(at 43.942 -470.56294)
		(size 0.7112)
		(drill 0.4064)
		(layers "F.Cu" "B.Cu")
		(net "GND")
	)
	(via
		(at 15.24 -303.276)
		(size 0.7112)
		(drill 0.4064)
		(layers "F.Cu" "B.Cu")
		(net "GND")
	)
	(via
		(at 19.3548 -363.3978)
		(size 0.7112)
		(drill 0.4064)
		(layers "F.Cu" "B.Cu")
		(net "GND")
	)
	(via
		(at 31.877 -233.68)
		(size 0.7112)
		(drill 0.4064)
		(layers "F.Cu" "B.Cu")
		(net "GND")
	)
	(via
		(at 51.181 -236.601)
		(size 0.5588)
		(drill 0.3048)
		(layers "F.Cu" "B.Cu")
		(net "GND")
	)
	(via
		(at 19.035268 -134.869682)
		(size 0.7112)
		(drill 0.4064)
		(layers "F.Cu" "B.Cu")
		(net "GND")
	)
	(via
		(at 48.895 -216.662)
		(size 0.7112)
		(drill 0.4064)
		(layers "F.Cu" "B.Cu")
		(net "GND")
	)
	(via
		(at 38.989 -239.014)
		(size 0.7112)
		(drill 0.4064)
		(layers "F.Cu" "B.Cu")
		(net "GND")
	)
	(via
		(at 39.7002 -140.2334)
		(size 0.5588)
		(drill 0.3048)
		(layers "F.Cu" "B.Cu")
		(net "GND")
	)
	(via
		(at 1.651 -95.25)
		(size 0.7112)
		(drill 0.4064)
		(layers "F.Cu" "B.Cu")
		(net "GND")
	)
	(via
		(at 30.819852 -368.813334)
		(size 0.7112)
		(drill 0.4064)
		(layers "F.Cu" "B.Cu")
		(net "GND")
	)
	(via
		(at 49.276 -226.949)
		(size 0.7112)
		(drill 0.4064)
		(layers "F.Cu" "B.Cu")
		(net "GND")
	)
	(via
		(at 21.1328 -369.697)
		(size 0.5588)
		(drill 0.3048)
		(layers "F.Cu" "B.Cu")
		(net "GND")
	)
	(via
		(at 13.1572 -312.8264)
		(size 0.7112)
		(drill 0.4064)
		(layers "F.Cu" "B.Cu")
		(net "GND")
	)
	(via
		(at 46.736 -250.825)
		(size 0.7112)
		(drill 0.4064)
		(layers "F.Cu" "B.Cu")
		(net "GND")
	)
	(via
		(at 49.403 -198.755)
		(size 0.7112)
		(drill 0.4064)
		(layers "F.Cu" "B.Cu")
		(net "GND")
	)
	(via
		(at 46.863 -223.266)
		(size 0.7112)
		(drill 0.4064)
		(layers "F.Cu" "B.Cu")
		(net "GND")
	)
	(via
		(at 44.196 -257.1496)
		(size 0.7112)
		(drill 0.4064)
		(layers "F.Cu" "B.Cu")
		(net "GND")
	)
	(via
		(at 20.701 -356.616)
		(size 0.7112)
		(drill 0.4064)
		(layers "F.Cu" "B.Cu")
		(net "GND")
	)
	(via
		(at 18.542 -378.7648)
		(size 0.7112)
		(drill 0.4064)
		(layers "F.Cu" "B.Cu")
		(net "GND")
	)
	(via
		(at 14.351 -449.4022)
		(size 0.7112)
		(drill 0.4064)
		(layers "F.Cu" "B.Cu")
		(net "GND")
	)
	(via
		(at 24.13 -36.322)
		(size 0.7112)
		(drill 0.4064)
		(layers "F.Cu" "B.Cu")
		(net "GND")
	)
	(via
		(at 9.8552 -391.5918)
		(size 0.7112)
		(drill 0.4064)
		(layers "F.Cu" "B.Cu")
		(net "GND")
	)
	(via
		(at 26.289 -231.013)
		(size 0.7112)
		(drill 0.4064)
		(layers "F.Cu" "B.Cu")
		(net "GND")
	)
	(via
		(at 1.347216 -400.3548)
		(size 0.7112)
		(drill 0.4064)
		(layers "F.Cu" "B.Cu")
		(net "GND")
	)
	(via
		(at 11.684 -309.372)
		(size 0.7112)
		(drill 0.4064)
		(layers "F.Cu" "B.Cu")
		(net "GND")
	)
	(via
		(at 49.911 -478.028)
		(size 0.7112)
		(drill 0.4064)
		(layers "F.Cu" "B.Cu")
		(net "GND")
	)
	(via
		(at 6.913372 -278.638)
		(size 0.7112)
		(drill 0.4064)
		(layers "F.Cu" "B.Cu")
		(net "GND")
	)
	(via
		(at 43.434 -271.272)
		(size 0.7112)
		(drill 0.4064)
		(layers "F.Cu" "B.Cu")
		(net "GND")
	)
	(via
		(at 37.465 -332.994)
		(size 0.7112)
		(drill 0.4064)
		(layers "F.Cu" "B.Cu")
		(net "GND")
	)
	(via
		(at 51.435 -208.788)
		(size 0.5588)
		(drill 0.3048)
		(layers "F.Cu" "B.Cu")
		(net "GND")
	)
	(via
		(at 47.3964 -108.1405)
		(size 0.7112)
		(drill 0.4064)
		(layers "F.Cu" "B.Cu")
		(net "GND")
	)
	(via
		(at 4.064 -213.868)
		(size 0.7112)
		(drill 0.4064)
		(layers "F.Cu" "B.Cu")
		(net "GND")
	)
	(via
		(at 36.957 -153.416)
		(size 0.7112)
		(drill 0.4064)
		(layers "F.Cu" "B.Cu")
		(net "GND")
	)
	(via
		(at 16.152876 -491.617)
		(size 0.7112)
		(drill 0.4064)
		(layers "F.Cu" "B.Cu")
		(net "GND")
	)
	(via
		(at 29.477462 -229.424738)
		(size 0.7112)
		(drill 0.4064)
		(layers "F.Cu" "B.Cu")
		(net "GND")
	)
	(via
		(at 11.684 -215.392)
		(size 0.7112)
		(drill 0.4064)
		(layers "F.Cu" "B.Cu")
		(net "GND")
	)
	(via
		(at 45.375576 -305.439826)
		(size 0.7112)
		(drill 0.4064)
		(layers "F.Cu" "B.Cu")
		(net "GND")
	)
	(via
		(at 48.768 -219.837)
		(size 0.7112)
		(drill 0.4064)
		(layers "F.Cu" "B.Cu")
		(net "GND")
	)
	(via
		(at 32.004 -226.695)
		(size 0.7112)
		(drill 0.4064)
		(layers "F.Cu" "B.Cu")
		(net "GND")
	)
	(via
		(at 9.2456 -386.9436)
		(size 0.5588)
		(drill 0.3048)
		(layers "F.Cu" "B.Cu")
		(net "GND")
	)
	(via
		(at 51.435 -325.12)
		(size 0.5588)
		(drill 0.3048)
		(layers "F.Cu" "B.Cu")
		(net "GND")
	)
	(via
		(at 31.242 -203.2)
		(size 0.7112)
		(drill 0.4064)
		(layers "F.Cu" "B.Cu")
		(net "GND")
	)
	(via
		(at 30.353 -189.611)
		(size 0.5588)
		(drill 0.3048)
		(layers "F.Cu" "B.Cu")
		(net "GND")
	)
	(via
		(at 16.5862 -479.1964)
		(size 0.5588)
		(drill 0.3048)
		(layers "F.Cu" "B.Cu")
		(net "GND")
	)
	(via
		(at 24.892 -108.331)
		(size 0.7112)
		(drill 0.4064)
		(layers "F.Cu" "B.Cu")
		(net "GND")
	)
	(via
		(at 29.21 -206.502)
		(size 0.7112)
		(drill 0.4064)
		(layers "F.Cu" "B.Cu")
		(net "GND")
	)
	(via
		(at 26.289 -272.669)
		(size 0.7112)
		(drill 0.4064)
		(layers "F.Cu" "B.Cu")
		(net "GND")
	)
	(via
		(at 11.4046 -442.0362)
		(size 0.7112)
		(drill 0.4064)
		(layers "F.Cu" "B.Cu")
		(net "GND")
	)
	(via
		(at 7.493 -92.583)
		(size 0.7112)
		(drill 0.4064)
		(layers "F.Cu" "B.Cu")
		(net "GND")
	)
	(via
		(at 3.3274 -439.1406)
		(size 0.7112)
		(drill 0.4064)
		(layers "F.Cu" "B.Cu")
		(net "GND")
	)
	(via
		(at 1.166876 -457.073)
		(size 0.7112)
		(drill 0.4064)
		(layers "F.Cu" "B.Cu")
		(net "GND")
	)
	(via
		(at 36.7284 -135.5852)
		(size 0.7112)
		(drill 0.4064)
		(layers "F.Cu" "B.Cu")
		(net "GND")
	)
	(via
		(at 1.2192 -371.0178)
		(size 0.7112)
		(drill 0.4064)
		(layers "F.Cu" "B.Cu")
		(net "GND")
	)
	(via
		(at 33.274 -38.1254)
		(size 0.7112)
		(drill 0.4064)
		(layers "F.Cu" "B.Cu")
		(net "GND")
	)
	(via
		(at 1.143 -51.435)
		(size 0.7112)
		(drill 0.4064)
		(layers "F.Cu" "B.Cu")
		(net "GND")
	)
	(via
		(at 31.496 -322.58)
		(size 0.7112)
		(drill 0.4064)
		(layers "F.Cu" "B.Cu")
		(net "GND")
	)
	(via
		(at 23.241 -312.166)
		(size 0.7112)
		(drill 0.4064)
		(layers "F.Cu" "B.Cu")
		(net "GND")
	)
	(via
		(at 8.636 -333.248)
		(size 0.7112)
		(drill 0.4064)
		(layers "F.Cu" "B.Cu")
		(net "GND")
	)
	(via
		(at 1.166876 -463.931)
		(size 0.7112)
		(drill 0.4064)
		(layers "F.Cu" "B.Cu")
		(net "GND")
	)
	(via
		(at 48.641 -193.04)
		(size 0.7112)
		(drill 0.4064)
		(layers "F.Cu" "B.Cu")
		(net "GND")
	)
	(via
		(at 26.543 -309.753)
		(size 0.7112)
		(drill 0.4064)
		(layers "F.Cu" "B.Cu")
		(net "GND")
	)
	(via
		(at 48.768 -138.049)
		(size 0.7112)
		(drill 0.4064)
		(layers "F.Cu" "B.Cu")
		(net "GND")
	)
	(via
		(at 1.347216 -306.832)
		(size 0.7112)
		(drill 0.4064)
		(layers "F.Cu" "B.Cu")
		(net "GND")
	)
	(via
		(at 31.75 -192.659)
		(size 0.7112)
		(drill 0.4064)
		(layers "F.Cu" "B.Cu")
		(net "GND")
	)
	(via
		(at 8.382 -400.05)
		(size 0.7112)
		(drill 0.3556)
		(layers "F.Cu" "B.Cu")
		(net "GND")
	)
	(via
		(at 31.8516 -251.968)
		(size 0.5588)
		(drill 0.3048)
		(layers "F.Cu" "B.Cu")
		(net "GND")
	)
	(via
		(at 10.16 -189.611)
		(size 0.7112)
		(drill 0.4064)
		(layers "F.Cu" "B.Cu")
		(net "GND")
	)
	(via
		(at 2.159 -314.198)
		(size 0.7112)
		(drill 0.4064)
		(layers "F.Cu" "B.Cu")
		(net "GND")
	)
	(via
		(at 8.128 -10.16)
		(size 0.7112)
		(drill 0.4064)
		(layers "F.Cu" "B.Cu")
		(net "GND")
	)
	(via
		(at 5.009134 -67.869562)
		(size 0.7112)
		(drill 0.4064)
		(layers "F.Cu" "B.Cu")
		(net "GND")
	)
	(via
		(at 29.748988 -367.792254)
		(size 0.7112)
		(drill 0.4064)
		(layers "F.Cu" "B.Cu")
		(net "GND")
	)
	(via
		(at 14.732 -306.324)
		(size 0.7112)
		(drill 0.4064)
		(layers "F.Cu" "B.Cu")
		(net "GND")
	)
	(via
		(at 4.572 -180.848)
		(size 0.7112)
		(drill 0.4064)
		(layers "F.Cu" "B.Cu")
		(net "GND")
	)
	(via
		(at 25.527 -352.806)
		(size 0.7112)
		(drill 0.4064)
		(layers "F.Cu" "B.Cu")
		(net "GND")
	)
	(via
		(at 6.858 -190.5)
		(size 0.7112)
		(drill 0.4064)
		(layers "F.Cu" "B.Cu")
		(net "GND")
	)
	(via
		(at 23.876 -362.6612)
		(size 0.7112)
		(drill 0.4064)
		(layers "F.Cu" "B.Cu")
		(net "GND")
	)
	(via
		(at 1.143 -491.744)
		(size 0.7112)
		(drill 0.4064)
		(layers "F.Cu" "B.Cu")
		(net "GND")
	)
	(via
		(at 12.2174 -216.7636)
		(size 0.7112)
		(drill 0.4064)
		(layers "F.Cu" "B.Cu")
		(net "GND")
	)
	(via
		(at 29.337 -236.22)
		(size 0.7112)
		(drill 0.4064)
		(layers "F.Cu" "B.Cu")
		(net "GND")
	)
	(via
		(at 11.938 -222.9104)
		(size 0.7112)
		(drill 0.4064)
		(layers "F.Cu" "B.Cu")
		(net "GND")
	)
	(via
		(at 37.084 -198.755)
		(size 0.5588)
		(drill 0.3048)
		(layers "F.Cu" "B.Cu")
		(net "GND")
	)
	(via
		(at 44.6532 -156.87929)
		(size 0.7112)
		(drill 0.4064)
		(layers "F.Cu" "B.Cu")
		(net "GND")
	)
	(via
		(at 38.0492 -256.2098)
		(size 0.5588)
		(drill 0.3048)
		(layers "F.Cu" "B.Cu")
		(net "GND")
	)
	(via
		(at 51.181 -96.012)
		(size 0.7112)
		(drill 0.4064)
		(layers "F.Cu" "B.Cu")
		(net "GND")
	)
	(via
		(at 40.894 -171.196)
		(size 0.5588)
		(drill 0.3048)
		(layers "F.Cu" "B.Cu")
		(net "GND")
	)
	(via
		(at 40.28313 -282.140406)
		(size 0.7112)
		(drill 0.4064)
		(layers "F.Cu" "B.Cu")
		(net "GND")
	)
	(via
		(at 3.556 -269.24)
		(size 0.7112)
		(drill 0.4064)
		(layers "F.Cu" "B.Cu")
		(net "GND")
	)
	(via
		(at 36.068 -121.539)
		(size 0.5588)
		(drill 0.3048)
		(layers "F.Cu" "B.Cu")
		(net "GND")
	)
	(via
		(at 35.306 -430.911)
		(size 0.7112)
		(drill 0.4064)
		(layers "F.Cu" "B.Cu")
		(net "GND")
	)
	(via
		(at 8.128 -353.441)
		(size 0.7112)
		(drill 0.4064)
		(layers "F.Cu" "B.Cu")
		(net "GND")
	)
	(via
		(at 13.7922 -232.537)
		(size 0.5588)
		(drill 0.3048)
		(layers "F.Cu" "B.Cu")
		(net "GND")
	)
	(via
		(at 1.420876 -250.063)
		(size 0.7112)
		(drill 0.4064)
		(layers "F.Cu" "B.Cu")
		(net "GND")
	)
	(via
		(at 1.524 -183.388)
		(size 0.7112)
		(drill 0.4064)
		(layers "F.Cu" "B.Cu")
		(net "GND")
	)
	(via
		(at 16.891 -364.109)
		(size 0.7112)
		(drill 0.4064)
		(layers "F.Cu" "B.Cu")
		(net "GND")
	)
	(via
		(at 20.066 -217.678)
		(size 0.7112)
		(drill 0.4064)
		(layers "F.Cu" "B.Cu")
		(net "GND")
	)
	(via
		(at 51.308 -194.31)
		(size 0.7112)
		(drill 0.4064)
		(layers "F.Cu" "B.Cu")
		(net "GND")
	)
	(via
		(at 33.4518 -145.0594)
		(size 0.7112)
		(drill 0.3556)
		(layers "F.Cu" "B.Cu")
		(net "GND")
	)
	(via
		(at 19.177 -237.871)
		(size 0.7112)
		(drill 0.4064)
		(layers "F.Cu" "B.Cu")
		(net "GND")
	)
	(via
		(at 10.0838 -469.0364)
		(size 0.7112)
		(drill 0.4064)
		(layers "F.Cu" "B.Cu")
		(net "GND")
	)
	(via
		(at 33.2486 -65.8114)
		(size 0.7112)
		(drill 0.4064)
		(layers "F.Cu" "B.Cu")
		(net "GND")
	)
	(via
		(at 26.797 -252.984)
		(size 0.7112)
		(drill 0.4064)
		(layers "F.Cu" "B.Cu")
		(net "GND")
	)
	(via
		(at 37.084 -209.296)
		(size 0.5588)
		(drill 0.3048)
		(layers "F.Cu" "B.Cu")
		(net "GND")
	)
	(via
		(at 34.8488 -31.3944)
		(size 0.7112)
		(drill 0.4064)
		(layers "F.Cu" "B.Cu")
		(net "GND")
	)
	(via
		(at 43.18 -276.733)
		(size 0.7112)
		(drill 0.4064)
		(layers "F.Cu" "B.Cu")
		(net "GND")
	)
	(via
		(at 30.48 -232.664)
		(size 0.7112)
		(drill 0.4064)
		(layers "F.Cu" "B.Cu")
		(net "GND")
	)
	(via
		(at 21.209 -247.9802)
		(size 0.5588)
		(drill 0.3048)
		(layers "F.Cu" "B.Cu")
		(net "GND")
	)
	(via
		(at 8.636 -237.363)
		(size 0.7112)
		(drill 0.4064)
		(layers "F.Cu" "B.Cu")
		(net "GND")
	)
	(via
		(at 11.303 -426.212)
		(size 0.5588)
		(drill 0.3048)
		(layers "F.Cu" "B.Cu")
		(net "GND")
	)
	(via
		(at 15.1384 -31.9532)
		(size 0.5588)
		(drill 0.3048)
		(layers "F.Cu" "B.Cu")
		(net "GND")
	)
	(via
		(at 32.258 -229.362)
		(size 0.7112)
		(drill 0.4064)
		(layers "F.Cu" "B.Cu")
		(net "GND")
	)
	(via
		(at 23.7744 -357.4034)
		(size 0.7112)
		(drill 0.4064)
		(layers "F.Cu" "B.Cu")
		(net "GND")
	)
	(via
		(at 3.937 -493.395)
		(size 0.7112)
		(drill 0.4064)
		(layers "F.Cu" "B.Cu")
		(net "GND")
	)
	(via
		(at 9.8298 -481.0252)
		(size 0.5588)
		(drill 0.3048)
		(layers "F.Cu" "B.Cu")
		(net "GND")
	)
	(via
		(at 14.732 -317.5)
		(size 0.7112)
		(drill 0.4064)
		(layers "F.Cu" "B.Cu")
		(net "GND")
	)
	(via
		(at 10.9728 -415.2392)
		(size 0.7112)
		(drill 0.4064)
		(layers "F.Cu" "B.Cu")
		(net "GND")
	)
	(via
		(at 49.784 -182.499)
		(size 0.7112)
		(drill 0.4064)
		(layers "F.Cu" "B.Cu")
		(net "GND")
	)
	(via
		(at 11.4046 -433.5272)
		(size 0.7112)
		(drill 0.4064)
		(layers "F.Cu" "B.Cu")
		(net "GND")
	)
	(via
		(at 51.308 -151.13)
		(size 0.7112)
		(drill 0.4064)
		(layers "F.Cu" "B.Cu")
		(net "GND")
	)
	(via
		(at 1.166876 -100.711)
		(size 0.7112)
		(drill 0.4064)
		(layers "F.Cu" "B.Cu")
		(net "GND")
	)
	(via
		(at 2.032 -172.212)
		(size 0.7112)
		(drill 0.4064)
		(layers "F.Cu" "B.Cu")
		(net "GND")
	)
	(via
		(at 51.308 -93.091)
		(size 0.7112)
		(drill 0.4064)
		(layers "F.Cu" "B.Cu")
		(net "GND")
	)
	(via
		(at 51.308 -69.596)
		(size 0.7112)
		(drill 0.4064)
		(layers "F.Cu" "B.Cu")
		(net "GND")
	)
	(via
		(at 45.72 -221.615)
		(size 0.5588)
		(drill 0.3048)
		(layers "F.Cu" "B.Cu")
		(net "GND")
	)
	(via
		(at 1.166876 -242.316)
		(size 0.7112)
		(drill 0.4064)
		(layers "F.Cu" "B.Cu")
		(net "GND")
	)
	(via
		(at 44.45 -272.415)
		(size 0.7112)
		(drill 0.4064)
		(layers "F.Cu" "B.Cu")
		(net "GND")
	)
	(via
		(at 9.525 -230.505)
		(size 0.7112)
		(drill 0.4064)
		(layers "F.Cu" "B.Cu")
		(net "GND")
	)
	(via
		(at 26.3398 -373.4562)
		(size 0.7112)
		(drill 0.4064)
		(layers "F.Cu" "B.Cu")
		(net "GND")
	)
	(via
		(at 7.493 -148.971)
		(size 0.5588)
		(drill 0.3048)
		(layers "F.Cu" "B.Cu")
		(net "GND")
	)
	(via
		(at 37.338 -342.392)
		(size 0.7112)
		(drill 0.4064)
		(layers "F.Cu" "B.Cu")
		(net "GND")
	)
	(via
		(at 11.176 -303.276)
		(size 0.7112)
		(drill 0.4064)
		(layers "F.Cu" "B.Cu")
		(net "GND")
	)
	(via
		(at 27.0002 -140.5128)
		(size 0.5588)
		(drill 0.3048)
		(layers "F.Cu" "B.Cu")
		(net "GND")
	)
	(via
		(at 51.308 -316.484)
		(size 0.5588)
		(drill 0.3048)
		(layers "F.Cu" "B.Cu")
		(net "GND")
	)
	(via
		(at 3.81 -471.1446)
		(size 0.7112)
		(drill 0.4064)
		(layers "F.Cu" "B.Cu")
		(net "GND")
	)
	(via
		(at 24.765 -358.648)
		(size 0.7112)
		(drill 0.4064)
		(layers "F.Cu" "B.Cu")
		(net "GND")
	)
	(via
		(at 23.368 -308.483)
		(size 0.7112)
		(drill 0.4064)
		(layers "F.Cu" "B.Cu")
		(net "GND")
	)
	(via
		(at 44.069 -38.481)
		(size 0.7112)
		(drill 0.4064)
		(layers "F.Cu" "B.Cu")
		(net "GND")
	)
	(via
		(at 31.75 -186.436)
		(size 0.7112)
		(drill 0.4064)
		(layers "F.Cu" "B.Cu")
		(net "GND")
	)
	(via
		(at 46.99 -171.069)
		(size 0.7112)
		(drill 0.4064)
		(layers "F.Cu" "B.Cu")
		(net "GND")
	)
	(via
		(at 49.276 -156.21)
		(size 0.7112)
		(drill 0.4064)
		(layers "F.Cu" "B.Cu")
		(net "GND")
	)
	(via
		(at 44.069 -194.056)
		(size 0.7112)
		(drill 0.4064)
		(layers "F.Cu" "B.Cu")
		(net "GND")
	)
	(via
		(at 20.096988 -143.6878)
		(size 0.7112)
		(drill 0.4064)
		(layers "F.Cu" "B.Cu")
		(net "GND")
	)
	(via
		(at 47.117 -458.343)
		(size 0.7112)
		(drill 0.4064)
		(layers "F.Cu" "B.Cu")
		(net "GND")
	)
	(via
		(at 48.7426 -42.5958)
		(size 0.7112)
		(drill 0.4064)
		(layers "F.Cu" "B.Cu")
		(net "GND")
	)
	(via
		(at 35.179 -438.785)
		(size 0.7112)
		(drill 0.4064)
		(layers "F.Cu" "B.Cu")
		(net "GND")
	)
	(via
		(at 51.181 -140.335)
		(size 0.7112)
		(drill 0.4064)
		(layers "F.Cu" "B.Cu")
		(net "GND")
	)
	(via
		(at 26.797 -178.435)
		(size 0.5588)
		(drill 0.3048)
		(layers "F.Cu" "B.Cu")
		(net "GND")
	)
	(via
		(at 10.033 -312.674)
		(size 0.7112)
		(drill 0.4064)
		(layers "F.Cu" "B.Cu")
		(net "GND")
	)
	(via
		(at 47.625 -85.852)
		(size 0.7112)
		(drill 0.4064)
		(layers "F.Cu" "B.Cu")
		(net "GND")
	)
	(via
		(at 42.291 -162.56)
		(size 0.7112)
		(drill 0.3556)
		(layers "F.Cu" "B.Cu")
		(net "GND")
	)
	(via
		(at 1.347216 -437.769)
		(size 0.7112)
		(drill 0.4064)
		(layers "F.Cu" "B.Cu")
		(net "GND")
	)
	(via
		(at 31.5468 -144.3736)
		(size 0.5588)
		(drill 0.3048)
		(layers "F.Cu" "B.Cu")
		(net "GND")
	)
	(via
		(at 8.5217 -274.3454)
		(size 0.7112)
		(drill 0.4064)
		(layers "F.Cu" "B.Cu")
		(net "GND")
	)
	(via
		(at 6.7945 -454.9394)
		(size 0.5588)
		(drill 0.3048)
		(layers "F.Cu" "B.Cu")
		(net "GND")
	)
	(via
		(at 33.5788 -361.8992)
		(size 0.7112)
		(drill 0.4064)
		(layers "F.Cu" "B.Cu")
		(net "GND")
	)
	(via
		(at 46.736 -14.097)
		(size 0.7112)
		(drill 0.4064)
		(layers "F.Cu" "B.Cu")
		(net "GND")
	)
	(via
		(at 11.1506 -34.8488)
		(size 0.7112)
		(drill 0.3556)
		(layers "F.Cu" "B.Cu")
		(net "GND")
	)
	(via
		(at 4.064 -240.792)
		(size 0.7112)
		(drill 0.4064)
		(layers "F.Cu" "B.Cu")
		(net "GND")
	)
	(via
		(at 49.53 -282.448)
		(size 0.5588)
		(drill 0.3048)
		(layers "F.Cu" "B.Cu")
		(net "GND")
	)
	(via
		(at 8.001 -477.139)
		(size 0.7112)
		(drill 0.4064)
		(layers "F.Cu" "B.Cu")
		(net "GND")
	)
	(via
		(at 8.128 -169.164)
		(size 0.7112)
		(drill 0.4064)
		(layers "F.Cu" "B.Cu")
		(net "GND")
	)
	(via
		(at 48.133 -400.558)
		(size 0.7112)
		(drill 0.4064)
		(layers "F.Cu" "B.Cu")
		(net "GND")
	)
	(via
		(at 1.143 -217.805)
		(size 0.7112)
		(drill 0.4064)
		(layers "F.Cu" "B.Cu")
		(net "GND")
	)
	(via
		(at 14.097 -245.872)
		(size 0.7112)
		(drill 0.4064)
		(layers "F.Cu" "B.Cu")
		(net "GND")
	)
	(via
		(at 13.1318 -33.4518)
		(size 0.7112)
		(drill 0.4064)
		(layers "F.Cu" "B.Cu")
		(net "GND")
	)
	(via
		(at 43.561 -208.153)
		(size 0.7112)
		(drill 0.4064)
		(layers "F.Cu" "B.Cu")
		(net "GND")
	)
	(via
		(at 51.181 -358.902)
		(size 0.5588)
		(drill 0.3048)
		(layers "F.Cu" "B.Cu")
		(net "GND")
	)
	(via
		(at 32.004 -242.316)
		(size 0.7112)
		(drill 0.4064)
		(layers "F.Cu" "B.Cu")
		(net "GND")
	)
	(via
		(at 11.2776 -404.3934)
		(size 0.7112)
		(drill 0.4064)
		(layers "F.Cu" "B.Cu")
		(net "GND")
	)
	(via
		(at 21.463 -14.351)
		(size 0.5588)
		(drill 0.3048)
		(layers "F.Cu" "B.Cu")
		(net "GND")
	)
	(via
		(at 49.0474 -172.466)
		(size 0.7112)
		(drill 0.4064)
		(layers "F.Cu" "B.Cu")
		(net "GND")
	)
	(via
		(at 21.717 -229.362)
		(size 0.7112)
		(drill 0.4064)
		(layers "F.Cu" "B.Cu")
		(net "GND")
	)
	(via
		(at 10.3886 -228.981)
		(size 0.7112)
		(drill 0.4064)
		(layers "F.Cu" "B.Cu")
		(net "GND")
	)
	(via
		(at 24.257 -372.872)
		(size 0.7112)
		(drill 0.4064)
		(layers "F.Cu" "B.Cu")
		(net "GND")
	)
	(via
		(at 30.226 -171.0182)
		(size 0.7112)
		(drill 0.4064)
		(layers "F.Cu" "B.Cu")
		(net "GND")
	)
	(via
		(at 27.206702 -171.196254)
		(size 0.7112)
		(drill 0.4064)
		(layers "F.Cu" "B.Cu")
		(net "GND")
	)
	(via
		(at 6.604 -109.855)
		(size 0.7112)
		(drill 0.4064)
		(layers "F.Cu" "B.Cu")
		(net "GND")
	)
	(via
		(at 43.688 -192.405)
		(size 0.7112)
		(drill 0.4064)
		(layers "F.Cu" "B.Cu")
		(net "GND")
	)
	(via
		(at 43.18 -280.162)
		(size 0.7112)
		(drill 0.4064)
		(layers "F.Cu" "B.Cu")
		(net "GND")
	)
	(via
		(at 6.858 -94.234)
		(size 0.7112)
		(drill 0.4064)
		(layers "F.Cu" "B.Cu")
		(net "GND")
	)
	(via
		(at 46.228 -432.816)
		(size 0.7112)
		(drill 0.4064)
		(layers "F.Cu" "B.Cu")
		(net "GND")
	)
	(via
		(at 4.572 -233.68)
		(size 0.7112)
		(drill 0.4064)
		(layers "F.Cu" "B.Cu")
		(net "GND")
	)
	(via
		(at 51.181 -251.714)
		(size 0.5588)
		(drill 0.3048)
		(layers "F.Cu" "B.Cu")
		(net "GND")
	)
	(via
		(at 1.524 -318.008)
		(size 0.7112)
		(drill 0.4064)
		(layers "F.Cu" "B.Cu")
		(net "GND")
	)
	(via
		(at 8.5344 -261.5946)
		(size 0.7112)
		(drill 0.4064)
		(layers "F.Cu" "B.Cu")
		(net "GND")
	)
	(via
		(at 6.2992 -489.331)
		(size 0.7112)
		(drill 0.4064)
		(layers "F.Cu" "B.Cu")
		(net "GND")
	)
	(via
		(at 40.767 -476.885)
		(size 0.7112)
		(drill 0.4064)
		(layers "F.Cu" "B.Cu")
		(net "GND")
	)
	(via
		(at 17.5514 -177.293524)
		(size 0.7112)
		(drill 0.4064)
		(layers "F.Cu" "B.Cu")
		(net "GND")
	)
	(via
		(at 29.591 -263.017)
		(size 0.7112)
		(drill 0.4064)
		(layers "F.Cu" "B.Cu")
		(net "GND")
	)
	(via
		(at 51.054 -281.051)
		(size 0.7112)
		(drill 0.4064)
		(layers "F.Cu" "B.Cu")
		(net "GND")
	)
	(via
		(at 11.303 -350.647)
		(size 0.5588)
		(drill 0.3048)
		(layers "F.Cu" "B.Cu")
		(net "GND")
	)
	(via
		(at 8.636 -279.908)
		(size 0.7112)
		(drill 0.4064)
		(layers "F.Cu" "B.Cu")
		(net "GND")
	)
	(via
		(at 1.347216 -235.204)
		(size 0.7112)
		(drill 0.4064)
		(layers "F.Cu" "B.Cu")
		(net "GND")
	)
	(via
		(at 37.338 -321.437)
		(size 0.7112)
		(drill 0.4064)
		(layers "F.Cu" "B.Cu")
		(net "GND")
	)
	(via
		(at 41.656 -14.097)
		(size 0.7112)
		(drill 0.4064)
		(layers "F.Cu" "B.Cu")
		(net "GND")
	)
	(via
		(at 20.955 -206.756)
		(size 0.7112)
		(drill 0.4064)
		(layers "F.Cu" "B.Cu")
		(net "GND")
	)
	(via
		(at 46.99 -11.43)
		(size 0.7112)
		(drill 0.4064)
		(layers "F.Cu" "B.Cu")
		(net "GND")
	)
	(via
		(at 20.828 -165.608)
		(size 0.5588)
		(drill 0.3048)
		(layers "F.Cu" "B.Cu")
		(net "GND")
	)
	(via
		(at 45.72 -231.775)
		(size 0.5588)
		(drill 0.3048)
		(layers "F.Cu" "B.Cu")
		(net "GND")
	)
	(via
		(at 33.02 -191.262)
		(size 0.5588)
		(drill 0.3048)
		(layers "F.Cu" "B.Cu")
		(net "GND")
	)
	(via
		(at 1.293876 -227.965)
		(size 0.7112)
		(drill 0.4064)
		(layers "F.Cu" "B.Cu")
		(net "GND")
	)
	(via
		(at 45.593 -224.536)
		(size 0.5588)
		(drill 0.3048)
		(layers "F.Cu" "B.Cu")
		(net "GND")
	)
	(via
		(at 46.3804 -138.9126)
		(size 0.7112)
		(drill 0.4064)
		(layers "F.Cu" "B.Cu")
		(net "GND")
	)
	(via
		(at 8.7376 -24.2062)
		(size 0.7112)
		(drill 0.4064)
		(layers "F.Cu" "B.Cu")
		(net "GND")
	)
	(via
		(at 1.166876 -30.607)
		(size 0.7112)
		(drill 0.4064)
		(layers "F.Cu" "B.Cu")
		(net "GND")
	)
	(via
		(at 13.208 -29.3624)
		(size 0.7112)
		(drill 0.4064)
		(layers "F.Cu" "B.Cu")
		(net "GND")
	)
	(via
		(at 23.0632 -338.1248)
		(size 0.7112)
		(drill 0.4064)
		(layers "F.Cu" "B.Cu")
		(net "GND")
	)
	(via
		(at 31.496 -343.408)
		(size 0.7112)
		(drill 0.4064)
		(layers "F.Cu" "B.Cu")
		(net "GND")
	)
	(via
		(at 1.4986 -460.7814)
		(size 0.7112)
		(drill 0.4064)
		(layers "F.Cu" "B.Cu")
		(net "GND")
	)
	(via
		(at 21.971 -236.728)
		(size 0.7112)
		(drill 0.4064)
		(layers "F.Cu" "B.Cu")
		(net "GND")
	)
	(via
		(at 49.53 -170.18)
		(size 0.7112)
		(drill 0.4064)
		(layers "F.Cu" "B.Cu")
		(net "GND")
	)
	(via
		(at 1.166876 -483.108)
		(size 0.7112)
		(drill 0.4064)
		(layers "F.Cu" "B.Cu")
		(net "GND")
	)
	(via
		(at 6.7818 -401.2692)
		(size 0.7112)
		(drill 0.4064)
		(layers "F.Cu" "B.Cu")
		(net "GND")
	)
	(via
		(at 44.45 -199.771)
		(size 0.7112)
		(drill 0.4064)
		(layers "F.Cu" "B.Cu")
		(net "GND")
	)
	(via
		(at 46.101 -187.579)
		(size 0.7112)
		(drill 0.4064)
		(layers "F.Cu" "B.Cu")
		(net "GND")
	)
	(via
		(at 3.556 -279.4)
		(size 0.7112)
		(drill 0.4064)
		(layers "F.Cu" "B.Cu")
		(net "GND")
	)
	(via
		(at 23.8252 -353.8728)
		(size 0.7112)
		(drill 0.4064)
		(layers "F.Cu" "B.Cu")
		(net "GND")
	)
	(via
		(at 28.067 -103.251)
		(size 0.7112)
		(drill 0.4064)
		(layers "F.Cu" "B.Cu")
		(net "GND")
	)
	(via
		(at 10.9474 -219.9894)
		(size 0.7112)
		(drill 0.3556)
		(layers "F.Cu" "B.Cu")
		(net "GND")
	)
	(via
		(at 9.652 -208.28)
		(size 0.7112)
		(drill 0.4064)
		(layers "F.Cu" "B.Cu")
		(net "GND")
	)
	(via
		(at 17.8689 -141.9479)
		(size 0.5588)
		(drill 0.3048)
		(layers "F.Cu" "B.Cu")
		(net "GND")
	)
	(via
		(at 3.175 -497.586)
		(size 0.7112)
		(drill 0.4064)
		(layers "F.Cu" "B.Cu")
		(net "GND")
	)
	(via
		(at 32.9692 -176.9872)
		(size 0.7112)
		(drill 0.4064)
		(layers "F.Cu" "B.Cu")
		(net "GND")
	)
	(via
		(at 16.51 -142.621)
		(size 0.5588)
		(drill 0.3048)
		(layers "F.Cu" "B.Cu")
		(net "GND")
	)
	(via
		(at 15.3924 -361.5944)
		(size 0.7112)
		(drill 0.4064)
		(layers "F.Cu" "B.Cu")
		(net "GND")
	)
	(via
		(at 4.064 -206.756)
		(size 0.7112)
		(drill 0.4064)
		(layers "F.Cu" "B.Cu")
		(net "GND")
	)
	(via
		(at 1.166876 -408.305)
		(size 0.7112)
		(drill 0.4064)
		(layers "F.Cu" "B.Cu")
		(net "GND")
	)
	(via
		(at 40.259 -273.2532)
		(size 0.7112)
		(drill 0.4064)
		(layers "F.Cu" "B.Cu")
		(net "GND")
	)
	(via
		(at 11.684 -488.442)
		(size 0.7112)
		(drill 0.4064)
		(layers "F.Cu" "B.Cu")
		(net "GND")
	)
	(via
		(at 1.293876 -344.043)
		(size 0.5588)
		(drill 0.3048)
		(layers "F.Cu" "B.Cu")
		(net "GND")
	)
	(via
		(at 10.541 -479.933)
		(size 0.5588)
		(drill 0.3048)
		(layers "F.Cu" "B.Cu")
		(net "GND")
	)
	(via
		(at 1.524 -283.972)
		(size 0.7112)
		(drill 0.4064)
		(layers "F.Cu" "B.Cu")
		(net "GND")
	)
	(via
		(at 48.8696 -134.4676)
		(size 0.7112)
		(drill 0.4064)
		(layers "F.Cu" "B.Cu")
		(net "GND")
	)
	(via
		(at 40.005 -217.932)
		(size 0.7112)
		(drill 0.4064)
		(layers "F.Cu" "B.Cu")
		(net "GND")
	)
	(via
		(at 31.115 -177.927)
		(size 0.5588)
		(drill 0.3048)
		(layers "F.Cu" "B.Cu")
		(net "GND")
	)
	(via
		(at 1.347216 -386.6134)
		(size 0.7112)
		(drill 0.4064)
		(layers "F.Cu" "B.Cu")
		(net "GND")
	)
	(via
		(at 26.543 -278.13)
		(size 0.7112)
		(drill 0.4064)
		(layers "F.Cu" "B.Cu")
		(net "GND")
	)
	(via
		(at 1.166876 -158.75)
		(size 0.7112)
		(drill 0.4064)
		(layers "F.Cu" "B.Cu")
		(net "GND")
	)
	(via
		(at 21.1836 -223.1644)
		(size 0.7112)
		(drill 0.4064)
		(layers "F.Cu" "B.Cu")
		(net "GND")
	)
	(via
		(at 51.181 -184.531)
		(size 0.5588)
		(drill 0.3048)
		(layers "F.Cu" "B.Cu")
		(net "GND")
	)
	(via
		(at 22.17674 -171.906184)
		(size 0.7112)
		(drill 0.4064)
		(layers "F.Cu" "B.Cu")
		(net "GND")
	)
	(via
		(at 4.064 -315.976)
		(size 0.7112)
		(drill 0.4064)
		(layers "F.Cu" "B.Cu")
		(net "GND")
	)
	(via
		(at 51.181 -138.303)
		(size 0.7112)
		(drill 0.4064)
		(layers "F.Cu" "B.Cu")
		(net "GND")
	)
	(via
		(at 38.735 -478.3074)
		(size 0.5588)
		(drill 0.3048)
		(layers "F.Cu" "B.Cu")
		(net "GND")
	)
	(via
		(at 31.369 -207.264)
		(size 0.7112)
		(drill 0.4064)
		(layers "F.Cu" "B.Cu")
		(net "GND")
	)
	(via
		(at 10.16 -329.692)
		(size 0.7112)
		(drill 0.4064)
		(layers "F.Cu" "B.Cu")
		(net "GND")
	)
	(via
		(at 41.275 -450.342)
		(size 0.7112)
		(drill 0.4064)
		(layers "F.Cu" "B.Cu")
		(net "GND")
	)
	(via
		(at 8.4074 -403.1996)
		(size 0.7112)
		(drill 0.4064)
		(layers "F.Cu" "B.Cu")
		(net "GND")
	)
	(via
		(at 33.02 -187.071)
		(size 0.7112)
		(drill 0.4064)
		(layers "F.Cu" "B.Cu")
		(net "GND")
	)
	(via
		(at 22.098 -164.592)
		(size 0.5588)
		(drill 0.3048)
		(layers "F.Cu" "B.Cu")
		(net "GND")
	)
	(via
		(at 6.236462 -292.924738)
		(size 0.7112)
		(drill 0.4064)
		(layers "F.Cu" "B.Cu")
		(net "GND")
	)
	(via
		(at 49.53 -275.971)
		(size 0.7112)
		(drill 0.4064)
		(layers "F.Cu" "B.Cu")
		(net "GND")
	)
	(via
		(at 1.1938 -425.7294)
		(size 0.7112)
		(drill 0.4064)
		(layers "F.Cu" "B.Cu")
		(net "GND")
	)
	(via
		(at 47.7774 -175.0314)
		(size 0.7112)
		(drill 0.4064)
		(layers "F.Cu" "B.Cu")
		(net "GND")
	)
	(via
		(at 9.398 -435.356)
		(size 0.7112)
		(drill 0.3556)
		(layers "F.Cu" "B.Cu")
		(net "GND")
	)
	(via
		(at 14.986 -366.903)
		(size 0.7112)
		(drill 0.4064)
		(layers "F.Cu" "B.Cu")
		(net "GND")
	)
	(via
		(at 4.064 -262.128)
		(size 0.7112)
		(drill 0.4064)
		(layers "F.Cu" "B.Cu")
		(net "GND")
	)
	(via
		(at 1.347216 -391.287)
		(size 0.7112)
		(drill 0.4064)
		(layers "F.Cu" "B.Cu")
		(net "GND")
	)
	(via
		(at 1.166876 -450.85)
		(size 0.7112)
		(drill 0.4064)
		(layers "F.Cu" "B.Cu")
		(net "GND")
	)
	(via
		(at 46.863 -487.807)
		(size 0.5588)
		(drill 0.3048)
		(layers "F.Cu" "B.Cu")
		(net "GND")
	)
	(via
		(at 31.623 -209.5754)
		(size 0.7112)
		(drill 0.4064)
		(layers "F.Cu" "B.Cu")
		(net "GND")
	)
	(via
		(at 7.8232 -356.5906)
		(size 0.7112)
		(drill 0.4064)
		(layers "F.Cu" "B.Cu")
		(net "GND")
	)
	(via
		(at 39.243 -235.331)
		(size 0.7112)
		(drill 0.4064)
		(layers "F.Cu" "B.Cu")
		(net "GND")
	)
	(via
		(at 3.556 -167.386)
		(size 0.7112)
		(drill 0.4064)
		(layers "F.Cu" "B.Cu")
		(net "GND")
	)
	(via
		(at 16.8148 -165.989)
		(size 0.5588)
		(drill 0.3048)
		(layers "F.Cu" "B.Cu")
		(net "GND")
	)
	(via
		(at 1.27 -125.73)
		(size 0.7112)
		(drill 0.4064)
		(layers "F.Cu" "B.Cu")
		(net "GND")
	)
	(via
		(at 16.129 -489.712)
		(size 0.7112)
		(drill 0.4064)
		(layers "F.Cu" "B.Cu")
		(net "GND")
	)
	(via
		(at 15.494 -297.942)
		(size 0.7112)
		(drill 0.4064)
		(layers "F.Cu" "B.Cu")
		(net "GND")
	)
	(via
		(at 25.7302 -99.0854)
		(size 0.7112)
		(drill 0.4064)
		(layers "F.Cu" "B.Cu")
		(net "GND")
	)
	(via
		(at 42.291 -196.977)
		(size 0.5588)
		(drill 0.3048)
		(layers "F.Cu" "B.Cu")
		(net "GND")
	)
	(via
		(at 1.143 -239.141)
		(size 0.7112)
		(drill 0.4064)
		(layers "F.Cu" "B.Cu")
		(net "GND")
	)
	(via
		(at 48.7172 -56.1594)
		(size 0.7112)
		(drill 0.4064)
		(layers "F.Cu" "B.Cu")
		(net "GND")
	)
	(via
		(at 5.842 -172.085)
		(size 0.7112)
		(drill 0.4064)
		(layers "F.Cu" "B.Cu")
		(net "GND")
	)
	(via
		(at 11.5824 -210.185)
		(size 0.7112)
		(drill 0.4064)
		(layers "F.Cu" "B.Cu")
		(net "GND")
	)
	(via
		(at 4.318 -9.271)
		(size 0.7112)
		(drill 0.4064)
		(layers "F.Cu" "B.Cu")
		(net "GND")
	)
	(via
		(at 51.181 -197.358)
		(size 0.5588)
		(drill 0.3048)
		(layers "F.Cu" "B.Cu")
		(net "GND")
	)
	(via
		(at 51.36134 -162.179)
		(size 0.5588)
		(drill 0.3048)
		(layers "F.Cu" "B.Cu")
		(net "GND")
	)
	(via
		(at 5.08 -176.784)
		(size 0.7112)
		(drill 0.4064)
		(layers "F.Cu" "B.Cu")
		(net "GND")
	)
	(via
		(at 26.416 -186.436)
		(size 0.7112)
		(drill 0.3556)
		(layers "F.Cu" "B.Cu")
		(net "GND")
	)
	(via
		(at 18.3642 -373.3292)
		(size 0.7112)
		(drill 0.4064)
		(layers "F.Cu" "B.Cu")
		(net "GND")
	)
	(via
		(at 11.557 -355.6)
		(size 0.5588)
		(drill 0.3048)
		(layers "F.Cu" "B.Cu")
		(net "GND")
	)
	(via
		(at 1.293876 -119.253)
		(size 0.7112)
		(drill 0.4064)
		(layers "F.Cu" "B.Cu")
		(net "GND")
	)
	(via
		(at 17.7292 -145.8468)
		(size 0.7112)
		(drill 0.4064)
		(layers "F.Cu" "B.Cu")
		(net "GND")
	)
	(via
		(at 51.181 -291.338)
		(size 0.5588)
		(drill 0.3048)
		(layers "F.Cu" "B.Cu")
		(net "GND")
	)
	(via
		(at 9.398 -31.496)
		(size 0.7112)
		(drill 0.4064)
		(layers "F.Cu" "B.Cu")
		(net "GND")
	)
	(via
		(at 48.641 -405.13)
		(size 0.7112)
		(drill 0.4064)
		(layers "F.Cu" "B.Cu")
		(net "GND")
	)
	(via
		(at 48.768 -240.919)
		(size 0.7112)
		(drill 0.4064)
		(layers "F.Cu" "B.Cu")
		(net "GND")
	)
	(via
		(at 13.6652 -255.5748)
		(size 0.5588)
		(drill 0.3048)
		(layers "F.Cu" "B.Cu")
		(net "GND")
	)
	(via
		(at 46.101 -435.991)
		(size 0.7112)
		(drill 0.4064)
		(layers "F.Cu" "B.Cu")
		(net "GND")
	)
	(via
		(at 45.6692 -239.1156)
		(size 0.5588)
		(drill 0.3048)
		(layers "F.Cu" "B.Cu")
		(net "GND")
	)
	(via
		(at 30.48 -182.245)
		(size 0.7112)
		(drill 0.4064)
		(layers "F.Cu" "B.Cu")
		(net "GND")
	)
	(via
		(at 13.462 -1.27)
		(size 0.7112)
		(drill 0.4064)
		(layers "F.Cu" "B.Cu")
		(net "GND")
	)
	(via
		(at 14.0462 -497.6114)
		(size 0.7112)
		(drill 0.4064)
		(layers "F.Cu" "B.Cu")
		(net "GND")
	)
	(via
		(at 1.143 -261.493)
		(size 0.7112)
		(drill 0.4064)
		(layers "F.Cu" "B.Cu")
		(net "GND")
	)
	(via
		(at 26.67 -39.37)
		(size 0.7112)
		(drill 0.4064)
		(layers "F.Cu" "B.Cu")
		(net "GND")
	)
	(via
		(at 36.576 -233.553)
		(size 0.7112)
		(drill 0.4064)
		(layers "F.Cu" "B.Cu")
		(net "GND")
	)
	(via
		(at 51.308 -83.312)
		(size 0.7112)
		(drill 0.4064)
		(layers "F.Cu" "B.Cu")
		(net "GND")
	)
	(via
		(at 6.9596 -482.4476)
		(size 0.5588)
		(drill 0.3048)
		(layers "F.Cu" "B.Cu")
		(net "GND")
	)
	(via
		(at 22.352 -148.971)
		(size 0.5588)
		(drill 0.3048)
		(layers "F.Cu" "B.Cu")
		(net "GND")
	)
	(via
		(at 20.066 -16.637)
		(size 0.5588)
		(drill 0.3048)
		(layers "F.Cu" "B.Cu")
		(net "GND")
	)
	(via
		(at 35.306 -434.975)
		(size 0.7112)
		(drill 0.4064)
		(layers "F.Cu" "B.Cu")
		(net "GND")
	)
	(via
		(at 48.871886 -106.08437)
		(size 0.7112)
		(drill 0.4064)
		(layers "F.Cu" "B.Cu")
		(net "GND")
	)
	(via
		(at 23.876 -246.8372)
		(size 0.5588)
		(drill 0.3048)
		(layers "F.Cu" "B.Cu")
		(net "GND")
	)
	(via
		(at 18.14703 -135.176768)
		(size 0.5588)
		(drill 0.3048)
		(layers "F.Cu" "B.Cu")
		(net "GND")
	)
	(via
		(at 48.387 -26.67)
		(size 0.7112)
		(drill 0.4064)
		(layers "F.Cu" "B.Cu")
		(net "GND")
	)
	(via
		(at 42.926 -202.057)
		(size 0.7112)
		(drill 0.4064)
		(layers "F.Cu" "B.Cu")
		(net "GND")
	)
	(via
		(at 7.874 -325.247)
		(size 0.7112)
		(drill 0.3556)
		(layers "F.Cu" "B.Cu")
		(net "GND")
	)
	(via
		(at 18.669 -185.928)
		(size 0.5588)
		(drill 0.3048)
		(layers "F.Cu" "B.Cu")
		(net "GND")
	)
	(via
		(at 8.636 -372.3386)
		(size 0.7112)
		(drill 0.4064)
		(layers "F.Cu" "B.Cu")
		(net "GND")
	)
	(via
		(at 16.764 -291.973)
		(size 0.7112)
		(drill 0.4064)
		(layers "F.Cu" "B.Cu")
		(net "GND")
	)
	(via
		(at 1.166876 -190.246)
		(size 0.5588)
		(drill 0.3048)
		(layers "F.Cu" "B.Cu")
		(net "GND")
	)
	(via
		(at 4.7244 -63.2714)
		(size 0.7112)
		(drill 0.3556)
		(layers "F.Cu" "B.Cu")
		(net "GND")
	)
	(via
		(at 13.716 -489.839)
		(size 0.7112)
		(drill 0.4064)
		(layers "F.Cu" "B.Cu")
		(net "GND")
	)
	(via
		(at 9.652 -338.836)
		(size 0.7112)
		(drill 0.4064)
		(layers "F.Cu" "B.Cu")
		(net "GND")
	)
	(via
		(at 42.1386 -182.1942)
		(size 0.5588)
		(drill 0.3048)
		(layers "F.Cu" "B.Cu")
		(net "GND")
	)
	(via
		(at 14.986 -373.888)
		(size 0.7112)
		(drill 0.4064)
		(layers "F.Cu" "B.Cu")
		(net "GND")
	)
	(via
		(at 9.7282 -401.2184)
		(size 0.7112)
		(drill 0.4064)
		(layers "F.Cu" "B.Cu")
		(net "GND")
	)
	(via
		(at 36.83 -11.43)
		(size 0.7112)
		(drill 0.4064)
		(layers "F.Cu" "B.Cu")
		(net "GND")
	)
	(via
		(at 1.293876 -145.923)
		(size 0.5588)
		(drill 0.3048)
		(layers "F.Cu" "B.Cu")
		(net "GND")
	)
	(via
		(at 9.144 -185.42)
		(size 0.7112)
		(drill 0.4064)
		(layers "F.Cu" "B.Cu")
		(net "GND")
	)
	(via
		(at 45.72 -217.424)
		(size 0.5588)
		(drill 0.3048)
		(layers "F.Cu" "B.Cu")
		(net "GND")
	)
	(via
		(at 13.4874 -363.3978)
		(size 0.7112)
		(drill 0.4064)
		(layers "F.Cu" "B.Cu")
		(net "GND")
	)
	(via
		(at 23.876 -231.267)
		(size 0.7112)
		(drill 0.4064)
		(layers "F.Cu" "B.Cu")
		(net "GND")
	)
	(via
		(at 30.48 -281.432)
		(size 0.7112)
		(drill 0.4064)
		(layers "F.Cu" "B.Cu")
		(net "GND")
	)
	(via
		(at 17.9832 -251.587)
		(size 0.5588)
		(drill 0.3048)
		(layers "F.Cu" "B.Cu")
		(net "GND")
	)
	(via
		(at 21.209 -247.0912)
		(size 0.5588)
		(drill 0.3048)
		(layers "F.Cu" "B.Cu")
		(net "GND")
	)
	(via
		(at 32.258 -32.766)
		(size 0.7112)
		(drill 0.3556)
		(layers "F.Cu" "B.Cu")
		(net "GND")
	)
	(via
		(at 29.845 -259.969)
		(size 0.7112)
		(drill 0.4064)
		(layers "F.Cu" "B.Cu")
		(net "GND")
	)
	(via
		(at 3.429 -77.089)
		(size 0.7112)
		(drill 0.4064)
		(layers "F.Cu" "B.Cu")
		(net "GND")
	)
	(via
		(at 7.3152 -135.5598)
		(size 0.5588)
		(drill 0.3048)
		(layers "F.Cu" "B.Cu")
		(net "GND")
	)
	(via
		(at 22.7838 -358.0638)
		(size 0.7112)
		(drill 0.4064)
		(layers "F.Cu" "B.Cu")
		(net "GND")
	)
	(via
		(at 51.308 -67.056)
		(size 0.7112)
		(drill 0.4064)
		(layers "F.Cu" "B.Cu")
		(net "GND")
	)
	(via
		(at 15.113 -223.9264)
		(size 0.5588)
		(drill 0.3048)
		(layers "F.Cu" "B.Cu")
		(net "GND")
	)
	(via
		(at 32.004 -236.22)
		(size 0.7112)
		(drill 0.4064)
		(layers "F.Cu" "B.Cu")
		(net "GND")
	)
	(via
		(at 19.0246 -357.8352)
		(size 0.7112)
		(drill 0.4064)
		(layers "F.Cu" "B.Cu")
		(net "GND")
	)
	(via
		(at 24.13 -39.37)
		(size 0.7112)
		(drill 0.4064)
		(layers "F.Cu" "B.Cu")
		(net "GND")
	)
	(via
		(at 51.308 -390.525)
		(size 0.5588)
		(drill 0.3048)
		(layers "F.Cu" "B.Cu")
		(net "GND")
	)
	(via
		(at 48.641 -189.611)
		(size 0.7112)
		(drill 0.4064)
		(layers "F.Cu" "B.Cu")
		(net "GND")
	)
	(via
		(at 24.765 -482.854)
		(size 0.7112)
		(drill 0.3556)
		(layers "F.Cu" "B.Cu")
		(net "GND")
	)
	(via
		(at 46.863 -82.677)
		(size 0.7112)
		(drill 0.4064)
		(layers "F.Cu" "B.Cu")
		(net "GND")
	)
	(via
		(at 36.0934 -147.6756)
		(size 0.5588)
		(drill 0.3048)
		(layers "F.Cu" "B.Cu")
		(net "GND")
	)
	(via
		(at 24.13 -34.036)
		(size 0.7112)
		(drill 0.4064)
		(layers "F.Cu" "B.Cu")
		(net "GND")
	)
	(via
		(at 19.4056 -253.7714)
		(size 0.7112)
		(drill 0.4064)
		(layers "F.Cu" "B.Cu")
		(net "GND")
	)
	(via
		(at 4.064 -247.904)
		(size 0.7112)
		(drill 0.4064)
		(layers "F.Cu" "B.Cu")
		(net "GND")
	)
	(via
		(at 29.724096 -368.808)
		(size 0.7112)
		(drill 0.4064)
		(layers "F.Cu" "B.Cu")
		(net "GND")
	)
	(via
		(at 34.29 -12.7)
		(size 0.7112)
		(drill 0.4064)
		(layers "F.Cu" "B.Cu")
		(net "GND")
	)
	(via
		(at 51.076606 -141.732)
		(size 0.7112)
		(drill 0.4064)
		(layers "F.Cu" "B.Cu")
		(net "GND")
	)
	(via
		(at 34.798 -363.0168)
		(size 0.7112)
		(drill 0.4064)
		(layers "F.Cu" "B.Cu")
		(net "GND")
	)
	(via
		(at 6.731 -111.76)
		(size 0.7112)
		(drill 0.4064)
		(layers "F.Cu" "B.Cu")
		(net "GND")
	)
	(via
		(at 37.465 -301.244)
		(size 0.7112)
		(drill 0.4064)
		(layers "F.Cu" "B.Cu")
		(net "GND")
	)
	(via
		(at 29.845 -317.754)
		(size 0.7112)
		(drill 0.4064)
		(layers "F.Cu" "B.Cu")
		(net "GND")
	)
	(via
		(at 42.037 -172.085)
		(size 0.7112)
		(drill 0.4064)
		(layers "F.Cu" "B.Cu")
		(net "GND")
	)
	(via
		(at 50.9778 -342.519)
		(size 0.5588)
		(drill 0.3048)
		(layers "F.Cu" "B.Cu")
		(net "GND")
	)
	(via
		(at 14.605 -250.0122)
		(size 0.5588)
		(drill 0.3048)
		(layers "F.Cu" "B.Cu")
		(net "GND")
	)
	(via
		(at 26.797 -99.06)
		(size 0.7112)
		(drill 0.4064)
		(layers "F.Cu" "B.Cu")
		(net "GND")
	)
	(via
		(at 29.718 -256.159)
		(size 0.7112)
		(drill 0.4064)
		(layers "F.Cu" "B.Cu")
		(net "GND")
	)
	(via
		(at 19.9136 -148.2598)
		(size 0.5588)
		(drill 0.3048)
		(layers "F.Cu" "B.Cu")
		(net "GND")
	)
	(via
		(at 46.99 -214.249)
		(size 0.7112)
		(drill 0.4064)
		(layers "F.Cu" "B.Cu")
		(net "GND")
	)
	(via
		(at 13.843 -263.017)
		(size 0.5588)
		(drill 0.3048)
		(layers "F.Cu" "B.Cu")
		(net "GND")
	)
	(via
		(at 26.289 -261.239)
		(size 0.7112)
		(drill 0.4064)
		(layers "F.Cu" "B.Cu")
		(net "GND")
	)
	(via
		(at 51.308 -267.208)
		(size 0.5588)
		(drill 0.3048)
		(layers "F.Cu" "B.Cu")
		(net "GND")
	)
	(via
		(at 38.608 -434.49494)
		(size 0.7112)
		(drill 0.4064)
		(layers "F.Cu" "B.Cu")
		(net "GND")
	)
	(via
		(at 41.489376 -300.0248)
		(size 0.7112)
		(drill 0.4064)
		(layers "F.Cu" "B.Cu")
		(net "GND")
	)
	(via
		(at 1.27 -473.4814)
		(size 0.7112)
		(drill 0.4064)
		(layers "F.Cu" "B.Cu")
		(net "GND")
	)
	(via
		(at 14.859 -280.543)
		(size 0.7112)
		(drill 0.3556)
		(layers "F.Cu" "B.Cu")
		(net "GND")
	)
	(via
		(at 1.524 -185.547)
		(size 0.7112)
		(drill 0.4064)
		(layers "F.Cu" "B.Cu")
		(net "GND")
	)
	(via
		(at 21.336 -343.408)
		(size 0.7112)
		(drill 0.4064)
		(layers "F.Cu" "B.Cu")
		(net "GND")
	)
	(via
		(at 30.607 -186.055)
		(size 0.7112)
		(drill 0.4064)
		(layers "F.Cu" "B.Cu")
		(net "GND")
	)
	(via
		(at 22.479 -238.887)
		(size 0.7112)
		(drill 0.4064)
		(layers "F.Cu" "B.Cu")
		(net "GND")
	)
	(via
		(at 19.812 -223.139)
		(size 0.7112)
		(drill 0.4064)
		(layers "F.Cu" "B.Cu")
		(net "GND")
	)
	(via
		(at 8.2804 -73.787)
		(size 0.5588)
		(drill 0.3048)
		(layers "F.Cu" "B.Cu")
		(net "GND")
	)
	(via
		(at 23.876 -346.964)
		(size 0.7112)
		(drill 0.4064)
		(layers "F.Cu" "B.Cu")
		(net "GND")
	)
	(via
		(at 14.605 -226.1362)
		(size 0.5588)
		(drill 0.3048)
		(layers "F.Cu" "B.Cu")
		(net "GND")
	)
	(via
		(at 49.784 -200.533)
		(size 0.7112)
		(drill 0.4064)
		(layers "F.Cu" "B.Cu")
		(net "GND")
	)
	(via
		(at 48.641 -180.467)
		(size 0.7112)
		(drill 0.4064)
		(layers "F.Cu" "B.Cu")
		(net "GND")
	)
	(via
		(at 1.293876 -322.199)
		(size 0.7112)
		(drill 0.4064)
		(layers "F.Cu" "B.Cu")
		(net "GND")
	)
	(via
		(at 46.9138 -168.6306)
		(size 0.7112)
		(drill 0.4064)
		(layers "F.Cu" "B.Cu")
		(net "GND")
	)
	(via
		(at 8.636 -258.445)
		(size 0.7112)
		(drill 0.4064)
		(layers "F.Cu" "B.Cu")
		(net "GND")
	)
	(via
		(at 51.076606 -103.378)
		(size 0.7112)
		(drill 0.4064)
		(layers "F.Cu" "B.Cu")
		(net "GND")
	)
	(via
		(at 31.877 -188.341)
		(size 0.7112)
		(drill 0.4064)
		(layers "F.Cu" "B.Cu")
		(net "GND")
	)
	(via
		(at 41.4528 -250.2408)
		(size 0.5588)
		(drill 0.3048)
		(layers "F.Cu" "B.Cu")
		(net "GND")
	)
	(via
		(at 46.99 -233.045)
		(size 0.7112)
		(drill 0.4064)
		(layers "F.Cu" "B.Cu")
		(net "GND")
	)
	(via
		(at 18.4658 -376.047)
		(size 0.7112)
		(drill 0.4064)
		(layers "F.Cu" "B.Cu")
		(net "GND")
	)
	(via
		(at 40.005 -168.783)
		(size 0.5588)
		(drill 0.3048)
		(layers "F.Cu" "B.Cu")
		(net "GND")
	)
	(via
		(at 30.353 -312.801)
		(size 0.7112)
		(drill 0.4064)
		(layers "F.Cu" "B.Cu")
		(net "GND")
	)
	(via
		(at 3.3274 -491.2106)
		(size 0.7112)
		(drill 0.4064)
		(layers "F.Cu" "B.Cu")
		(net "GND")
	)
	(via
		(at 1.524 -292.608)
		(size 0.7112)
		(drill 0.4064)
		(layers "F.Cu" "B.Cu")
		(net "GND")
	)
	(via
		(at 26.67 -11.43)
		(size 0.7112)
		(drill 0.4064)
		(layers "F.Cu" "B.Cu")
		(net "GND")
	)
	(via
		(at 15.621 -350.52)
		(size 0.7112)
		(drill 0.4064)
		(layers "F.Cu" "B.Cu")
		(net "GND")
	)
	(via
		(at 34.163 -224.917)
		(size 0.7112)
		(drill 0.4064)
		(layers "F.Cu" "B.Cu")
		(net "GND")
	)
	(via
		(at 13.462 -176.5554)
		(size 0.5588)
		(drill 0.3048)
		(layers "F.Cu" "B.Cu")
		(net "GND")
	)
	(via
		(at 13.1826 -37.0078)
		(size 0.7112)
		(drill 0.4064)
		(layers "F.Cu" "B.Cu")
		(net "GND")
	)
	(via
		(at 41.529 -204.597)
		(size 0.7112)
		(drill 0.4064)
		(layers "F.Cu" "B.Cu")
		(net "GND")
	)
	(via
		(at 35.8902 -75.7174)
		(size 0.7112)
		(drill 0.4064)
		(layers "F.Cu" "B.Cu")
		(net "GND")
	)
	(via
		(at 51.1048 -480.187)
		(size 0.5588)
		(drill 0.3048)
		(layers "F.Cu" "B.Cu")
		(net "GND")
	)
	(via
		(at 4.191 -44.45)
		(size 0.7112)
		(drill 0.4064)
		(layers "F.Cu" "B.Cu")
		(net "GND")
	)
	(via
		(at 32.6898 -26.4668)
		(size 0.7112)
		(drill 0.4064)
		(layers "F.Cu" "B.Cu")
		(net "GND")
	)
	(via
		(at 49.911 -457.327)
		(size 0.7112)
		(drill 0.4064)
		(layers "F.Cu" "B.Cu")
		(net "GND")
	)
	(via
		(at 24.511 -232.791)
		(size 0.7112)
		(drill 0.4064)
		(layers "F.Cu" "B.Cu")
		(net "GND")
	)
	(via
		(at 34.417 -235.585)
		(size 0.7112)
		(drill 0.4064)
		(layers "F.Cu" "B.Cu")
		(net "GND")
	)
	(via
		(at 4.064 -320.548)
		(size 0.7112)
		(drill 0.4064)
		(layers "F.Cu" "B.Cu")
		(net "GND")
	)
	(via
		(at 15.4432 -37.5158)
		(size 0.7112)
		(drill 0.4064)
		(layers "F.Cu" "B.Cu")
		(net "GND")
	)
	(via
		(at 38.608 -454.68794)
		(size 0.7112)
		(drill 0.4064)
		(layers "F.Cu" "B.Cu")
		(net "GND")
	)
	(via
		(at 37.973 -13.208)
		(size 0.5588)
		(drill 0.3048)
		(layers "F.Cu" "B.Cu")
		(net "GND")
	)
	(via
		(at 49.9872 -210.439)
		(size 0.7112)
		(drill 0.4064)
		(layers "F.Cu" "B.Cu")
		(net "GND")
	)
	(via
		(at 15.494 -346.329)
		(size 0.7112)
		(drill 0.4064)
		(layers "F.Cu" "B.Cu")
		(net "GND")
	)
	(via
		(at 6.8326 -393.1666)
		(size 0.7112)
		(drill 0.4064)
		(layers "F.Cu" "B.Cu")
		(net "GND")
	)
	(via
		(at 1.27 -34.925)
		(size 0.7112)
		(drill 0.4064)
		(layers "F.Cu" "B.Cu")
		(net "GND")
	)
	(via
		(at 37.084 -184.404)
		(size 0.5588)
		(drill 0.3048)
		(layers "F.Cu" "B.Cu")
		(net "GND")
	)
	(via
		(at 13.716 -300.736)
		(size 0.7112)
		(drill 0.4064)
		(layers "F.Cu" "B.Cu")
		(net "GND")
	)
	(via
		(at 51.181 -274.955)
		(size 0.5588)
		(drill 0.3048)
		(layers "F.Cu" "B.Cu")
		(net "GND")
	)
	(via
		(at 10.8458 -407.924)
		(size 0.5588)
		(drill 0.3048)
		(layers "F.Cu" "B.Cu")
		(net "GND")
	)
	(via
		(at 32.1564 -371.221)
		(size 0.7112)
		(drill 0.4064)
		(layers "F.Cu" "B.Cu")
		(net "GND")
	)
	(via
		(at 51.36134 -371.348)
		(size 0.5588)
		(drill 0.3048)
		(layers "F.Cu" "B.Cu")
		(net "GND")
	)
	(via
		(at 37.338 -349.758)
		(size 0.7112)
		(drill 0.4064)
		(layers "F.Cu" "B.Cu")
		(net "GND")
	)
	(via
		(at 51.181 -258.826)
		(size 0.5588)
		(drill 0.3048)
		(layers "F.Cu" "B.Cu")
		(net "GND")
	)
	(via
		(at 46.99 -470.535)
		(size 0.7112)
		(drill 0.4064)
		(layers "F.Cu" "B.Cu")
		(net "GND")
	)
	(via
		(at 3.556 -155.956)
		(size 0.7112)
		(drill 0.4064)
		(layers "F.Cu" "B.Cu")
		(net "GND")
	)
	(via
		(at 37.211 -315.341)
		(size 0.7112)
		(drill 0.4064)
		(layers "F.Cu" "B.Cu")
		(net "GND")
	)
	(via
		(at 6.604 -22.098)
		(size 0.7112)
		(drill 0.4064)
		(layers "F.Cu" "B.Cu")
		(net "GND")
	)
	(via
		(at 5.08 -1.524)
		(size 0.7112)
		(drill 0.4064)
		(layers "F.Cu" "B.Cu")
		(net "GND")
	)
	(via
		(at 51.181 -332.74)
		(size 0.5588)
		(drill 0.3048)
		(layers "F.Cu" "B.Cu")
		(net "GND")
	)
	(via
		(at 31.623 -222.631)
		(size 0.7112)
		(drill 0.4064)
		(layers "F.Cu" "B.Cu")
		(net "GND")
	)
	(via
		(at 51.308 -218.313)
		(size 0.5588)
		(drill 0.3048)
		(layers "F.Cu" "B.Cu")
		(net "GND")
	)
	(via
		(at 50.927 -476.631)
		(size 0.5588)
		(drill 0.3048)
		(layers "F.Cu" "B.Cu")
		(net "GND")
	)
	(via
		(at 40.259 -435.991)
		(size 0.7112)
		(drill 0.4064)
		(layers "F.Cu" "B.Cu")
		(net "GND")
	)
	(via
		(at 51.308 -148.844)
		(size 0.7112)
		(drill 0.4064)
		(layers "F.Cu" "B.Cu")
		(net "GND")
	)
	(via
		(at 7.3914 -437.2737)
		(size 0.5588)
		(drill 0.3048)
		(layers "F.Cu" "B.Cu")
		(net "GND")
	)
	(via
		(at 29.21 -281.559)
		(size 0.7112)
		(drill 0.4064)
		(layers "F.Cu" "B.Cu")
		(net "GND")
	)
	(via
		(at 8.29945 -76.073)
		(size 0.5588)
		(drill 0.3048)
		(layers "F.Cu" "B.Cu")
		(net "GND")
	)
	(via
		(at 42.2402 -259.4102)
		(size 0.7112)
		(drill 0.4064)
		(layers "F.Cu" "B.Cu")
		(net "GND")
	)
	(via
		(at 3.2766 -448.3608)
		(size 0.7112)
		(drill 0.4064)
		(layers "F.Cu" "B.Cu")
		(net "GND")
	)
	(via
		(at 46.1772 -93.726)
		(size 0.7112)
		(drill 0.4064)
		(layers "F.Cu" "B.Cu")
		(net "GND")
	)
	(via
		(at 50.292 -414.655)
		(size 0.7112)
		(drill 0.4064)
		(layers "F.Cu" "B.Cu")
		(net "GND")
	)
	(via
		(at 15.6464 -496.4938)
		(size 0.7112)
		(drill 0.4064)
		(layers "F.Cu" "B.Cu")
		(net "GND")
	)
	(via
		(at 37.084 -191.77)
		(size 0.5588)
		(drill 0.3048)
		(layers "F.Cu" "B.Cu")
		(net "GND")
	)
	(via
		(at 1.905 -416.6108)
		(size 0.7112)
		(drill 0.4064)
		(layers "F.Cu" "B.Cu")
		(net "GND")
	)
	(via
		(at 1.347216 -86.995)
		(size 0.7112)
		(drill 0.4064)
		(layers "F.Cu" "B.Cu")
		(net "GND")
	)
	(via
		(at 45.1358 -485.8512)
		(size 0.5588)
		(drill 0.3048)
		(layers "F.Cu" "B.Cu")
		(net "GND")
	)
	(via
		(at 49.022 -395.351)
		(size 0.7112)
		(drill 0.4064)
		(layers "F.Cu" "B.Cu")
		(net "GND")
	)
	(via
		(at 1.420876 -174.879)
		(size 0.7112)
		(drill 0.4064)
		(layers "F.Cu" "B.Cu")
		(net "GND")
	)
	(via
		(at 22.479 -177.8)
		(size 0.5588)
		(drill 0.3048)
		(layers "F.Cu" "B.Cu")
		(net "GND")
	)
	(via
		(at 44.704 -33.274)
		(size 0.7112)
		(drill 0.4064)
		(layers "F.Cu" "B.Cu")
		(net "GND")
	)
	(via
		(at 35.052 -463.296)
		(size 0.7112)
		(drill 0.4064)
		(layers "F.Cu" "B.Cu")
		(net "GND")
	)
	(via
		(at 18.923 -371.2972)
		(size 0.7112)
		(drill 0.4064)
		(layers "F.Cu" "B.Cu")
		(net "GND")
	)
	(via
		(at 33.909 -238.252)
		(size 0.7112)
		(drill 0.4064)
		(layers "F.Cu" "B.Cu")
		(net "GND")
	)
	(via
		(at 20.32 -373.888)
		(size 0.5588)
		(drill 0.3048)
		(layers "F.Cu" "B.Cu")
		(net "GND")
	)
	(via
		(at 34.798 -149.8346)
		(size 0.5588)
		(drill 0.3048)
		(layers "F.Cu" "B.Cu")
		(net "GND")
	)
	(via
		(at 16.002 -376.5042)
		(size 0.7112)
		(drill 0.4064)
		(layers "F.Cu" "B.Cu")
		(net "GND")
	)
	(via
		(at 51.076606 -71.7804)
		(size 0.7112)
		(drill 0.4064)
		(layers "F.Cu" "B.Cu")
		(net "GND")
	)
	(via
		(at 18.388838 -134.187438)
		(size 0.5588)
		(drill 0.3048)
		(layers "F.Cu" "B.Cu")
		(net "GND")
	)
	(via
		(at 23.622 -478.663)
		(size 0.7112)
		(drill 0.3556)
		(layers "F.Cu" "B.Cu")
		(net "GND")
	)
	(via
		(at 4.064 -230.124)
		(size 0.7112)
		(drill 0.4064)
		(layers "F.Cu" "B.Cu")
		(net "GND")
	)
	(via
		(at 46.6344 -448.3354)
		(size 0.7112)
		(drill 0.4064)
		(layers "F.Cu" "B.Cu")
		(net "GND")
	)
	(via
		(at 29.591 -266.446)
		(size 0.7112)
		(drill 0.4064)
		(layers "F.Cu" "B.Cu")
		(net "GND")
	)
	(via
		(at 8.636 -272.288)
		(size 0.7112)
		(drill 0.4064)
		(layers "F.Cu" "B.Cu")
		(net "GND")
	)
	(via
		(at 1.2446 -83.312)
		(size 0.7112)
		(drill 0.4064)
		(layers "F.Cu" "B.Cu")
		(net "GND")
	)
	(via
		(at 26.67 -299.974)
		(size 0.5588)
		(drill 0.3048)
		(layers "F.Cu" "B.Cu")
		(net "GND")
	)
	(via
		(at 1.397 -75.057)
		(size 0.7112)
		(drill 0.4064)
		(layers "F.Cu" "B.Cu")
		(net "GND")
	)
	(via
		(at 49.657 -254.254)
		(size 0.7112)
		(drill 0.4064)
		(layers "F.Cu" "B.Cu")
		(net "GND")
	)
	(via
		(at 30.734 -291.465)
		(size 0.7112)
		(drill 0.3556)
		(layers "F.Cu" "B.Cu")
		(net "GND")
	)
	(via
		(at 19.685 -232.918)
		(size 0.7112)
		(drill 0.4064)
		(layers "F.Cu" "B.Cu")
		(net "GND")
	)
	(via
		(at 1.524 -177.292)
		(size 0.7112)
		(drill 0.4064)
		(layers "F.Cu" "B.Cu")
		(net "GND")
	)
	(via
		(at 8.6868 -72.3392)
		(size 0.5588)
		(drill 0.3048)
		(layers "F.Cu" "B.Cu")
		(net "GND")
	)
	(via
		(at 8.128 -282.956)
		(size 0.7112)
		(drill 0.4064)
		(layers "F.Cu" "B.Cu")
		(net "GND")
	)
	(via
		(at 32.893 -201.295)
		(size 0.7112)
		(drill 0.4064)
		(layers "F.Cu" "B.Cu")
		(net "GND")
	)
	(via
		(at 1.1938 -116.3828)
		(size 0.7112)
		(drill 0.4064)
		(layers "F.Cu" "B.Cu")
		(net "GND")
	)
	(via
		(at 13.716 -337.82)
		(size 0.7112)
		(drill 0.4064)
		(layers "F.Cu" "B.Cu")
		(net "GND")
	)
	(via
		(at 26.924 -180.086)
		(size 0.5588)
		(drill 0.3048)
		(layers "F.Cu" "B.Cu")
		(net "GND")
	)
	(via
		(at 6.604 -185.928)
		(size 0.7112)
		(drill 0.4064)
		(layers "F.Cu" "B.Cu")
		(net "GND")
	)
	(via
		(at 10.668 -327.66)
		(size 0.7112)
		(drill 0.4064)
		(layers "F.Cu" "B.Cu")
		(net "GND")
	)
	(via
		(at 37.465 -310.261)
		(size 0.7112)
		(drill 0.4064)
		(layers "F.Cu" "B.Cu")
		(net "GND")
	)
	(via
		(at 19.05 -478.028)
		(size 0.7112)
		(drill 0.3556)
		(layers "F.Cu" "B.Cu")
		(net "GND")
	)
	(via
		(at 10.668 -321.564)
		(size 0.7112)
		(drill 0.4064)
		(layers "F.Cu" "B.Cu")
		(net "GND")
	)
	(via
		(at 1.420876 -22.098)
		(size 0.7112)
		(drill 0.4064)
		(layers "F.Cu" "B.Cu")
		(net "GND")
	)
	(via
		(at 20.701 -238.76)
		(size 0.7112)
		(drill 0.4064)
		(layers "F.Cu" "B.Cu")
		(net "GND")
	)
	(via
		(at 14.732 -323.088)
		(size 0.7112)
		(drill 0.4064)
		(layers "F.Cu" "B.Cu")
		(net "GND")
	)
	(via
		(at 41.8338 -262.5344)
		(size 0.7112)
		(drill 0.4064)
		(layers "F.Cu" "B.Cu")
		(net "GND")
	)
	(via
		(at 16.129 -45.5422)
		(size 0.5588)
		(drill 0.3048)
		(layers "F.Cu" "B.Cu")
		(net "GND")
	)
	(via
		(at 51.308 -74.93)
		(size 0.7112)
		(drill 0.4064)
		(layers "F.Cu" "B.Cu")
		(net "GND")
	)
	(via
		(at 29.4132 -346.4306)
		(size 0.7112)
		(drill 0.4064)
		(layers "F.Cu" "B.Cu")
		(net "GND")
	)
	(via
		(at 30.734 -195.0466)
		(size 0.7112)
		(drill 0.4064)
		(layers "F.Cu" "B.Cu")
		(net "GND")
	)
	(via
		(at 23.876 -340.36)
		(size 0.7112)
		(drill 0.4064)
		(layers "F.Cu" "B.Cu")
		(net "GND")
	)
	(via
		(at 49.403 -392.684)
		(size 0.7112)
		(drill 0.4064)
		(layers "F.Cu" "B.Cu")
		(net "GND")
	)
	(via
		(at 11.5316 -387.0452)
		(size 0.7112)
		(drill 0.4064)
		(layers "F.Cu" "B.Cu")
		(net "GND")
	)
	(via
		(at 50.038 -207.01)
		(size 0.7112)
		(drill 0.4064)
		(layers "F.Cu" "B.Cu")
		(net "GND")
	)
	(via
		(at 39.5986 -354.8634)
		(size 0.5588)
		(drill 0.3048)
		(layers "F.Cu" "B.Cu")
		(net "GND")
	)
	(via
		(at 21.844 -38.608)
		(size 0.7112)
		(drill 0.4064)
		(layers "F.Cu" "B.Cu")
		(net "GND")
	)
	(via
		(at 44.704 -172.466)
		(size 0.7112)
		(drill 0.4064)
		(layers "F.Cu" "B.Cu")
		(net "GND")
	)
	(via
		(at 19.2024 -360.7562)
		(size 0.7112)
		(drill 0.4064)
		(layers "F.Cu" "B.Cu")
		(net "GND")
	)
	(via
		(at 45.974 -274.193)
		(size 0.7112)
		(drill 0.4064)
		(layers "F.Cu" "B.Cu")
		(net "GND")
	)
	(via
		(at 2.032 -347.472)
		(size 0.7112)
		(drill 0.4064)
		(layers "F.Cu" "B.Cu")
		(net "GND")
	)
	(via
		(at 14.7574 -370.6622)
		(size 0.7112)
		(drill 0.4064)
		(layers "F.Cu" "B.Cu")
		(net "GND")
	)
	(via
		(at 1.143 -253.238)
		(size 0.7112)
		(drill 0.4064)
		(layers "F.Cu" "B.Cu")
		(net "GND")
	)
	(via
		(at 1.347216 -167.894)
		(size 0.7112)
		(drill 0.4064)
		(layers "F.Cu" "B.Cu")
		(net "GND")
	)
	(via
		(at 6.363462 -246.696738)
		(size 0.7112)
		(drill 0.4064)
		(layers "F.Cu" "B.Cu")
		(net "GND")
	)
	(via
		(at 51.2318 -352.6282)
		(size 0.5588)
		(drill 0.3048)
		(layers "F.Cu" "B.Cu")
		(net "GND")
	)
	(via
		(at 45.847 -151.13)
		(size 0.7112)
		(drill 0.4064)
		(layers "F.Cu" "B.Cu")
		(net "GND")
	)
	(via
		(at 4.572 -224.536)
		(size 0.7112)
		(drill 0.4064)
		(layers "F.Cu" "B.Cu")
		(net "GND")
	)
	(via
		(at 51.308 -89.662)
		(size 0.7112)
		(drill 0.4064)
		(layers "F.Cu" "B.Cu")
		(net "GND")
	)
	(via
		(at 40.894 -482.981)
		(size 0.7112)
		(drill 0.4064)
		(layers "F.Cu" "B.Cu")
		(net "GND")
	)
	(via
		(at 13.1318 -59.6392)
		(size 0.5588)
		(drill 0.3048)
		(layers "F.Cu" "B.Cu")
		(net "GND")
	)
	(via
		(at 28.956 -334.772)
		(size 0.7112)
		(drill 0.4064)
		(layers "F.Cu" "B.Cu")
		(net "GND")
	)
	(via
		(at 25.18918 -377.39066)
		(size 0.7112)
		(drill 0.4064)
		(layers "F.Cu" "B.Cu")
		(net "GND")
	)
	(via
		(at 44.069 -197.485)
		(size 0.7112)
		(drill 0.4064)
		(layers "F.Cu" "B.Cu")
		(net "GND")
	)
	(via
		(at 26.035 -108.331)
		(size 0.7112)
		(drill 0.4064)
		(layers "F.Cu" "B.Cu")
		(net "GND")
	)
	(via
		(at 7.112 -272.288)
		(size 0.7112)
		(drill 0.4064)
		(layers "F.Cu" "B.Cu")
		(net "GND")
	)
	(via
		(at 30.48 -279.908)
		(size 0.7112)
		(drill 0.4064)
		(layers "F.Cu" "B.Cu")
		(net "GND")
	)
	(via
		(at 12.459462 -495.743738)
		(size 0.7112)
		(drill 0.4064)
		(layers "F.Cu" "B.Cu")
		(net "GND")
	)
	(via
		(at 34.925 -222.631)
		(size 0.7112)
		(drill 0.4064)
		(layers "F.Cu" "B.Cu")
		(net "GND")
	)
	(via
		(at 1.27 -62.865)
		(size 0.7112)
		(drill 0.4064)
		(layers "F.Cu" "B.Cu")
		(net "GND")
	)
	(via
		(at 37.1602 -486.0798)
		(size 0.5588)
		(drill 0.3048)
		(layers "F.Cu" "B.Cu")
		(net "GND")
	)
	(via
		(at 43.561508 -286.904938)
		(size 0.7112)
		(drill 0.4064)
		(layers "F.Cu" "B.Cu")
		(net "GND")
	)
	(via
		(at 17.78 -232.283)
		(size 0.7112)
		(drill 0.4064)
		(layers "F.Cu" "B.Cu")
		(net "GND")
	)
	(via
		(at 41.1734 -485.648)
		(size 0.5588)
		(drill 0.3048)
		(layers "F.Cu" "B.Cu")
		(net "GND")
	)
	(via
		(at 8.636 -247.523)
		(size 0.7112)
		(drill 0.4064)
		(layers "F.Cu" "B.Cu")
		(net "GND")
	)
	(via
		(at 8.509 -242.062)
		(size 0.7112)
		(drill 0.4064)
		(layers "F.Cu" "B.Cu")
		(net "GND")
	)
	(via
		(at 16.026892 -30.252162)
		(size 0.7112)
		(drill 0.4064)
		(layers "F.Cu" "B.Cu")
		(net "GND")
	)
	(via
		(at 35.306 -470.154)
		(size 0.7112)
		(drill 0.4064)
		(layers "F.Cu" "B.Cu")
		(net "GND")
	)
	(via
		(at 51.181 -52.832)
		(size 0.7112)
		(drill 0.4064)
		(layers "F.Cu" "B.Cu")
		(net "GND")
	)
	(via
		(at 23.749 -376.6058)
		(size 0.7112)
		(drill 0.4064)
		(layers "F.Cu" "B.Cu")
		(net "GND")
	)
	(via
		(at 50.038 -435.102)
		(size 0.7112)
		(drill 0.4064)
		(layers "F.Cu" "B.Cu")
		(net "GND")
	)
	(via
		(at 3.429 -58.547)
		(size 0.7112)
		(drill 0.4064)
		(layers "F.Cu" "B.Cu")
		(net "GND")
	)
	(via
		(at 14.605 -266.827)
		(size 0.7112)
		(drill 0.3556)
		(layers "F.Cu" "B.Cu")
		(net "GND")
	)
	(via
		(at 24.892 -171.279058)
		(size 0.7112)
		(drill 0.4064)
		(layers "F.Cu" "B.Cu")
		(net "GND")
	)
	(via
		(at 47.117 -38.481)
		(size 0.7112)
		(drill 0.4064)
		(layers "F.Cu" "B.Cu")
		(net "GND")
	)
	(via
		(at 1.347216 -134.3406)
		(size 0.5588)
		(drill 0.3048)
		(layers "F.Cu" "B.Cu")
		(net "GND")
	)
	(via
		(at 15.621 -222.631)
		(size 0.7112)
		(drill 0.4064)
		(layers "F.Cu" "B.Cu")
		(net "GND")
	)
	(via
		(at 39.497 -261.62)
		(size 0.5588)
		(drill 0.3048)
		(layers "F.Cu" "B.Cu")
		(net "GND")
	)
	(via
		(at 37.465 -338.328)
		(size 0.7112)
		(drill 0.4064)
		(layers "F.Cu" "B.Cu")
		(net "GND")
	)
	(via
		(at 51.435 -255.524)
		(size 0.5588)
		(drill 0.3048)
		(layers "F.Cu" "B.Cu")
		(net "GND")
	)
	(via
		(at 32.639 -273.5072)
		(size 0.7112)
		(drill 0.3556)
		(layers "F.Cu" "B.Cu")
		(net "GND")
	)
	(via
		(at 11.176 -340.36)
		(size 0.7112)
		(drill 0.4064)
		(layers "F.Cu" "B.Cu")
		(net "GND")
	)
	(via
		(at 43.5864 -151.2316)
		(size 0.7112)
		(drill 0.4064)
		(layers "F.Cu" "B.Cu")
		(net "GND")
	)
	(via
		(at 13.462 -43.561)
		(size 0.5588)
		(drill 0.3048)
		(layers "F.Cu" "B.Cu")
		(net "GND")
	)
	(via
		(at 44.45 -11.43)
		(size 0.7112)
		(drill 0.4064)
		(layers "F.Cu" "B.Cu")
		(net "GND")
	)
	(via
		(at 18.2372 -178.1302)
		(size 0.7112)
		(drill 0.4064)
		(layers "F.Cu" "B.Cu")
		(net "GND")
	)
	(via
		(at 28.321 -259.08)
		(size 0.7112)
		(drill 0.4064)
		(layers "F.Cu" "B.Cu")
		(net "GND")
	)
	(via
		(at 29.464 -342.9)
		(size 0.7112)
		(drill 0.4064)
		(layers "F.Cu" "B.Cu")
		(net "GND")
	)
	(via
		(at 34.29 -11.43)
		(size 0.7112)
		(drill 0.4064)
		(layers "F.Cu" "B.Cu")
		(net "GND")
	)
	(via
		(at 29.972 -36.195)
		(size 0.7112)
		(drill 0.4064)
		(layers "F.Cu" "B.Cu")
		(net "GND")
	)
	(via
		(at 34.1884 -149.0218)
		(size 0.5588)
		(drill 0.3048)
		(layers "F.Cu" "B.Cu")
		(net "GND")
	)
	(via
		(at 27.178 -233.172)
		(size 0.7112)
		(drill 0.4064)
		(layers "F.Cu" "B.Cu")
		(net "GND")
	)
	(via
		(at 26.289 -264.668)
		(size 0.7112)
		(drill 0.4064)
		(layers "F.Cu" "B.Cu")
		(net "GND")
	)
	(via
		(at 33.4772 -73.5838)
		(size 0.7112)
		(drill 0.4064)
		(layers "F.Cu" "B.Cu")
		(net "GND")
	)
	(via
		(at 49.911 -408.051)
		(size 0.5588)
		(drill 0.3048)
		(layers "F.Cu" "B.Cu")
		(net "GND")
	)
	(via
		(at 28.829 -192.024)
		(size 0.5588)
		(drill 0.3048)
		(layers "F.Cu" "B.Cu")
		(net "GND")
	)
	(via
		(at 7.493 -87.249)
		(size 0.5588)
		(drill 0.3048)
		(layers "F.Cu" "B.Cu")
		(net "GND")
	)
	(via
		(at 26.67 -31.75)
		(size 0.7112)
		(drill 0.4064)
		(layers "F.Cu" "B.Cu")
		(net "GND")
	)
	(via
		(at 48.641 -414.274)
		(size 0.7112)
		(drill 0.4064)
		(layers "F.Cu" "B.Cu")
		(net "GND")
	)
	(via
		(at 41.783 -330.073)
		(size 0.7112)
		(drill 0.4064)
		(layers "F.Cu" "B.Cu")
		(net "GND")
	)
	(via
		(at 7.493 -104.267)
		(size 0.5588)
		(drill 0.3048)
		(layers "F.Cu" "B.Cu")
		(net "GND")
	)
	(via
		(at 32.766 -196.723)
		(size 0.7112)
		(drill 0.4064)
		(layers "F.Cu" "B.Cu")
		(net "GND")
	)
	(via
		(at 35.687 -215.011)
		(size 0.7112)
		(drill 0.4064)
		(layers "F.Cu" "B.Cu")
		(net "GND")
	)
	(via
		(at 11.43 -362.712)
		(size 0.5588)
		(drill 0.3048)
		(layers "F.Cu" "B.Cu")
		(net "GND")
	)
	(via
		(at 48.895 -246.888)
		(size 0.7112)
		(drill 0.4064)
		(layers "F.Cu" "B.Cu")
		(net "GND")
	)
	(via
		(at 8.636 -429.641)
		(size 0.5588)
		(drill 0.3048)
		(layers "F.Cu" "B.Cu")
		(net "GND")
	)
	(via
		(at 22.86 -226.822)
		(size 0.7112)
		(drill 0.4064)
		(layers "F.Cu" "B.Cu")
		(net "GND")
	)
	(via
		(at 1.347216 -421.386)
		(size 0.7112)
		(drill 0.4064)
		(layers "F.Cu" "B.Cu")
		(net "GND")
	)
	(via
		(at 46.228 -438.404)
		(size 0.7112)
		(drill 0.4064)
		(layers "F.Cu" "B.Cu")
		(net "GND")
	)
	(via
		(at 33.274 -35.0774)
		(size 0.7112)
		(drill 0.4064)
		(layers "F.Cu" "B.Cu")
		(net "GND")
	)
	(via
		(at 14.224 -259.461)
		(size 0.5588)
		(drill 0.3048)
		(layers "F.Cu" "B.Cu")
		(net "GND")
	)
	(via
		(at 12.192 -207.264)
		(size 0.7112)
		(drill 0.4064)
		(layers "F.Cu" "B.Cu")
		(net "GND")
	)
	(via
		(at 1.143 -246.38)
		(size 0.7112)
		(drill 0.4064)
		(layers "F.Cu" "B.Cu")
		(net "GND")
	)
	(via
		(at 1.420876 -79.248)
		(size 0.7112)
		(drill 0.4064)
		(layers "F.Cu" "B.Cu")
		(net "GND")
	)
	(via
		(at 43.434 -262.255)
		(size 0.7112)
		(drill 0.4064)
		(layers "F.Cu" "B.Cu")
		(net "GND")
	)
	(via
		(at 29.1592 -255.27)
		(size 0.7112)
		(drill 0.4064)
		(layers "F.Cu" "B.Cu")
		(net "GND")
	)
	(via
		(at 13.7668 -52.7939)
		(size 0.5588)
		(drill 0.3048)
		(layers "F.Cu" "B.Cu")
		(net "GND")
	)
	(via
		(at 51.4096 -366.776)
		(size 0.5588)
		(drill 0.3048)
		(layers "F.Cu" "B.Cu")
		(net "GND")
	)
	(via
		(at 5.715 -48.26)
		(size 0.7112)
		(drill 0.4064)
		(layers "F.Cu" "B.Cu")
		(net "GND")
	)
	(via
		(at 23.4188 -140.6652)
		(size 0.5588)
		(drill 0.3048)
		(layers "F.Cu" "B.Cu")
		(net "GND")
	)
	(via
		(at 31.75 -355.219)
		(size 0.5588)
		(drill 0.3048)
		(layers "F.Cu" "B.Cu")
		(net "GND")
	)
	(via
		(at 36.576 -235.966)
		(size 0.7112)
		(drill 0.4064)
		(layers "F.Cu" "B.Cu")
		(net "GND")
	)
	(via
		(at 37.465 -140.081)
		(size 0.7112)
		(drill 0.4064)
		(layers "F.Cu" "B.Cu")
		(net "GND")
	)
	(via
		(at 51.181 -157.861)
		(size 0.7112)
		(drill 0.4064)
		(layers "F.Cu" "B.Cu")
		(net "GND")
	)
	(via
		(at 22.606 -151.13)
		(size 0.5588)
		(drill 0.3048)
		(layers "F.Cu" "B.Cu")
		(net "GND")
	)
	(via
		(at 1.166876 -414.528)
		(size 0.7112)
		(drill 0.4064)
		(layers "F.Cu" "B.Cu")
		(net "GND")
	)
	(via
		(at 10.9982 -385.699)
		(size 0.7112)
		(drill 0.4064)
		(layers "F.Cu" "B.Cu")
		(net "GND")
	)
	(via
		(at 33.909 -146.177)
		(size 0.5588)
		(drill 0.3048)
		(layers "F.Cu" "B.Cu")
		(net "GND")
	)
	(via
		(at 21.59 -11.43)
		(size 0.7112)
		(drill 0.4064)
		(layers "F.Cu" "B.Cu")
		(net "GND")
	)
	(via
		(at 23.368 -315.341)
		(size 0.7112)
		(drill 0.4064)
		(layers "F.Cu" "B.Cu")
		(net "GND")
	)
	(via
		(at 31.4452 -333.2226)
		(size 0.7112)
		(drill 0.4064)
		(layers "F.Cu" "B.Cu")
		(net "GND")
	)
	(via
		(at 19.558 -368.046)
		(size 0.7112)
		(drill 0.4064)
		(layers "F.Cu" "B.Cu")
		(net "GND")
	)
	(via
		(at 16.256 -169.3164)
		(size 0.5588)
		(drill 0.3048)
		(layers "F.Cu" "B.Cu")
		(net "GND")
	)
	(via
		(at 50.038 -440.817)
		(size 0.7112)
		(drill 0.4064)
		(layers "F.Cu" "B.Cu")
		(net "GND")
	)
	(via
		(at 11.6586 -389.3312)
		(size 0.7112)
		(drill 0.4064)
		(layers "F.Cu" "B.Cu")
		(net "GND")
	)
	(via
		(at 42.019982 -175.862488)
		(size 0.5588)
		(drill 0.3048)
		(layers "F.Cu" "B.Cu")
		(net "GND")
	)
	(via
		(at 1.27 -224.409)
		(size 0.7112)
		(drill 0.4064)
		(layers "F.Cu" "B.Cu")
		(net "GND")
	)
	(via
		(at 47.625 -276.86)
		(size 0.7112)
		(drill 0.4064)
		(layers "F.Cu" "B.Cu")
		(net "GND")
	)
	(via
		(at 37.211 -360.075226)
		(size 0.7112)
		(drill 0.4064)
		(layers "F.Cu" "B.Cu")
		(net "GND")
	)
	(via
		(at 1.524 -268.732)
		(size 0.7112)
		(drill 0.4064)
		(layers "F.Cu" "B.Cu")
		(net "GND")
	)
	(via
		(at 14.4018 -355.6254)
		(size 0.7112)
		(drill 0.4064)
		(layers "F.Cu" "B.Cu")
		(net "GND")
	)
	(via
		(at 1.27 -56.134)
		(size 0.7112)
		(drill 0.4064)
		(layers "F.Cu" "B.Cu")
		(net "GND")
	)
	(via
		(at 30.3022 -316.3316)
		(size 0.7112)
		(drill 0.4064)
		(layers "F.Cu" "B.Cu")
		(net "GND")
	)
	(via
		(at 51.054 -56.515)
		(size 0.7112)
		(drill 0.4064)
		(layers "F.Cu" "B.Cu")
		(net "GND")
	)
	(via
		(at 8.636 -249.936)
		(size 0.7112)
		(drill 0.4064)
		(layers "F.Cu" "B.Cu")
		(net "GND")
	)
	(via
		(at 35.2552 -41.1734)
		(size 0.7112)
		(drill 0.4064)
		(layers "F.Cu" "B.Cu")
		(net "GND")
	)
	(via
		(at 3.2004 -455.3712)
		(size 0.7112)
		(drill 0.4064)
		(layers "F.Cu" "B.Cu")
		(net "GND")
	)
	(via
		(at 23.1902 -146.558)
		(size 0.5588)
		(drill 0.3048)
		(layers "F.Cu" "B.Cu")
		(net "GND")
	)
	(via
		(at 29.718 -134.62)
		(size 0.7112)
		(drill 0.4064)
		(layers "F.Cu" "B.Cu")
		(net "GND")
	)
	(via
		(at 23.622 -177.419)
		(size 0.5588)
		(drill 0.3048)
		(layers "F.Cu" "B.Cu")
		(net "GND")
	)
	(via
		(at 3.683 -467.868)
		(size 0.7112)
		(drill 0.4064)
		(layers "F.Cu" "B.Cu")
		(net "GND")
	)
	(via
		(at 3.175 -50.165)
		(size 0.7112)
		(drill 0.4064)
		(layers "F.Cu" "B.Cu")
		(net "GND")
	)
	(via
		(at 42.164 -190.881)
		(size 0.5588)
		(drill 0.3048)
		(layers "F.Cu" "B.Cu")
		(net "GND")
	)
	(via
		(at 22.987 -211.201)
		(size 0.7112)
		(drill 0.4064)
		(layers "F.Cu" "B.Cu")
		(net "GND")
	)
	(via
		(at 3.683 -25.527)
		(size 0.7112)
		(drill 0.4064)
		(layers "F.Cu" "B.Cu")
		(net "GND")
	)
	(via
		(at 1.420876 -197.612)
		(size 0.7112)
		(drill 0.4064)
		(layers "F.Cu" "B.Cu")
		(net "GND")
	)
	(via
		(at 23.368 -318.516)
		(size 0.7112)
		(drill 0.4064)
		(layers "F.Cu" "B.Cu")
		(net "GND")
	)
	(via
		(at 1.166876 -47.625)
		(size 0.7112)
		(drill 0.4064)
		(layers "F.Cu" "B.Cu")
		(net "GND")
	)
	(via
		(at 24.7142 -251.6632)
		(size 0.5588)
		(drill 0.3048)
		(layers "F.Cu" "B.Cu")
		(net "GND")
	)
	(via
		(at 48.641 -183.896)
		(size 0.7112)
		(drill 0.4064)
		(layers "F.Cu" "B.Cu")
		(net "GND")
	)
	(via
		(at 41.148 -207.645)
		(size 0.5588)
		(drill 0.3048)
		(layers "F.Cu" "B.Cu")
		(net "GND")
	)
	(via
		(at 14.7066 -482.5492)
		(size 0.5588)
		(drill 0.3048)
		(layers "F.Cu" "B.Cu")
		(net "GND")
	)
	(via
		(at 1.143 -26.797)
		(size 0.7112)
		(drill 0.4064)
		(layers "F.Cu" "B.Cu")
		(net "GND")
	)
	(via
		(at 5.588 -189.484)
		(size 0.7112)
		(drill 0.4064)
		(layers "F.Cu" "B.Cu")
		(net "GND")
	)
	(via
		(at 9.652 -211.836)
		(size 0.7112)
		(drill 0.4064)
		(layers "F.Cu" "B.Cu")
		(net "GND")
	)
	(via
		(at 51.435 -244.348)
		(size 0.5588)
		(drill 0.3048)
		(layers "F.Cu" "B.Cu")
		(net "GND")
	)
	(via
		(at 29.083 -329.311)
		(size 0.7112)
		(drill 0.4064)
		(layers "F.Cu" "B.Cu")
		(net "GND")
	)
	(via
		(at 1.547876 -208.153)
		(size 0.7112)
		(drill 0.4064)
		(layers "F.Cu" "B.Cu")
		(net "GND")
	)
	(via
		(at 38.735 -449.86194)
		(size 0.7112)
		(drill 0.4064)
		(layers "F.Cu" "B.Cu")
		(net "GND")
	)
	(via
		(at 48.1076 -392.2014)
		(size 0.7112)
		(drill 0.4064)
		(layers "F.Cu" "B.Cu")
		(net "GND")
	)
	(via
		(at 48.8442 -104.3813)
		(size 0.7112)
		(drill 0.4064)
		(layers "F.Cu" "B.Cu")
		(net "GND")
	)
	(via
		(at 31.75 -245.618)
		(size 0.7112)
		(drill 0.4064)
		(layers "F.Cu" "B.Cu")
		(net "GND")
	)
	(via
		(at 51.054 -109.347)
		(size 0.7112)
		(drill 0.4064)
		(layers "F.Cu" "B.Cu")
		(net "GND")
	)
	(via
		(at 15.875 -218.948)
		(size 0.7112)
		(drill 0.4064)
		(layers "F.Cu" "B.Cu")
		(net "GND")
	)
	(via
		(at 7.112 -321.564)
		(size 0.7112)
		(drill 0.4064)
		(layers "F.Cu" "B.Cu")
		(net "GND")
	)
	(via
		(at 51.054 -488.442)
		(size 0.7112)
		(drill 0.4064)
		(layers "F.Cu" "B.Cu")
		(net "GND")
	)
	(via
		(at 6.096 -299.72)
		(size 0.7112)
		(drill 0.4064)
		(layers "F.Cu" "B.Cu")
		(net "GND")
	)
	(via
		(at 16.383 -10.16)
		(size 0.7112)
		(drill 0.4064)
		(layers "F.Cu" "B.Cu")
		(net "GND")
	)
	(via
		(at 48.9204 -160.782)
		(size 0.7112)
		(drill 0.4064)
		(layers "F.Cu" "B.Cu")
		(net "GND")
	)
	(via
		(at 43.307 -30.607)
		(size 0.7112)
		(drill 0.4064)
		(layers "F.Cu" "B.Cu")
		(net "GND")
	)
	(via
		(at 1.166876 -264.541)
		(size 0.7112)
		(drill 0.4064)
		(layers "F.Cu" "B.Cu")
		(net "GND")
	)
	(via
		(at 47.244 -36.322)
		(size 0.7112)
		(drill 0.4064)
		(layers "F.Cu" "B.Cu")
		(net "GND")
	)
	(via
		(at 20.701 -359.791)
		(size 0.7112)
		(drill 0.4064)
		(layers "F.Cu" "B.Cu")
		(net "GND")
	)
	(via
		(at 33.909 -147.828)
		(size 0.5588)
		(drill 0.3048)
		(layers "F.Cu" "B.Cu")
		(net "GND")
	)
	(via
		(at 27.686 -275.209)
		(size 0.7112)
		(drill 0.4064)
		(layers "F.Cu" "B.Cu")
		(net "GND")
	)
	(via
		(at 14.097 -242.697)
		(size 0.7112)
		(drill 0.4064)
		(layers "F.Cu" "B.Cu")
		(net "GND")
	)
	(via
		(at 19.558 -219.202)
		(size 0.7112)
		(drill 0.4064)
		(layers "F.Cu" "B.Cu")
		(net "GND")
	)
	(via
		(at 31.4452 -339.8266)
		(size 0.7112)
		(drill 0.4064)
		(layers "F.Cu" "B.Cu")
		(net "GND")
	)
	(via
		(at 1.547876 -65.278)
		(size 0.7112)
		(drill 0.4064)
		(layers "F.Cu" "B.Cu")
		(net "GND")
	)
	(via
		(at 11.2014 -428.0408)
		(size 0.5588)
		(drill 0.3048)
		(layers "F.Cu" "B.Cu")
		(net "GND")
	)
	(via
		(at 46.5074 -466.9282)
		(size 0.7112)
		(drill 0.4064)
		(layers "F.Cu" "B.Cu")
		(net "GND")
	)
	(via
		(at 26.5684 -488.5436)
		(size 0.5588)
		(drill 0.3048)
		(layers "F.Cu" "B.Cu")
		(net "GND")
	)
	(via
		(at 3.683 -28.575)
		(size 0.7112)
		(drill 0.4064)
		(layers "F.Cu" "B.Cu")
		(net "GND")
	)
	(via
		(at 51.435 -248.285)
		(size 0.5588)
		(drill 0.3048)
		(layers "F.Cu" "B.Cu")
		(net "GND")
	)
	(via
		(at 1.347216 -382.0414)
		(size 0.7112)
		(drill 0.4064)
		(layers "F.Cu" "B.Cu")
		(net "GND")
	)
	(via
		(at 50.8 -30.48)
		(size 0.7112)
		(drill 0.4064)
		(layers "F.Cu" "B.Cu")
		(net "GND")
	)
	(via
		(at 3.556 -120.904)
		(size 0.5588)
		(drill 0.3048)
		(layers "F.Cu" "B.Cu")
		(net "GND")
	)
	(via
		(at 26.797 -103.251)
		(size 0.7112)
		(drill 0.4064)
		(layers "F.Cu" "B.Cu")
		(net "GND")
	)
	(via
		(at 18.796 -15.367)
		(size 0.5588)
		(drill 0.3048)
		(layers "F.Cu" "B.Cu")
		(net "GND")
	)
	(via
		(at 28.829 -183.134)
		(size 0.5588)
		(drill 0.3048)
		(layers "F.Cu" "B.Cu")
		(net "GND")
	)
	(via
		(at 28.194 -354.076)
		(size 0.5588)
		(drill 0.3048)
		(layers "F.Cu" "B.Cu")
		(net "GND")
	)
	(via
		(at 49.149 -261.366)
		(size 0.7112)
		(drill 0.4064)
		(layers "F.Cu" "B.Cu")
		(net "GND")
	)
	(via
		(at 10.16 -288.544)
		(size 0.7112)
		(drill 0.4064)
		(layers "F.Cu" "B.Cu")
		(net "GND")
	)
	(via
		(at 30.226 -27.813)
		(size 0.7112)
		(drill 0.4064)
		(layers "F.Cu" "B.Cu")
		(net "GND")
	)
	(via
		(at 36.703 -476.758)
		(size 0.7112)
		(drill 0.3556)
		(layers "F.Cu" "B.Cu")
		(net "GND")
	)
	(via
		(at 43.434 -265.684)
		(size 0.7112)
		(drill 0.4064)
		(layers "F.Cu" "B.Cu")
		(net "GND")
	)
	(via
		(at 11.811 -377.1646)
		(size 0.7112)
		(drill 0.4064)
		(layers "F.Cu" "B.Cu")
		(net "GND")
	)
	(via
		(at 48.7172 -325.3486)
		(size 0.7112)
		(drill 0.4064)
		(layers "F.Cu" "B.Cu")
		(net "GND")
	)
	(via
		(at 48.387 -211.074)
		(size 0.7112)
		(drill 0.4064)
		(layers "F.Cu" "B.Cu")
		(net "GND")
	)
	(via
		(at 11.303 -465.709)
		(size 0.7112)
		(drill 0.4064)
		(layers "F.Cu" "B.Cu")
		(net "GND")
	)
	(via
		(at 7.112 -335.28)
		(size 0.7112)
		(drill 0.4064)
		(layers "F.Cu" "B.Cu")
		(net "GND")
	)
	(via
		(at 4.064 -244.348)
		(size 0.7112)
		(drill 0.4064)
		(layers "F.Cu" "B.Cu")
		(net "GND")
	)
	(via
		(at 24.397462 -229.424738)
		(size 0.7112)
		(drill 0.4064)
		(layers "F.Cu" "B.Cu")
		(net "GND")
	)
	(via
		(at 1.420876 -220.726)
		(size 0.7112)
		(drill 0.4064)
		(layers "F.Cu" "B.Cu")
		(net "GND")
	)
	(via
		(at 51.308 -199.644)
		(size 0.7112)
		(drill 0.4064)
		(layers "F.Cu" "B.Cu")
		(net "GND")
	)
	(via
		(at 51.181 -41.91)
		(size 0.5588)
		(drill 0.3048)
		(layers "F.Cu" "B.Cu")
		(net "GND")
	)
	(via
		(at 48.768 -244.348)
		(size 0.7112)
		(drill 0.4064)
		(layers "F.Cu" "B.Cu")
		(net "GND")
	)
	(via
		(at 43.883072 -454.68794)
		(size 0.7112)
		(drill 0.4064)
		(layers "F.Cu" "B.Cu")
		(net "GND")
	)
	(via
		(at 24.892 -325.628)
		(size 0.7112)
		(drill 0.4064)
		(layers "F.Cu" "B.Cu")
		(net "GND")
	)
	(via
		(at 1.143 -211.709)
		(size 0.7112)
		(drill 0.4064)
		(layers "F.Cu" "B.Cu")
		(net "GND")
	)
	(via
		(at 50.927 -111.125)
		(size 0.7112)
		(drill 0.4064)
		(layers "F.Cu" "B.Cu")
		(net "GND")
	)
	(via
		(at 34.671 -245.618)
		(size 0.7112)
		(drill 0.4064)
		(layers "F.Cu" "B.Cu")
		(net "GND")
	)
	(via
		(at 10.795 -431.673)
		(size 0.7112)
		(drill 0.4064)
		(layers "F.Cu" "B.Cu")
		(net "GND")
	)
	(via
		(at 6.223 -478.536)
		(size 0.7112)
		(drill 0.4064)
		(layers "F.Cu" "B.Cu")
		(net "GND")
	)
	(via
		(at 8.636 -290.576)
		(size 0.7112)
		(drill 0.4064)
		(layers "F.Cu" "B.Cu")
		(net "GND")
	)
	(via
		(at 10.8204 -366.8268)
		(size 0.7112)
		(drill 0.4064)
		(layers "F.Cu" "B.Cu")
		(net "GND")
	)
	(via
		(at 49.1998 -151.13)
		(size 0.7112)
		(drill 0.4064)
		(layers "F.Cu" "B.Cu")
		(net "GND")
	)
	(via
		(at 31.6992 -176.9364)
		(size 0.7112)
		(drill 0.4064)
		(layers "F.Cu" "B.Cu")
		(net "GND")
	)
	(via
		(at 24.892 -179.832)
		(size 0.5588)
		(drill 0.3048)
		(layers "F.Cu" "B.Cu")
		(net "GND")
	)
	(via
		(at 30.734 -197.104)
		(size 0.7112)
		(drill 0.4064)
		(layers "F.Cu" "B.Cu")
		(net "GND")
	)
	(via
		(at 41.91 -199.644)
		(size 0.7112)
		(drill 0.4064)
		(layers "F.Cu" "B.Cu")
		(net "GND")
	)
	(via
		(at 17.8816 -366.903)
		(size 0.7112)
		(drill 0.4064)
		(layers "F.Cu" "B.Cu")
		(net "GND")
	)
	(via
		(at 4.064 -251.46)
		(size 0.7112)
		(drill 0.4064)
		(layers "F.Cu" "B.Cu")
		(net "GND")
	)
	(via
		(at 16.383 -279.146)
		(size 0.5588)
		(drill 0.3048)
		(layers "F.Cu" "B.Cu")
		(net "GND")
	)
	(via
		(at 51.181 -212.217)
		(size 0.7112)
		(drill 0.4064)
		(layers "F.Cu" "B.Cu")
		(net "GND")
	)
	(via
		(at 28.956 -323.596)
		(size 0.7112)
		(drill 0.4064)
		(layers "F.Cu" "B.Cu")
		(net "GND")
	)
	(via
		(at 51.308 -222.25)
		(size 0.5588)
		(drill 0.3048)
		(layers "F.Cu" "B.Cu")
		(net "GND")
	)
	(via
		(at 12.0904 -202.3872)
		(size 0.7112)
		(drill 0.4064)
		(layers "F.Cu" "B.Cu")
		(net "GND")
	)
	(via
		(at 38.608 -431.06594)
		(size 0.7112)
		(drill 0.4064)
		(layers "F.Cu" "B.Cu")
		(net "GND")
	)
	(via
		(at 31.8516 -249.8344)
		(size 0.5588)
		(drill 0.3048)
		(layers "F.Cu" "B.Cu")
		(net "GND")
	)
	(via
		(at 6.617462 -210.374738)
		(size 0.7112)
		(drill 0.4064)
		(layers "F.Cu" "B.Cu")
		(net "GND")
	)
	(via
		(at 26.543 -306.832)
		(size 0.7112)
		(drill 0.4064)
		(layers "F.Cu" "B.Cu")
		(net "GND")
	)
	(via
		(at 1.524 -278.384)
		(size 0.7112)
		(drill 0.4064)
		(layers "F.Cu" "B.Cu")
		(net "GND")
	)
	(via
		(at 27.94 -241.173)
		(size 0.7112)
		(drill 0.4064)
		(layers "F.Cu" "B.Cu")
		(net "GND")
	)
	(via
		(at 6.604 -256.54)
		(size 0.7112)
		(drill 0.4064)
		(layers "F.Cu" "B.Cu")
		(net "GND")
	)
	(via
		(at 29.591 -269.875)
		(size 0.7112)
		(drill 0.4064)
		(layers "F.Cu" "B.Cu")
		(net "GND")
	)
	(via
		(at 37.084 -194.437)
		(size 0.5588)
		(drill 0.3048)
		(layers "F.Cu" "B.Cu")
		(net "GND")
	)
	(via
		(at 34.29 -233.172)
		(size 0.7112)
		(drill 0.4064)
		(layers "F.Cu" "B.Cu")
		(net "GND")
	)
	(via
		(at 6.223 -216.789)
		(size 0.7112)
		(drill 0.4064)
		(layers "F.Cu" "B.Cu")
		(net "GND")
	)
	(segment
		(start 23.040086 -62.079886)
		(end 23.040086 -63.159894)
		(width 0.635)
		(layer "B.Cu")
		(net "GND")
	)
	(segment
		(start 45.619924 -43.659806)
		(end 46.699932 -43.659806)
		(width 0.635)
		(layer "B.Cu")
		(net "GND")
	)
	(segment
		(start 40.999918 -443.95009)
		(end 40.999918 -449.068698)
		(width 0.635)
		(layer "B.Cu")
		(net "GND")
	)
	(segment
		(start 23.040086 -62.079886)
		(end 24.120094 -62.079886)
		(width 0.635)
		(layer "B.Cu")
		(net "GND")
	)
	(segment
		(start 45.619924 -45.119798)
		(end 45.619924 -46.199806)
		(width 0.635)
		(layer "B.Cu")
		(net "GND")
	)
	(segment
		(start 45.619924 -43.659806)
		(end 45.619924 -44.739814)
		(width 0.635)
		(layer "B.Cu")
		(net "GND")
	)
	(segment
		(start 37.999924 -43.659806)
		(end 39.079932 -43.659806)
		(width 0.635)
		(layer "B.Cu")
		(net "GND")
	)
	(segment
		(start 23.040086 -41.119806)
		(end 23.040086 -42.199814)
		(width 0.635)
		(layer "B.Cu")
		(net "GND")
	)
	(segment
		(start 39.459916 -51.919886)
		(end 40.539924 -51.919886)
		(width 0.635)
		(layer "B.Cu")
		(net "GND")
	)
	(segment
		(start 40.33139 -337.49996)
		(end 45.449998 -337.49996)
		(width 0.635)
		(layer "B.Cu")
		(net "GND")
	)
	(segment
		(start 25.580086 -40.039798)
		(end 25.580086 -41.119806)
		(width 0.635)
		(layer "B.Cu")
		(net "GND")
	)
	(segment
		(start 45.449998 -337.49996)
		(end 50.568606 -337.49996)
		(width 0.635)
		(layer "B.Cu")
		(net "GND")
	)
	(segment
		(start 45.449998 -337.49996)
		(end 45.449998 -342.618568)
		(width 0.635)
		(layer "B.Cu")
		(net "GND")
	)
	(segment
		(start 2.643378 -39.99992)
		(end 6.999986 -39.99992)
		(width 0.635)
		(layer "B.Cu")
		(net "GND")
	)
	(segment
		(start 41.999916 -48.739806)
		(end 43.079924 -48.739806)
		(width 0.635)
		(layer "B.Cu")
		(net "GND")
	)
	(segment
		(start 45.619924 -42.579798)
		(end 45.619924 -43.659806)
		(width 0.635)
		(layer "B.Cu")
		(net "GND")
	)
	(segment
		(start 44.539916 -48.739806)
		(end 45.619924 -48.739806)
		(width 0.635)
		(layer "B.Cu")
		(net "GND")
	)
	(segment
		(start 6.999986 -459.999842)
		(end 11.356594 -459.999842)
		(width 0.635)
		(layer "B.Cu")
		(net "GND")
	)
	(segment
		(start 45.619924 -41.119806)
		(end 46.699932 -41.119806)
		(width 0.635)
		(layer "B.Cu")
		(net "GND")
	)
	(segment
		(start 23.040086 -42.579798)
		(end 23.040086 -43.659806)
		(width 0.635)
		(layer "B.Cu")
		(net "GND")
	)
	(segment
		(start 45.619924 -40.039798)
		(end 45.619924 -41.119806)
		(width 0.635)
		(layer "B.Cu")
		(net "GND")
	)
	(segment
		(start 45.619924 -46.199806)
		(end 46.699932 -46.199806)
		(width 0.635)
		(layer "B.Cu")
		(net "GND")
	)
	(segment
		(start 19.420078 -43.659806)
		(end 20.500086 -43.659806)
		(width 0.635)
		(layer "B.Cu")
		(net "GND")
	)
	(segment
		(start 24.500078 -43.659806)
		(end 25.580086 -43.659806)
		(width 0.635)
		(layer "B.Cu")
		(net "GND")
	)
	(segment
		(start 37.999924 -47.659798)
		(end 37.999924 -48.739806)
		(width 0.635)
		(layer "B.Cu")
		(net "GND")
	)
	(segment
		(start 43.079924 -48.739806)
		(end 43.079924 -49.819814)
		(width 0.635)
		(layer "B.Cu")
		(net "GND")
	)
	(segment
		(start 45.500036 -480.000056)
		(end 49.856644 -480.000056)
		(width 0.635)
		(layer "B.Cu")
		(net "GND")
	)
	(segment
		(start 2.972816 -198.419974)
		(end 4.040124 -198.419974)
		(width 0.635)
		(layer "B.Cu")
		(net "GND")
	)
	(segment
		(start 2.972816 -22.37994)
		(end 4.040124 -22.37994)
		(width 0.635)
		(layer "B.Cu")
		(net "GND")
	)
	(segment
		(start 44.539916 -41.119806)
		(end 45.619924 -41.119806)
		(width 0.635)
		(layer "B.Cu")
		(net "GND")
	)
	(segment
		(start 37.999924 -46.199806)
		(end 39.079932 -46.199806)
		(width 0.635)
		(layer "B.Cu")
		(net "GND")
	)
	(segment
		(start 37.999924 -45.119798)
		(end 37.999924 -46.199806)
		(width 0.635)
		(layer "B.Cu")
		(net "GND")
	)
	(segment
		(start 45.500036 -290.64331)
		(end 45.500036 -294.999918)
		(width 0.635)
		(layer "B.Cu")
		(net "GND")
	)
	(segment
		(start 36.919916 -48.739806)
		(end 37.999924 -48.739806)
		(width 0.635)
		(layer "B.Cu")
		(net "GND")
	)
	(segment
		(start 6.999986 -459.999842)
		(end 6.999986 -464.35645)
		(width 0.635)
		(layer "B.Cu")
		(net "GND")
	)
	(segment
		(start 40.539924 -48.739806)
		(end 41.619932 -48.739806)
		(width 0.635)
		(layer "B.Cu")
		(net "GND")
	)
	(segment
		(start 6.999986 -39.99992)
		(end 6.999986 -44.356528)
		(width 0.635)
		(layer "B.Cu")
		(net "GND")
	)
	(segment
		(start 43.079924 -46.199806)
		(end 43.079924 -47.279814)
		(width 0.635)
		(layer "B.Cu")
		(net "GND")
	)
	(segment
		(start 20.500086 -41.119806)
		(end 21.580094 -41.119806)
		(width 0.635)
		(layer "B.Cu")
		(net "GND")
	)
	(segment
		(start 4.040124 -310.672734)
		(end 4.040124 -311.740042)
		(width 0.635)
		(layer "B.Cu")
		(net "GND")
	)
	(segment
		(start 40.999918 -457.931266)
		(end 40.999918 -463.049874)
		(width 0.635)
		(layer "B.Cu")
		(net "GND")
	)
	(segment
		(start 4.040124 -22.37994)
		(end 5.107432 -22.37994)
		(width 0.635)
		(layer "B.Cu")
		(net "GND")
	)
	(segment
		(start 23.040086 -40.039798)
		(end 23.040086 -41.119806)
		(width 0.635)
		(layer "B.Cu")
		(net "GND")
	)
	(segment
		(start 43.079924 -43.659806)
		(end 44.159932 -43.659806)
		(width 0.635)
		(layer "B.Cu")
		(net "GND")
	)
	(segment
		(start 36.919916 -41.119806)
		(end 37.999924 -41.119806)
		(width 0.635)
		(layer "B.Cu")
		(net "GND")
	)
	(segment
		(start 27.040078 -43.659806)
		(end 28.120086 -43.659806)
		(width 0.635)
		(layer "B.Cu")
		(net "GND")
	)
	(segment
		(start 40.539924 -43.659806)
		(end 41.619932 -43.659806)
		(width 0.635)
		(layer "B.Cu")
		(net "GND")
	)
	(segment
		(start 41.999916 -46.199806)
		(end 43.079924 -46.199806)
		(width 0.635)
		(layer "B.Cu")
		(net "GND")
	)
	(segment
		(start 45.500036 -15.643352)
		(end 45.500036 -19.99996)
		(width 0.635)
		(layer "B.Cu")
		(net "GND")
	)
	(segment
		(start 40.539924 -47.659798)
		(end 40.539924 -48.739806)
		(width 0.635)
		(layer "B.Cu")
		(net "GND")
	)
	(segment
		(start 6.999986 -159.999934)
		(end 6.999986 -164.356542)
		(width 0.635)
		(layer "B.Cu")
		(net "GND")
	)
	(segment
		(start 2.972816 -487.780076)
		(end 4.040124 -487.780076)
		(width 0.635)
		(layer "B.Cu")
		(net "GND")
	)
	(segment
		(start 24.500078 -41.119806)
		(end 25.580086 -41.119806)
		(width 0.635)
		(layer "B.Cu")
		(net "GND")
	)
	(segment
		(start 4.040124 -21.312632)
		(end 4.040124 -22.37994)
		(width 0.635)
		(layer "B.Cu")
		(net "GND")
	)
	(segment
		(start 36.919916 -46.199806)
		(end 37.999924 -46.199806)
		(width 0.635)
		(layer "B.Cu")
		(net "GND")
	)
	(segment
		(start 37.999924 -41.119806)
		(end 37.999924 -42.199814)
		(width 0.635)
		(layer "B.Cu")
		(net "GND")
	)
	(segment
		(start 37.999924 -48.739806)
		(end 37.999924 -49.819814)
		(width 0.635)
		(layer "B.Cu")
		(net "GND")
	)
	(segment
		(start 40.999918 -463.049874)
		(end 40.999918 -468.168482)
		(width 0.635)
		(layer "B.Cu")
		(net "GND")
	)
	(segment
		(start 28.120086 -41.119806)
		(end 28.120086 -42.199814)
		(width 0.635)
		(layer "B.Cu")
		(net "GND")
	)
	(segment
		(start 39.459916 -48.739806)
		(end 40.539924 -48.739806)
		(width 0.635)
		(layer "B.Cu")
		(net "GND")
	)
	(segment
		(start 40.539924 -45.119798)
		(end 40.539924 -46.199806)
		(width 0.635)
		(layer "B.Cu")
		(net "GND")
	)
	(segment
		(start 2.972816 -311.740042)
		(end 4.040124 -311.740042)
		(width 0.635)
		(layer "B.Cu")
		(net "GND")
	)
	(segment
		(start 4.040124 -198.419974)
		(end 5.107432 -198.419974)
		(width 0.635)
		(layer "B.Cu")
		(net "GND")
	)
	(segment
		(start 25.580086 -42.579798)
		(end 25.580086 -43.659806)
		(width 0.635)
		(layer "B.Cu")
		(net "GND")
	)
	(segment
		(start 28.120086 -43.659806)
		(end 29.200094 -43.659806)
		(width 0.635)
		(layer "B.Cu")
		(net "GND")
	)
	(segment
		(start 40.539924 -50.839878)
		(end 40.539924 -51.919886)
		(width 0.635)
		(layer "B.Cu")
		(net "GND")
	)
	(segment
		(start 19.685508 -42.845228)
		(end 20.500086 -43.659806)
		(width 0.635)
		(layer "B.Cu")
		(net "GND")
	)
	(segment
		(start 37.999924 -41.119806)
		(end 39.079932 -41.119806)
		(width 0.635)
		(layer "B.Cu")
		(net "GND")
	)
	(segment
		(start 21.960078 -41.119806)
		(end 23.040086 -41.119806)
		(width 0.635)
		(layer "B.Cu")
		(net "GND")
	)
	(segment
		(start 45.619924 -46.199806)
		(end 45.619924 -47.279814)
		(width 0.635)
		(layer "B.Cu")
		(net "GND")
	)
	(segment
		(start 25.580086 -41.119806)
		(end 26.660094 -41.119806)
		(width 0.635)
		(layer "B.Cu")
		(net "GND")
	)
	(segment
		(start 44.539916 -46.199806)
		(end 45.619924 -46.199806)
		(width 0.635)
		(layer "B.Cu")
		(net "GND")
	)
	(segment
		(start 4.040124 -487.780076)
		(end 4.040124 -488.847384)
		(width 0.635)
		(layer "B.Cu")
		(net "GND")
	)
	(segment
		(start 40.539924 -48.739806)
		(end 40.539924 -49.819814)
		(width 0.635)
		(layer "B.Cu")
		(net "GND")
	)
	(segment
		(start 6.999986 -35.643312)
		(end 6.999986 -39.99992)
		(width 0.635)
		(layer "B.Cu")
		(net "GND")
	)
	(segment
		(start 40.539924 -43.659806)
		(end 40.539924 -44.739814)
		(width 0.635)
		(layer "B.Cu")
		(net "GND")
	)
	(segment
		(start 27.040078 -41.119806)
		(end 28.120086 -41.119806)
		(width 0.635)
		(layer "B.Cu")
		(net "GND")
	)
	(segment
		(start 45.500036 -19.99996)
		(end 45.500036 -24.356568)
		(width 0.635)
		(layer "B.Cu")
		(net "GND")
	)
	(segment
		(start 43.079924 -41.119806)
		(end 43.079924 -42.199814)
		(width 0.635)
		(layer "B.Cu")
		(net "GND")
	)
	(segment
		(start 45.500036 -19.99996)
		(end 49.856644 -19.99996)
		(width 0.635)
		(layer "B.Cu")
		(net "GND")
	)
	(segment
		(start 37.999924 -46.199806)
		(end 37.999924 -47.279814)
		(width 0.635)
		(layer "B.Cu")
		(net "GND")
	)
	(segment
		(start 28.120086 -40.039798)
		(end 28.120086 -41.119806)
		(width 0.635)
		(layer "B.Cu")
		(net "GND")
	)
	(segment
		(start 45.619924 -41.119806)
		(end 45.619924 -42.199814)
		(width 0.635)
		(layer "B.Cu")
		(net "GND")
	)
	(segment
		(start 45.619924 -48.739806)
		(end 46.699932 -48.739806)
		(width 0.635)
		(layer "B.Cu")
		(net "GND")
	)
	(segment
		(start 37.999924 -42.579798)
		(end 37.999924 -43.659806)
		(width 0.635)
		(layer "B.Cu")
		(net "GND")
	)
	(segment
		(start 35.88131 -443.95009)
		(end 40.999918 -443.95009)
		(width 0.635)
		(layer "B.Cu")
		(net "GND")
	)
	(segment
		(start 4.040124 -487.780076)
		(end 5.107432 -487.780076)
		(width 0.635)
		(layer "B.Cu")
		(net "GND")
	)
	(segment
		(start 37.999924 -43.659806)
		(end 37.999924 -44.739814)
		(width 0.635)
		(layer "B.Cu")
		(net "GND")
	)
	(segment
		(start 39.459916 -62.079886)
		(end 40.539924 -62.079886)
		(width 0.635)
		(layer "B.Cu")
		(net "GND")
	)
	(segment
		(start 4.040124 -486.712768)
		(end 4.040124 -487.780076)
		(width 0.635)
		(layer "B.Cu")
		(net "GND")
	)
	(segment
		(start 40.539924 -40.039798)
		(end 40.539924 -41.119806)
		(width 0.635)
		(layer "B.Cu")
		(net "GND")
	)
	(segment
		(start 4.499864 -335.643474)
		(end 4.499864 -340.000082)
		(width 0.635)
		(layer "B.Cu")
		(net "GND")
	)
	(segment
		(start 36.919916 -43.659806)
		(end 37.999924 -43.659806)
		(width 0.635)
		(layer "B.Cu")
		(net "GND")
	)
	(segment
		(start 45.500036 -294.999918)
		(end 45.500036 -299.356526)
		(width 0.635)
		(layer "B.Cu")
		(net "GND")
	)
	(segment
		(start 41.999916 -43.659806)
		(end 43.079924 -43.659806)
		(width 0.635)
		(layer "B.Cu")
		(net "GND")
	)
	(segment
		(start 45.619924 -48.739806)
		(end 45.619924 -49.819814)
		(width 0.635)
		(layer "B.Cu")
		(net "GND")
	)
	(segment
		(start 4.040124 -22.37994)
		(end 4.040124 -23.447248)
		(width 0.635)
		(layer "B.Cu")
		(net "GND")
	)
	(segment
		(start 4.040124 -311.740042)
		(end 5.107432 -311.740042)
		(width 0.635)
		(layer "B.Cu")
		(net "GND")
	)
	(segment
		(start 6.999986 -455.643234)
		(end 6.999986 -459.999842)
		(width 0.635)
		(layer "B.Cu")
		(net "GND")
	)
	(segment
		(start 35.88131 -463.049874)
		(end 40.999918 -463.049874)
		(width 0.635)
		(layer "B.Cu")
		(net "GND")
	)
	(segment
		(start 43.079924 -46.199806)
		(end 44.159932 -46.199806)
		(width 0.635)
		(layer "B.Cu")
		(net "GND")
	)
	(segment
		(start 40.539924 -62.079886)
		(end 40.539924 -63.159894)
		(width 0.635)
		(layer "B.Cu")
		(net "GND")
	)
	(segment
		(start 45.500036 -480.000056)
		(end 45.500036 -484.356664)
		(width 0.635)
		(layer "B.Cu")
		(net "GND")
	)
	(segment
		(start 40.539924 -41.119806)
		(end 40.539924 -42.199814)
		(width 0.635)
		(layer "B.Cu")
		(net "GND")
	)
	(segment
		(start 39.459916 -41.119806)
		(end 40.539924 -41.119806)
		(width 0.635)
		(layer "B.Cu")
		(net "GND")
	)
	(segment
		(start 43.079924 -47.659798)
		(end 43.079924 -48.739806)
		(width 0.635)
		(layer "B.Cu")
		(net "GND")
	)
	(segment
		(start 28.120086 -42.579798)
		(end 28.120086 -43.659806)
		(width 0.635)
		(layer "B.Cu")
		(net "GND")
	)
	(segment
		(start 23.040086 -43.659806)
		(end 24.120094 -43.659806)
		(width 0.635)
		(layer "B.Cu")
		(net "GND")
	)
	(segment
		(start 4.040124 -376.672602)
		(end 4.040124 -377.73991)
		(width 0.635)
		(layer "B.Cu")
		(net "GND")
	)
	(segment
		(start 43.079924 -42.579798)
		(end 43.079924 -43.659806)
		(width 0.635)
		(layer "B.Cu")
		(net "GND")
	)
	(segment
		(start 41.143428 -294.999918)
		(end 45.500036 -294.999918)
		(width 0.635)
		(layer "B.Cu")
		(net "GND")
	)
	(segment
		(start 40.539924 -41.119806)
		(end 41.619932 -41.119806)
		(width 0.635)
		(layer "B.Cu")
		(net "GND")
	)
	(segment
		(start 45.500036 -294.999918)
		(end 49.856644 -294.999918)
		(width 0.635)
		(layer "B.Cu")
		(net "GND")
	)
	(segment
		(start 41.143428 -19.99996)
		(end 45.500036 -19.99996)
		(width 0.635)
		(layer "B.Cu")
		(net "GND")
	)
	(segment
		(start 43.079924 -45.119798)
		(end 43.079924 -46.199806)
		(width 0.635)
		(layer "B.Cu")
		(net "GND")
	)
	(segment
		(start 41.143174 -144.999964)
		(end 45.499782 -144.999964)
		(width 0.635)
		(layer "B.Cu")
		(net "GND")
	)
	(segment
		(start 40.539924 -51.919886)
		(end 41.619932 -51.919886)
		(width 0.635)
		(layer "B.Cu")
		(net "GND")
	)
	(segment
		(start 45.499782 -144.999964)
		(end 45.499782 -149.356572)
		(width 0.635)
		(layer "B.Cu")
		(net "GND")
	)
	(segment
		(start 4.499864 -340.000082)
		(end 8.856472 -340.000082)
		(width 0.635)
		(layer "B.Cu")
		(net "GND")
	)
	(segment
		(start 39.459916 -43.659806)
		(end 40.539924 -43.659806)
		(width 0.635)
		(layer "B.Cu")
		(net "GND")
	)
	(segment
		(start 41.143428 -480.000056)
		(end 45.500036 -480.000056)
		(width 0.635)
		(layer "B.Cu")
		(net "GND")
	)
	(segment
		(start 40.999918 -443.95009)
		(end 46.118526 -443.95009)
		(width 0.635)
		(layer "B.Cu")
		(net "GND")
	)
	(segment
		(start 37.999924 -48.739806)
		(end 39.079932 -48.739806)
		(width 0.635)
		(layer "B.Cu")
		(net "GND")
	)
	(segment
		(start 40.999918 -438.831482)
		(end 40.999918 -443.95009)
		(width 0.635)
		(layer "B.Cu")
		(net "GND")
	)
	(segment
		(start 6.999986 -155.643326)
		(end 6.999986 -159.999934)
		(width 0.635)
		(layer "B.Cu")
		(net "GND")
	)
	(segment
		(start 25.580086 -43.659806)
		(end 26.660094 -43.659806)
		(width 0.635)
		(layer "B.Cu")
		(net "GND")
	)
	(segment
		(start 40.539924 -46.199806)
		(end 40.539924 -47.279814)
		(width 0.635)
		(layer "B.Cu")
		(net "GND")
	)
	(segment
		(start 4.040124 -311.740042)
		(end 4.040124 -312.80735)
		(width 0.635)
		(layer "B.Cu")
		(net "GND")
	)
	(segment
		(start 45.499782 -144.999964)
		(end 49.85639 -144.999964)
		(width 0.635)
		(layer "B.Cu")
		(net "GND")
	)
	(segment
		(start 40.999918 -463.049874)
		(end 46.118526 -463.049874)
		(width 0.635)
		(layer "B.Cu")
		(net "GND")
	)
	(segment
		(start 43.079924 -41.119806)
		(end 44.159932 -41.119806)
		(width 0.635)
		(layer "B.Cu")
		(net "GND")
	)
	(segment
		(start 2.643378 -459.999842)
		(end 6.999986 -459.999842)
		(width 0.635)
		(layer "B.Cu")
		(net "GND")
	)
	(segment
		(start 23.040086 -41.119806)
		(end 24.120094 -41.119806)
		(width 0.635)
		(layer "B.Cu")
		(net "GND")
	)
	(segment
		(start 28.120086 -41.119806)
		(end 29.200094 -41.119806)
		(width 0.635)
		(layer "B.Cu")
		(net "GND")
	)
	(segment
		(start 20.500086 -40.039798)
		(end 20.500086 -41.119806)
		(width 0.635)
		(layer "B.Cu")
		(net "GND")
	)
	(segment
		(start 45.500036 -475.643448)
		(end 45.500036 -480.000056)
		(width 0.635)
		(layer "B.Cu")
		(net "GND")
	)
	(segment
		(start 4.499864 -340.000082)
		(end 4.499864 -344.35669)
		(width 0.635)
		(layer "B.Cu")
		(net "GND")
	)
	(segment
		(start 4.040124 -198.419974)
		(end 4.040124 -199.487282)
		(width 0.635)
		(layer "B.Cu")
		(net "GND")
	)
	(segment
		(start 40.539924 -42.579798)
		(end 40.539924 -43.659806)
		(width 0.635)
		(layer "B.Cu")
		(net "GND")
	)
	(segment
		(start 41.999916 -41.119806)
		(end 43.079924 -41.119806)
		(width 0.635)
		(layer "B.Cu")
		(net "GND")
	)
	(segment
		(start 43.079924 -40.039798)
		(end 43.079924 -41.119806)
		(width 0.635)
		(layer "B.Cu")
		(net "GND")
	)
	(segment
		(start 45.449998 -332.381352)
		(end 45.449998 -337.49996)
		(width 0.635)
		(layer "B.Cu")
		(net "GND")
	)
	(segment
		(start 25.580086 -41.119806)
		(end 25.580086 -42.199814)
		(width 0.635)
		(layer "B.Cu")
		(net "GND")
	)
	(segment
		(start 6.999986 -39.99992)
		(end 11.356594 -39.99992)
		(width 0.635)
		(layer "B.Cu")
		(net "GND")
	)
	(segment
		(start 43.079924 -43.659806)
		(end 43.079924 -44.739814)
		(width 0.635)
		(layer "B.Cu")
		(net "GND")
	)
	(segment
		(start 45.499782 -140.643356)
		(end 45.499782 -144.999964)
		(width 0.635)
		(layer "B.Cu")
		(net "GND")
	)
	(segment
		(start 44.539916 -43.659806)
		(end 45.619924 -43.659806)
		(width 0.635)
		(layer "B.Cu")
		(net "GND")
	)
	(segment
		(start 43.079924 -48.739806)
		(end 44.159932 -48.739806)
		(width 0.635)
		(layer "B.Cu")
		(net "GND")
	)
	(segment
		(start 37.999924 -40.039798)
		(end 37.999924 -41.119806)
		(width 0.635)
		(layer "B.Cu")
		(net "GND")
	)
	(segment
		(start 4.040124 -197.352666)
		(end 4.040124 -198.419974)
		(width 0.635)
		(layer "B.Cu")
		(net "GND")
	)
	(segment
		(start 40.539924 -46.199806)
		(end 41.619932 -46.199806)
		(width 0.635)
		(layer "B.Cu")
		(net "GND")
	)
	(segment
		(start 45.619924 -47.659798)
		(end 45.619924 -48.739806)
		(width 0.635)
		(layer "B.Cu")
		(net "GND")
	)
	(segment
		(start 3.23469 -376.934476)
		(end 4.040124 -377.73991)
		(width 0.635)
		(layer "B.Cu")
		(net "GND")
	)
	(segment
		(start 39.459916 -46.199806)
		(end 40.539924 -46.199806)
		(width 0.635)
		(layer "B.Cu")
		(net "GND")
	)
	(segment
		(start 27.61234 -164.091366)
		(end 27.373834 -164.091366)
		(width 0.1397)
		(layer "F.Cu")
		(net "NCT7904D_PWM4")
	)
	(segment
		(start 25.8826 -165.5826)
		(end 25.8826 -166.1414)
		(width 0.1397)
		(layer "F.Cu")
		(net "NCT7904D_PWM4")
	)
	(segment
		(start 27.373834 -164.091366)
		(end 25.8826 -165.5826)
		(width 0.1397)
		(layer "F.Cu")
		(net "NCT7904D_PWM4")
	)
	(segment
		(start 28.2956 -167.259)
		(end 28.2956 -166.5224)
		(width 0.1397)
		(layer "F.Cu")
		(net "NCT7904D_PWM3")
	)
	(segment
		(start 28.09875 -166.32555)
		(end 28.09875 -165.677342)
		(width 0.1397)
		(layer "F.Cu")
		(net "NCT7904D_PWM3")
	)
	(segment
		(start 28.2956 -166.5224)
		(end 28.09875 -166.32555)
		(width 0.1397)
		(layer "F.Cu")
		(net "NCT7904D_PWM3")
	)
	(segment
		(start 28.09875 -165.677342)
		(end 28.61183 -165.164262)
		(width 0.1397)
		(layer "F.Cu")
		(net "NCT7904D_PWM3")
	)
	(segment
		(start 28.61183 -165.164262)
		(end 28.61183 -164.091366)
		(width 0.1397)
		(layer "F.Cu")
		(net "NCT7904D_PWM3")
	)
	(segment
		(start 26.6446 -167.3225)
		(end 28.2321 -167.3225)
		(width 0.1397)
		(layer "F.Cu")
		(net "NCT7904D_PWM3")
	)
	(segment
		(start 28.2321 -167.3225)
		(end 28.2956 -167.259)
		(width 0.1397)
		(layer "F.Cu")
		(net "NCT7904D_PWM3")
	)
	(via
		(at 28.2956 -167.259)
		(size 0.7112)
		(drill 0.3556)
		(layers "F.Cu" "B.Cu")
		(net "NCT7904D_PWM3")
	)
	(segment
		(start 29.3624 -166.8145)
		(end 30.2641 -166.8145)
		(width 0.1397)
		(layer "F.Cu")
		(net "NCT7904D_PWM2")
	)
	(segment
		(start 30.2641 -166.8145)
		(end 30.3022 -166.7764)
		(width 0.1397)
		(layer "F.Cu")
		(net "NCT7904D_PWM2")
	)
	(segment
		(start 29.3116 -165.721792)
		(end 29.61132 -165.422072)
		(width 0.1397)
		(layer "F.Cu")
		(net "NCT7904D_PWM2")
	)
	(segment
		(start 29.3624 -166.8145)
		(end 29.3116 -166.7637)
		(width 0.1397)
		(layer "F.Cu")
		(net "NCT7904D_PWM2")
	)
	(segment
		(start 29.3116 -166.7637)
		(end 29.3116 -165.721792)
		(width 0.1397)
		(layer "F.Cu")
		(net "NCT7904D_PWM2")
	)
	(segment
		(start 29.61132 -165.422072)
		(end 29.61132 -164.091366)
		(width 0.1397)
		(layer "F.Cu")
		(net "NCT7904D_PWM2")
	)
	(via
		(at 30.3022 -166.7764)
		(size 0.7112)
		(drill 0.3556)
		(layers "F.Cu" "B.Cu")
		(net "NCT7904D_PWM2")
	)
	(segment
		(start 31.010352 -166.702994)
		(end 30.61208 -166.304722)
		(width 0.1397)
		(layer "F.Cu")
		(net "NCT7904D_PWM1")
	)
	(segment
		(start 29.5402 -169.4561)
		(end 30.6959 -169.4561)
		(width 0.1397)
		(layer "F.Cu")
		(net "NCT7904D_PWM1")
	)
	(segment
		(start 30.6959 -169.4561)
		(end 31.010352 -169.141648)
		(width 0.1397)
		(layer "F.Cu")
		(net "NCT7904D_PWM1")
	)
	(segment
		(start 31.010352 -169.141648)
		(end 31.010352 -166.702994)
		(width 0.1397)
		(layer "F.Cu")
		(net "NCT7904D_PWM1")
	)
	(segment
		(start 30.61208 -166.304722)
		(end 30.61208 -164.091366)
		(width 0.1397)
		(layer "F.Cu")
		(net "NCT7904D_PWM1")
	)
	(via
		(at 31.010352 -169.141648)
		(size 0.7112)
		(drill 0.3556)
		(layers "F.Cu" "B.Cu")
		(net "NCT7904D_PWM1")
	)
	(segment
		(start 4.040124 -18.772632)
		(end 4.040124 -19.83994)
		(width 0.635)
		(layer "F.Cu")
		(net "P12V_FAN6")
	)
	(segment
		(start 4.040124 -19.83994)
		(end 4.040124 -20.907248)
		(width 0.635)
		(layer "F.Cu")
		(net "P12V_FAN6")
	)
	(segment
		(start 4.040124 -19.83994)
		(end 5.107432 -19.83994)
		(width 0.635)
		(layer "F.Cu")
		(net "P12V_FAN6")
	)
	(segment
		(start 2.972816 -19.83994)
		(end 4.040124 -19.83994)
		(width 0.635)
		(layer "F.Cu")
		(net "P12V_FAN6")
	)
	(segment
		(start 22.3012 -375.285)
		(end 22.3012 -375.2723)
		(width 0.254)
		(layer "F.Cu")
		(net "ADM1276_UV")
	)
	(segment
		(start 22.733 -374.8405)
		(end 23.749 -374.8405)
		(width 0.254)
		(layer "F.Cu")
		(net "ADM1276_UV")
	)
	(segment
		(start 23.1775 -368.554)
		(end 22.0726 -368.554)
		(width 0.254)
		(layer "F.Cu")
		(net "ADM1276_UV")
	)
	(segment
		(start 25.527 -360.7435)
		(end 25.527 -360.045)
		(width 0.254)
		(layer "F.Cu")
		(net "ADM1276_UV")
	)
	(segment
		(start 22.2885 -376.936)
		(end 22.2885 -375.2977)
		(width 0.254)
		(layer "F.Cu")
		(net "ADM1276_UV")
	)
	(segment
		(start 27.813 -372.618)
		(end 28.418028 -372.012972)
		(width 0.254)
		(layer "F.Cu")
		(net "ADM1276_UV")
	)
	(segment
		(start 22.2885 -377.2027)
		(end 22.2885 -376.936)
		(width 0.254)
		(layer "F.Cu")
		(net "ADM1276_UV")
	)
	(segment
		(start 23.749 -374.8405)
		(end 23.749 -374.65)
		(width 0.254)
		(layer "F.Cu")
		(net "ADM1276_UV")
	)
	(segment
		(start 22.2885 -375.2977)
		(end 22.3012 -375.285)
		(width 0.254)
		(layer "F.Cu")
		(net "ADM1276_UV")
	)
	(segment
		(start 23.1902 -378.1044)
		(end 22.2885 -377.2027)
		(width 0.254)
		(layer "F.Cu")
		(net "ADM1276_UV")
	)
	(segment
		(start 22.3012 -375.2723)
		(end 22.733 -374.8405)
		(width 0.254)
		(layer "F.Cu")
		(net "ADM1276_UV")
	)
	(segment
		(start 23.749 -374.65)
		(end 25.781 -372.618)
		(width 0.254)
		(layer "F.Cu")
		(net "ADM1276_UV")
	)
	(segment
		(start 28.418028 -372.012972)
		(end 28.418028 -371.2464)
		(width 0.254)
		(layer "F.Cu")
		(net "ADM1276_UV")
	)
	(segment
		(start 25.527 -360.045)
		(end 25.2984 -359.8164)
		(width 0.254)
		(layer "F.Cu")
		(net "ADM1276_UV")
	)
	(segment
		(start 25.781 -372.618)
		(end 27.813 -372.618)
		(width 0.254)
		(layer "F.Cu")
		(net "ADM1276_UV")
	)
	(segment
		(start 25.2984 -359.8164)
		(end 25.2984 -359.791)
		(width 0.254)
		(layer "F.Cu")
		(net "ADM1276_UV")
	)
	(via
		(at 22.7584 -371.856)
		(size 0.7112)
		(drill 0.3556)
		(layers "F.Cu" "B.Cu")
		(net "ADM1276_UV")
	)
	(via
		(at 23.1902 -378.1044)
		(size 0.7112)
		(drill 0.4064)
		(layers "F.Cu" "B.Cu")
		(net "ADM1276_UV")
	)
	(via
		(at 22.0726 -368.554)
		(size 0.7112)
		(drill 0.4064)
		(layers "F.Cu" "B.Cu")
		(net "ADM1276_UV")
	)
	(via
		(at 25.2984 -359.791)
		(size 0.7112)
		(drill 0.4064)
		(layers "F.Cu" "B.Cu")
		(net "ADM1276_UV")
	)
	(segment
		(start 21.4884 -361.1626)
		(end 21.4884 -367.9698)
		(width 0.254)
		(layer "B.Cu")
		(net "ADM1276_UV")
	)
	(segment
		(start 22.86 -359.791)
		(end 21.4884 -361.1626)
		(width 0.254)
		(layer "B.Cu")
		(net "ADM1276_UV")
	)
	(segment
		(start 22.7584 -377.6726)
		(end 23.1902 -378.1044)
		(width 0.254)
		(layer "B.Cu")
		(net "ADM1276_UV")
	)
	(segment
		(start 21.4884 -367.9698)
		(end 22.0726 -368.554)
		(width 0.254)
		(layer "B.Cu")
		(net "ADM1276_UV")
	)
	(segment
		(start 22.7584 -369.2398)
		(end 22.7584 -371.856)
		(width 0.254)
		(layer "B.Cu")
		(net "ADM1276_UV")
	)
	(segment
		(start 22.7584 -371.856)
		(end 22.7584 -377.6726)
		(width 0.254)
		(layer "B.Cu")
		(net "ADM1276_UV")
	)
	(segment
		(start 25.2984 -359.791)
		(end 22.86 -359.791)
		(width 0.254)
		(layer "B.Cu")
		(net "ADM1276_UV")
	)
	(segment
		(start 22.0726 -368.554)
		(end 22.7584 -369.2398)
		(width 0.254)
		(layer "B.Cu")
		(net "ADM1276_UV")
	)
	(segment
		(start 4.040124 -195.879974)
		(end 5.107432 -195.879974)
		(width 0.635)
		(layer "F.Cu")
		(net "P12V_FAN4")
	)
	(segment
		(start 4.040124 -194.812666)
		(end 4.040124 -195.879974)
		(width 0.635)
		(layer "F.Cu")
		(net "P12V_FAN4")
	)
	(segment
		(start 2.972816 -195.879974)
		(end 4.040124 -195.879974)
		(width 0.635)
		(layer "F.Cu")
		(net "P12V_FAN4")
	)
	(segment
		(start 4.040124 -195.879974)
		(end 4.040124 -196.947282)
		(width 0.635)
		(layer "F.Cu")
		(net "P12V_FAN4")
	)
	(via
		(at 16.51 -194.564)
		(size 0.7112)
		(drill 0.3556)
		(layers "F.Cu" "B.Cu")
		(net "P12V_FAN4")
	)
	(via
		(at 16.51 -196.85)
		(size 0.7112)
		(drill 0.3556)
		(layers "F.Cu" "B.Cu")
		(net "P12V_FAN4")
	)
	(segment
		(start 2.972816 -375.19991)
		(end 4.040124 -375.19991)
		(width 0.635)
		(layer "F.Cu")
		(net "P12V_FAN2")
	)
	(segment
		(start 4.040124 -375.19991)
		(end 4.040124 -376.267218)
		(width 0.635)
		(layer "F.Cu")
		(net "P12V_FAN2")
	)
	(segment
		(start 4.040124 -375.19991)
		(end 5.107432 -375.19991)
		(width 0.635)
		(layer "F.Cu")
		(net "P12V_FAN2")
	)
	(segment
		(start 4.040124 -374.132602)
		(end 4.040124 -375.19991)
		(width 0.635)
		(layer "F.Cu")
		(net "P12V_FAN2")
	)
	(via
		(at 18.034 -313.0804)
		(size 0.7112)
		(drill 0.3556)
		(layers "F.Cu" "B.Cu")
		(net "P12V_FAN2")
	)
	(segment
		(start 4.040124 -129.880106)
		(end 5.107432 -129.880106)
		(width 0.635)
		(layer "F.Cu")
		(net "P12V_FAN5")
	)
	(segment
		(start 2.972816 -129.880106)
		(end 4.040124 -129.880106)
		(width 0.635)
		(layer "F.Cu")
		(net "P12V_FAN5")
	)
	(segment
		(start 4.040124 -129.880106)
		(end 4.040124 -130.947414)
		(width 0.635)
		(layer "F.Cu")
		(net "P12V_FAN5")
	)
	(via
		(at 6.9342 -150.622)
		(size 0.7112)
		(drill 0.3556)
		(layers "F.Cu" "B.Cu")
		(net "P12V_FAN5")
	)
	(via
		(at 2.794 -146.812)
		(size 0.7112)
		(drill 0.3556)
		(layers "F.Cu" "B.Cu")
		(net "P12V_FAN5")
	)
	(via
		(at 9.398 -153.67)
		(size 0.7112)
		(drill 0.3556)
		(layers "F.Cu" "B.Cu")
		(net "P12V_FAN5")
	)
	(segment
		(start 4.040124 -308.132734)
		(end 4.040124 -309.200042)
		(width 0.635)
		(layer "F.Cu")
		(net "P12V_FAN3")
	)
	(segment
		(start 2.972816 -309.200042)
		(end 4.040124 -309.200042)
		(width 0.635)
		(layer "F.Cu")
		(net "P12V_FAN3")
	)
	(segment
		(start 4.040124 -309.200042)
		(end 4.040124 -310.26735)
		(width 0.635)
		(layer "F.Cu")
		(net "P12V_FAN3")
	)
	(segment
		(start 4.040124 -309.200042)
		(end 5.107432 -309.200042)
		(width 0.635)
		(layer "F.Cu")
		(net "P12V_FAN3")
	)
	(via
		(at 13.2334 -287.7058)
		(size 0.7112)
		(drill 0.3556)
		(layers "F.Cu" "B.Cu")
		(net "P12V_FAN3")
	)
	(segment
		(start 4.040124 -485.240076)
		(end 5.107432 -485.240076)
		(width 0.635)
		(layer "F.Cu")
		(net "P12V_FAN1")
	)
	(segment
		(start 2.972816 -485.240076)
		(end 4.040124 -485.240076)
		(width 0.635)
		(layer "F.Cu")
		(net "P12V_FAN1")
	)
	(segment
		(start 4.040124 -485.240076)
		(end 4.040124 -486.307384)
		(width 0.635)
		(layer "F.Cu")
		(net "P12V_FAN1")
	)
	(segment
		(start 4.040124 -484.172768)
		(end 4.040124 -485.240076)
		(width 0.635)
		(layer "F.Cu")
		(net "P12V_FAN1")
	)
	(via
		(at 20.828 -486.41)
		(size 0.7112)
		(drill 0.3556)
		(layers "F.Cu" "B.Cu")
		(net "P12V_FAN1")
	)
	(via
		(at 16.764 -486.918)
		(size 0.7112)
		(drill 0.3556)
		(layers "F.Cu" "B.Cu")
		(net "P12V_FAN1")
	)
	(segment
		(start 25.654 -370.967)
		(end 26.513028 -370.107972)
		(width 0.254)
		(layer "F.Cu")
		(net "ADM1276_OV")
	)
	(segment
		(start 22.7203 -371.2845)
		(end 22.733 -371.2718)
		(width 0.254)
		(layer "F.Cu")
		(net "ADM1276_OV")
	)
	(segment
		(start 24.257 -371.0305)
		(end 25.654 -371.0305)
		(width 0.254)
		(layer "F.Cu")
		(net "ADM1276_OV")
	)
	(segment
		(start 24.257 -371.0305)
		(end 22.9743 -371.0305)
		(width 0.254)
		(layer "F.Cu")
		(net "ADM1276_OV")
	)
	(segment
		(start 25.654 -371.0305)
		(end 25.654 -370.967)
		(width 0.254)
		(layer "F.Cu")
		(net "ADM1276_OV")
	)
	(segment
		(start 21.209 -371.2845)
		(end 22.7203 -371.2845)
		(width 0.254)
		(layer "F.Cu")
		(net "ADM1276_OV")
	)
	(segment
		(start 26.513028 -370.107972)
		(end 27.2796 -370.107972)
		(width 0.254)
		(layer "F.Cu")
		(net "ADM1276_OV")
	)
	(segment
		(start 22.9743 -371.0305)
		(end 22.733 -371.2718)
		(width 0.254)
		(layer "F.Cu")
		(net "ADM1276_OV")
	)
	(via
		(at 25.654 -371.0305)
		(size 0.7112)
		(drill 0.3556)
		(layers "F.Cu" "B.Cu")
		(net "ADM1276_OV")
	)
	(segment
		(start 4.1148 -419.3286)
		(end 3.5814 -418.7952)
		(width 0.508)
		(layer "F.Cu")
		(net "P12V")
	)
	(segment
		(start 12.6746 -224.4852)
		(end 13.1826 -224.4852)
		(width 0.508)
		(layer "F.Cu")
		(net "P12V")
	)
	(segment
		(start 44.704 -124.3584)
		(end 44.704 -124.701808)
		(width 0.508)
		(layer "F.Cu")
		(net "P12V")
	)
	(segment
		(start 10.5664 -453.136)
		(end 10.668 -453.2376)
		(width 0.508)
		(layer "F.Cu")
		(net "P12V")
	)
	(segment
		(start 42.9768 -122.6312)
		(end 44.704 -124.3584)
		(width 0.508)
		(layer "F.Cu")
		(net "P12V")
	)
	(segment
		(start 15.4813 -146.6088)
		(end 15.4813 -146.9263)
		(width 0.508)
		(layer "F.Cu")
		(net "P12V")
	)
	(segment
		(start 5.4864 -84.7852)
		(end 5.4864 -84.3788)
		(width 0.508)
		(layer "F.Cu")
		(net "P12V")
	)
	(segment
		(start 16.1036 -147.5486)
		(end 16.1036 -147.6756)
		(width 0.508)
		(layer "F.Cu")
		(net "P12V")
	)
	(segment
		(start 13.1826 -224.4852)
		(end 14.1478 -223.52)
		(width 0.508)
		(layer "F.Cu")
		(net "P12V")
	)
	(segment
		(start 9.906 -146.7739)
		(end 9.398 -146.7739)
		(width 0.508)
		(layer "F.Cu")
		(net "P12V")
	)
	(segment
		(start 19.2405 -260.4516)
		(end 19.2405 -259.334)
		(width 0.508)
		(layer "F.Cu")
		(net "P12V")
	)
	(segment
		(start 19.2659 -259.3086)
		(end 19.2659 -257.6068)
		(width 0.508)
		(layer "F.Cu")
		(net "P12V")
	)
	(segment
		(start 24.4094 -134.7343)
		(end 23.7617 -134.7343)
		(width 0.508)
		(layer "F.Cu")
		(net "P12V")
	)
	(segment
		(start 20.828 -122.8344)
		(end 18.833592 -124.828808)
		(width 0.508)
		(layer "F.Cu")
		(net "P12V")
	)
	(segment
		(start 14.8209 -148.336)
		(end 15.4432 -148.336)
		(width 0.508)
		(layer "F.Cu")
		(net "P12V")
	)
	(segment
		(start 42.799 -122.6312)
		(end 40.753792 -124.676408)
		(width 0.508)
		(layer "F.Cu")
		(net "P12V")
	)
	(segment
		(start 18.3261 -256.667)
		(end 18.6563 -256.9972)
		(width 0.508)
		(layer "F.Cu")
		(net "P12V")
	)
	(segment
		(start 9.5631 -453.136)
		(end 10.5664 -453.136)
		(width 0.508)
		(layer "F.Cu")
		(net "P12V")
	)
	(segment
		(start 8.4963 -144.9832)
		(end 8.4963 -145.8722)
		(width 0.508)
		(layer "F.Cu")
		(net "P12V")
	)
	(segment
		(start 17.895316 -15.247874)
		(end 17.895316 -16.053816)
		(width 0.508)
		(layer "F.Cu")
		(net "P12V")
	)
	(segment
		(start 23.1775 -179.8066)
		(end 23.1775 -178.9938)
		(width 0.508)
		(layer "F.Cu")
		(net "P12V")
	)
	(segment
		(start 40.4495 -149.9235)
		(end 40.4495 -149.86)
		(width 0.508)
		(layer "F.Cu")
		(net "P12V")
	)
	(segment
		(start 18.3515 -297.7261)
		(end 18.0594 -297.434)
		(width 0.508)
		(layer "F.Cu")
		(net "P12V")
	)
	(segment
		(start 18.3261 -255.0922)
		(end 18.3261 -256.667)
		(width 0.508)
		(layer "F.Cu")
		(net "P12V")
	)
	(segment
		(start 3.5814 -418.7952)
		(end 2.667 -418.7952)
		(width 0.508)
		(layer "F.Cu")
		(net "P12V")
	)
	(segment
		(start 12.2936 -445.0461)
		(end 12.2682 -445.0715)
		(width 0.508)
		(layer "F.Cu")
		(net "P12V")
	)
	(segment
		(start 15.4432 -148.336)
		(end 16.1036 -147.6756)
		(width 0.508)
		(layer "F.Cu")
		(net "P12V")
	)
	(segment
		(start 13.2588 -62.1538)
		(end 12.064746 -62.1538)
		(width 0.508)
		(layer "F.Cu")
		(net "P12V")
	)
	(segment
		(start 17.25803 -13.462)
		(end 16.383 -13.462)
		(width 0.508)
		(layer "F.Cu")
		(net "P12V")
	)
	(segment
		(start 10.668 -453.2376)
		(end 9.7663 -454.1393)
		(width 0.508)
		(layer "F.Cu")
		(net "P12V")
	)
	(segment
		(start 23.7617 -134.7343)
		(end 23.1902 -134.1628)
		(width 0.508)
		(layer "F.Cu")
		(net "P12V")
	)
	(segment
		(start 3.5306 -433.2732)
		(end 3.5306 -433.3748)
		(width 0.508)
		(layer "F.Cu")
		(net "P12V")
	)
	(segment
		(start 19.2405 -260.4516)
		(end 19.2405 -261.6454)
		(width 0.508)
		(layer "F.Cu")
		(net "P12V")
	)
	(segment
		(start 12.2936 -443.7126)
		(end 12.2936 -445.0461)
		(width 0.508)
		(layer "F.Cu")
		(net "P12V")
	)
	(segment
		(start 16.2433 -249.0343)
		(end 14.5034 -249.0343)
		(width 0.508)
		(layer "F.Cu")
		(net "P12V")
	)
	(segment
		(start 5.4864 -84.3788)
		(end 6.4262 -83.439)
		(width 0.508)
		(layer "F.Cu")
		(net "P12V")
	)
	(segment
		(start 12.064492 -62.153546)
		(end 12.064492 -62.889892)
		(width 0.508)
		(layer "F.Cu")
		(net "P12V")
	)
	(segment
		(start 19.2659 -257.6068)
		(end 18.6563 -256.9972)
		(width 0.508)
		(layer "F.Cu")
		(net "P12V")
	)
	(segment
		(start 40.4495 -149.86)
		(end 39.6875 -149.098)
		(width 0.508)
		(layer "F.Cu")
		(net "P12V")
	)
	(segment
		(start 14.8209 -150.622)
		(end 14.8209 -148.336)
		(width 0.508)
		(layer "F.Cu")
		(net "P12V")
	)
	(segment
		(start 17.526 -184.6072)
		(end 17.526 -184.658)
		(width 0.508)
		(layer "F.Cu")
		(net "P12V")
	)
	(segment
		(start 17.119092 -17.158462)
		(end 16.256 -17.158462)
		(width 0.508)
		(layer "F.Cu")
		(net "P12V")
	)
	(segment
		(start 17.4625 -184.7215)
		(end 17.4625 -185.42)
		(width 0.508)
		(layer "F.Cu")
		(net "P12V")
	)
	(segment
		(start 16.256 -249.047)
		(end 16.2433 -249.0343)
		(width 0.508)
		(layer "F.Cu")
		(net "P12V")
	)
	(segment
		(start 17.271492 -13.475462)
		(end 17.25803 -13.462)
		(width 0.508)
		(layer "F.Cu")
		(net "P12V")
	)
	(segment
		(start 9.8806 -63.627)
		(end 9.8806 -62.7126)
		(width 0.508)
		(layer "F.Cu")
		(net "P12V")
	)
	(segment
		(start 10.5664 -445.5795)
		(end 10.5664 -443.7126)
		(width 0.508)
		(layer "F.Cu")
		(net "P12V")
	)
	(segment
		(start 8.6741 -450.6976)
		(end 9.7028 -450.6976)
		(width 0.508)
		(layer "F.Cu")
		(net "P12V")
	)
	(segment
		(start 20.828 -122.8344)
		(end 22.822408 -124.828808)
		(width 0.508)
		(layer "F.Cu")
		(net "P12V")
	)
	(segment
		(start 8.0264 -260.1722)
		(end 8.4836 -259.715)
		(width 0.508)
		(layer "F.Cu")
		(net "P12V")
	)
	(segment
		(start 9.398 -146.7739)
		(end 8.4963 -145.8722)
		(width 0.508)
		(layer "F.Cu")
		(net "P12V")
	)
	(segment
		(start 40.753792 -124.701808)
		(end 40.132 -124.701808)
		(width 0.508)
		(layer "F.Cu")
		(net "P12V")
	)
	(segment
		(start 43.0403 -134.0866)
		(end 43.3324 -134.3787)
		(width 0.508)
		(layer "F.Cu")
		(net "P12V")
	)
	(segment
		(start 4.0132 -432.7906)
		(end 3.5306 -433.2732)
		(width 0.508)
		(layer "F.Cu")
		(net "P12V")
	)
	(segment
		(start 9.7663 -454.1393)
		(end 9.7663 -454.2028)
		(width 0.508)
		(layer "F.Cu")
		(net "P12V")
	)
	(segment
		(start 15.4813 -146.9263)
		(end 16.1036 -147.5486)
		(width 0.508)
		(layer "F.Cu")
		(net "P12V")
	)
	(segment
		(start 42.1894 -134.0866)
		(end 43.0403 -134.0866)
		(width 0.508)
		(layer "F.Cu")
		(net "P12V")
	)
	(segment
		(start 12.064746 -62.1538)
		(end 12.064492 -62.153546)
		(width 0.508)
		(layer "F.Cu")
		(net "P12V")
	)
	(segment
		(start 40.753792 -124.676408)
		(end 40.753792 -124.701808)
		(width 0.508)
		(layer "F.Cu")
		(net "P12V")
	)
	(segment
		(start 10.795 -64.5414)
		(end 9.8806 -63.627)
		(width 0.508)
		(layer "F.Cu")
		(net "P12V")
	)
	(segment
		(start 39.9923 -146.9771)
		(end 39.2684 -147.701)
		(width 0.508)
		(layer "F.Cu")
		(net "P12V")
	)
	(segment
		(start 40.132 -146.9771)
		(end 39.9923 -146.9771)
		(width 0.508)
		(layer "F.Cu")
		(net "P12V")
	)
	(segment
		(start 9.7028 -450.6976)
		(end 9.8552 -450.85)
		(width 0.508)
		(layer "F.Cu")
		(net "P12V")
	)
	(segment
		(start 18.3515 -298.4754)
		(end 18.3515 -297.7261)
		(width 0.508)
		(layer "F.Cu")
		(net "P12V")
	)
	(segment
		(start 42.9768 -122.6312)
		(end 42.799 -122.6312)
		(width 0.508)
		(layer "F.Cu")
		(net "P12V")
	)
	(segment
		(start 17.895316 -16.053816)
		(end 17.9705 -16.129)
		(width 0.508)
		(layer "F.Cu")
		(net "P12V")
	)
	(segment
		(start 22.822408 -124.828808)
		(end 22.86 -124.828808)
		(width 0.508)
		(layer "F.Cu")
		(net "P12V")
	)
	(segment
		(start 19.2405 -259.334)
		(end 19.2659 -259.3086)
		(width 0.508)
		(layer "F.Cu")
		(net "P12V")
	)
	(segment
		(start 18.833592 -124.828808)
		(end 18.288 -124.828808)
		(width 0.508)
		(layer "F.Cu")
		(net "P12V")
	)
	(segment
		(start 17.526 -184.658)
		(end 17.4625 -184.7215)
		(width 0.508)
		(layer "F.Cu")
		(net "P12V")
	)
	(segment
		(start 8.4836 -259.715)
		(end 9.906 -259.715)
		(width 0.508)
		(layer "F.Cu")
		(net "P12V")
	)
	(segment
		(start 19.2405 -261.6454)
		(end 19.7485 -262.1534)
		(width 0.508)
		(layer "F.Cu")
		(net "P12V")
	)
	(segment
		(start 4.0132 -431.5968)
		(end 4.0132 -432.7906)
		(width 0.508)
		(layer "F.Cu")
		(net "P12V")
	)
	(segment
		(start 8.8011 -452.374)
		(end 9.5631 -453.136)
		(width 0.508)
		(layer "F.Cu")
		(net "P12V")
	)
	(segment
		(start 4.1148 -420.9034)
		(end 4.1148 -419.3286)
		(width 0.508)
		(layer "F.Cu")
		(net "P12V")
	)
	(segment
		(start 12.064492 -62.889892)
		(end 12.319 -63.1444)
		(width 0.508)
		(layer "F.Cu")
		(net "P12V")
	)
	(via
		(at 29.21 -19.431)
		(size 0.5588)
		(drill 0.3048)
		(layers "F.Cu" "B.Cu")
		(net "P12V")
	)
	(via
		(at 34.798 -127.381)
		(size 0.7112)
		(drill 0.4064)
		(layers "F.Cu" "B.Cu")
		(net "P12V")
	)
	(via
		(at 13.2334 -130.3274)
		(size 0.5588)
		(drill 0.3048)
		(layers "F.Cu" "B.Cu")
		(net "P12V")
	)
	(via
		(at 25.019 -18.542)
		(size 0.5588)
		(drill 0.3048)
		(layers "F.Cu" "B.Cu")
		(net "P12V")
	)
	(via
		(at 29.21 -123.4694)
		(size 0.7112)
		(drill 0.3556)
		(layers "F.Cu" "B.Cu")
		(net "P12V")
	)
	(via
		(at 23.622 -385.7498)
		(size 0.7112)
		(drill 0.4064)
		(layers "F.Cu" "B.Cu")
		(net "P12V")
	)
	(via
		(at 23.241 -23.495)
		(size 0.5588)
		(drill 0.3048)
		(layers "F.Cu" "B.Cu")
		(net "P12V")
	)
	(via
		(at 24.892 -397.4338)
		(size 0.7112)
		(drill 0.3556)
		(layers "F.Cu" "B.Cu")
		(net "P12V")
	)
	(via
		(at 42.392092 -398.043908)
		(size 0.7112)
		(drill 0.4064)
		(layers "F.Cu" "B.Cu")
		(net "P12V")
	)
	(via
		(at 25.3492 -122.428)
		(size 0.7112)
		(drill 0.4064)
		(layers "F.Cu" "B.Cu")
		(net "P12V")
	)
	(via
		(at 32.766 -129.413)
		(size 0.7112)
		(drill 0.4064)
		(layers "F.Cu" "B.Cu")
		(net "P12V")
	)
	(via
		(at 19.812 -130.7592)
		(size 0.7112)
		(drill 0.4064)
		(layers "F.Cu" "B.Cu")
		(net "P12V")
	)
	(via
		(at 34.544 -390.144)
		(size 0.7112)
		(drill 0.4064)
		(layers "F.Cu" "B.Cu")
		(net "P12V")
	)
	(via
		(at 13.589 -385.826)
		(size 0.7112)
		(drill 0.4064)
		(layers "F.Cu" "B.Cu")
		(net "P12V")
	)
	(via
		(at 44.196 -386.588)
		(size 0.7112)
		(drill 0.4064)
		(layers "F.Cu" "B.Cu")
		(net "P12V")
	)
	(via
		(at 17.895316 -15.247874)
		(size 0.5588)
		(drill 0.3048)
		(layers "F.Cu" "B.Cu")
		(net "P12V")
	)
	(via
		(at 32.766 -396.875)
		(size 0.7112)
		(drill 0.4064)
		(layers "F.Cu" "B.Cu")
		(net "P12V")
	)
	(via
		(at 34.798 -476.885)
		(size 0.7112)
		(drill 0.3556)
		(layers "F.Cu" "B.Cu")
		(net "P12V")
	)
	(via
		(at 32.766 -389.89)
		(size 0.7112)
		(drill 0.4064)
		(layers "F.Cu" "B.Cu")
		(net "P12V")
	)
	(via
		(at 22.098 -270.002)
		(size 0.7112)
		(drill 0.4064)
		(layers "F.Cu" "B.Cu")
		(net "P12V")
	)
	(via
		(at 44.4246 -132.9182)
		(size 0.7112)
		(drill 0.4064)
		(layers "F.Cu" "B.Cu")
		(net "P12V")
	)
	(via
		(at 40.9702 -397.0274)
		(size 0.7112)
		(drill 0.4064)
		(layers "F.Cu" "B.Cu")
		(net "P12V")
	)
	(via
		(at 30.988 -394.208)
		(size 0.7112)
		(drill 0.4064)
		(layers "F.Cu" "B.Cu")
		(net "P12V")
	)
	(via
		(at 21.717 -256.413)
		(size 0.7112)
		(drill 0.3556)
		(layers "F.Cu" "B.Cu")
		(net "P12V")
	)
	(via
		(at 10.795 -64.5414)
		(size 0.5588)
		(drill 0.3048)
		(layers "F.Cu" "B.Cu")
		(net "P12V")
	)
	(via
		(at 43.18 -393.319)
		(size 0.7112)
		(drill 0.4064)
		(layers "F.Cu" "B.Cu")
		(net "P12V")
	)
	(via
		(at 28.1432 -122.5804)
		(size 0.7112)
		(drill 0.4064)
		(layers "F.Cu" "B.Cu")
		(net "P12V")
	)
	(via
		(at 26.543 -25.654)
		(size 0.5588)
		(drill 0.3048)
		(layers "F.Cu" "B.Cu")
		(net "P12V")
	)
	(via
		(at 32.766 -391.795)
		(size 0.7112)
		(drill 0.4064)
		(layers "F.Cu" "B.Cu")
		(net "P12V")
	)
	(via
		(at 14.1478 -223.52)
		(size 0.5588)
		(drill 0.3048)
		(layers "F.Cu" "B.Cu")
		(net "P12V")
	)
	(via
		(at 36.576 -127.381)
		(size 0.7112)
		(drill 0.4064)
		(layers "F.Cu" "B.Cu")
		(net "P12V")
	)
	(via
		(at 21.59 -128.6256)
		(size 0.7112)
		(drill 0.4064)
		(layers "F.Cu" "B.Cu")
		(net "P12V")
	)
	(via
		(at 45.339 -322.199)
		(size 0.7112)
		(drill 0.3556)
		(layers "F.Cu" "B.Cu")
		(net "P12V")
	)
	(via
		(at 27.178 -202.7428)
		(size 0.7112)
		(drill 0.4064)
		(layers "F.Cu" "B.Cu")
		(net "P12V")
	)
	(via
		(at 10.668 -453.2376)
		(size 0.7112)
		(drill 0.4064)
		(layers "F.Cu" "B.Cu")
		(net "P12V")
	)
	(via
		(at 38.1 -398.78)
		(size 0.7112)
		(drill 0.4064)
		(layers "F.Cu" "B.Cu")
		(net "P12V")
	)
	(via
		(at 36.576 -129.413)
		(size 0.5588)
		(drill 0.3048)
		(layers "F.Cu" "B.Cu")
		(net "P12V")
	)
	(via
		(at 14.859 -385.826)
		(size 0.7112)
		(drill 0.4064)
		(layers "F.Cu" "B.Cu")
		(net "P12V")
	)
	(via
		(at 43.18 -391.414)
		(size 0.7112)
		(drill 0.4064)
		(layers "F.Cu" "B.Cu")
		(net "P12V")
	)
	(via
		(at 24.257 -184.912)
		(size 0.7112)
		(drill 0.3556)
		(layers "F.Cu" "B.Cu")
		(net "P12V")
	)
	(via
		(at 44.196 -384.937)
		(size 0.7112)
		(drill 0.4064)
		(layers "F.Cu" "B.Cu")
		(net "P12V")
	)
	(via
		(at 24.7015 -259.969)
		(size 0.7112)
		(drill 0.4064)
		(layers "F.Cu" "B.Cu")
		(net "P12V")
	)
	(via
		(at 32.766 -125.349)
		(size 0.7112)
		(drill 0.4064)
		(layers "F.Cu" "B.Cu")
		(net "P12V")
	)
	(via
		(at 34.925 -132.969)
		(size 0.7112)
		(drill 0.4064)
		(layers "F.Cu" "B.Cu")
		(net "P12V")
	)
	(via
		(at 44.323 -381.889)
		(size 0.7112)
		(drill 0.4064)
		(layers "F.Cu" "B.Cu")
		(net "P12V")
	)
	(via
		(at 21.463 -130.6576)
		(size 0.7112)
		(drill 0.4064)
		(layers "F.Cu" "B.Cu")
		(net "P12V")
	)
	(via
		(at 25.908 -393.7)
		(size 0.7112)
		(drill 0.4064)
		(layers "F.Cu" "B.Cu")
		(net "P12V")
	)
	(via
		(at 48.006 -363.728)
		(size 0.7112)
		(drill 0.3556)
		(layers "F.Cu" "B.Cu")
		(net "P12V")
	)
	(via
		(at 39.8272 -128.7526)
		(size 0.7112)
		(drill 0.4064)
		(layers "F.Cu" "B.Cu")
		(net "P12V")
	)
	(via
		(at 28.1432 -128.6764)
		(size 0.7112)
		(drill 0.4064)
		(layers "F.Cu" "B.Cu")
		(net "P12V")
	)
	(via
		(at 16.764 -129.667)
		(size 0.7112)
		(drill 0.3556)
		(layers "F.Cu" "B.Cu")
		(net "P12V")
	)
	(via
		(at 47.371 -126.492)
		(size 0.7112)
		(drill 0.4064)
		(layers "F.Cu" "B.Cu")
		(net "P12V")
	)
	(via
		(at 44.1198 -130.5306)
		(size 0.7112)
		(drill 0.4064)
		(layers "F.Cu" "B.Cu")
		(net "P12V")
	)
	(via
		(at 34.544 -394.97)
		(size 0.7112)
		(drill 0.4064)
		(layers "F.Cu" "B.Cu")
		(net "P12V")
	)
	(via
		(at 25.4 -128.524)
		(size 0.7112)
		(drill 0.4064)
		(layers "F.Cu" "B.Cu")
		(net "P12V")
	)
	(via
		(at 30.48 -132.969)
		(size 0.7112)
		(drill 0.4064)
		(layers "F.Cu" "B.Cu")
		(net "P12V")
	)
	(via
		(at 23.876 -393.7)
		(size 0.7112)
		(drill 0.4064)
		(layers "F.Cu" "B.Cu")
		(net "P12V")
	)
	(via
		(at 25.908 -398.272)
		(size 0.7112)
		(drill 0.4064)
		(layers "F.Cu" "B.Cu")
		(net "P12V")
	)
	(via
		(at 27.148028 -201.727054)
		(size 0.7112)
		(drill 0.4064)
		(layers "F.Cu" "B.Cu")
		(net "P12V")
	)
	(via
		(at 10.795 -125.222)
		(size 0.7112)
		(drill 0.4064)
		(layers "F.Cu" "B.Cu")
		(net "P12V")
	)
	(via
		(at 18.3134 -132.5372)
		(size 0.7112)
		(drill 0.4064)
		(layers "F.Cu" "B.Cu")
		(net "P12V")
	)
	(via
		(at 9.930384 -171.428918)
		(size 0.7112)
		(drill 0.4064)
		(layers "F.Cu" "B.Cu")
		(net "P12V")
	)
	(via
		(at 14.478 -398.399)
		(size 0.7112)
		(drill 0.4064)
		(layers "F.Cu" "B.Cu")
		(net "P12V")
	)
	(via
		(at 39.37 -287.147)
		(size 0.7112)
		(drill 0.4064)
		(layers "F.Cu" "B.Cu")
		(net "P12V")
	)
	(via
		(at 22.733 -12.573)
		(size 0.5588)
		(drill 0.3048)
		(layers "F.Cu" "B.Cu")
		(net "P12V")
	)
	(via
		(at 17.526 -184.6072)
		(size 0.5588)
		(drill 0.3048)
		(layers "F.Cu" "B.Cu")
		(net "P12V")
	)
	(via
		(at 30.226 -388.493)
		(size 0.7112)
		(drill 0.4064)
		(layers "F.Cu" "B.Cu")
		(net "P12V")
	)
	(via
		(at 28.956 -392.684)
		(size 0.7112)
		(drill 0.4064)
		(layers "F.Cu" "B.Cu")
		(net "P12V")
	)
	(via
		(at 18.288 -130.7592)
		(size 0.7112)
		(drill 0.4064)
		(layers "F.Cu" "B.Cu")
		(net "P12V")
	)
	(via
		(at 13.1318 -132.715)
		(size 0.7112)
		(drill 0.4064)
		(layers "F.Cu" "B.Cu")
		(net "P12V")
	)
	(via
		(at 23.8506 -28.3972)
		(size 0.5588)
		(drill 0.3048)
		(layers "F.Cu" "B.Cu")
		(net "P12V")
	)
	(via
		(at 34.544 -393.192)
		(size 0.7112)
		(drill 0.4064)
		(layers "F.Cu" "B.Cu")
		(net "P12V")
	)
	(via
		(at 42.1894 -134.0866)
		(size 0.5588)
		(drill 0.3048)
		(layers "F.Cu" "B.Cu")
		(net "P12V")
	)
	(via
		(at 39.37 -284.48)
		(size 0.7112)
		(drill 0.4064)
		(layers "F.Cu" "B.Cu")
		(net "P12V")
	)
	(via
		(at 28.956 -394.208)
		(size 0.7112)
		(drill 0.4064)
		(layers "F.Cu" "B.Cu")
		(net "P12V")
	)
	(via
		(at 28.956 -397.256)
		(size 0.7112)
		(drill 0.4064)
		(layers "F.Cu" "B.Cu")
		(net "P12V")
	)
	(via
		(at 51.076606 -132.969)
		(size 0.7112)
		(drill 0.4064)
		(layers "F.Cu" "B.Cu")
		(net "P12V")
	)
	(via
		(at 20.32 -389.0264)
		(size 0.7112)
		(drill 0.4064)
		(layers "F.Cu" "B.Cu")
		(net "P12V")
	)
	(via
		(at 27.686 -19.431)
		(size 0.5588)
		(drill 0.3048)
		(layers "F.Cu" "B.Cu")
		(net "P12V")
	)
	(via
		(at 26.797 -185.928)
		(size 0.7112)
		(drill 0.3556)
		(layers "F.Cu" "B.Cu")
		(net "P12V")
	)
	(via
		(at 12.319 -63.1444)
		(size 0.5588)
		(drill 0.3048)
		(layers "F.Cu" "B.Cu")
		(net "P12V")
	)
	(via
		(at 23.749 -25.781)
		(size 0.5588)
		(drill 0.3048)
		(layers "F.Cu" "B.Cu")
		(net "P12V")
	)
	(via
		(at 16.256 -17.158462)
		(size 0.5588)
		(drill 0.3048)
		(layers "F.Cu" "B.Cu")
		(net "P12V")
	)
	(via
		(at 8.4963 -145.8722)
		(size 0.5588)
		(drill 0.3048)
		(layers "F.Cu" "B.Cu")
		(net "P12V")
	)
	(via
		(at 10.16 -167.386)
		(size 0.7112)
		(drill 0.4064)
		(layers "F.Cu" "B.Cu")
		(net "P12V")
	)
	(via
		(at 28.1432 -127.1524)
		(size 0.7112)
		(drill 0.4064)
		(layers "F.Cu" "B.Cu")
		(net "P12V")
	)
	(via
		(at 36.576 -131.445)
		(size 0.7112)
		(drill 0.4064)
		(layers "F.Cu" "B.Cu")
		(net "P12V")
	)
	(via
		(at 16.256 -249.047)
		(size 0.7112)
		(drill 0.4064)
		(layers "F.Cu" "B.Cu")
		(net "P12V")
	)
	(via
		(at 32.766 -131.445)
		(size 0.7112)
		(drill 0.4064)
		(layers "F.Cu" "B.Cu")
		(net "P12V")
	)
	(via
		(at 41.021 -311.785)
		(size 0.7112)
		(drill 0.4064)
		(layers "F.Cu" "B.Cu")
		(net "P12V")
	)
	(via
		(at 30.988 -392.684)
		(size 0.7112)
		(drill 0.4064)
		(layers "F.Cu" "B.Cu")
		(net "P12V")
	)
	(via
		(at 47.371 -131.826)
		(size 0.7112)
		(drill 0.4064)
		(layers "F.Cu" "B.Cu")
		(net "P12V")
	)
	(via
		(at 51.1048 -131.8768)
		(size 0.7112)
		(drill 0.4064)
		(layers "F.Cu" "B.Cu")
		(net "P12V")
	)
	(via
		(at 30.988 -400.304)
		(size 0.7112)
		(drill 0.4064)
		(layers "F.Cu" "B.Cu")
		(net "P12V")
	)
	(via
		(at 21.6408 -384.81)
		(size 0.7112)
		(drill 0.4064)
		(layers "F.Cu" "B.Cu")
		(net "P12V")
	)
	(via
		(at 23.876 -396.748)
		(size 0.7112)
		(drill 0.4064)
		(layers "F.Cu" "B.Cu")
		(net "P12V")
	)
	(via
		(at 2.667 -418.7952)
		(size 0.5588)
		(drill 0.3048)
		(layers "F.Cu" "B.Cu")
		(net "P12V")
	)
	(via
		(at 29.4386 -398.7038)
		(size 0.7112)
		(drill 0.4064)
		(layers "F.Cu" "B.Cu")
		(net "P12V")
	)
	(via
		(at 24.638 -13.081)
		(size 0.5588)
		(drill 0.3048)
		(layers "F.Cu" "B.Cu")
		(net "P12V")
	)
	(via
		(at 28.1432 -125.6284)
		(size 0.7112)
		(drill 0.4064)
		(layers "F.Cu" "B.Cu")
		(net "P12V")
	)
	(via
		(at 16.1036 -147.6756)
		(size 0.5588)
		(drill 0.3048)
		(layers "F.Cu" "B.Cu")
		(net "P12V")
	)
	(via
		(at 28.448 -25.654)
		(size 0.5588)
		(drill 0.3048)
		(layers "F.Cu" "B.Cu")
		(net "P12V")
	)
	(via
		(at 25.4 -130.048)
		(size 0.7112)
		(drill 0.4064)
		(layers "F.Cu" "B.Cu")
		(net "P12V")
	)
	(via
		(at 23.876 -395.224)
		(size 0.7112)
		(drill 0.4064)
		(layers "F.Cu" "B.Cu")
		(net "P12V")
	)
	(via
		(at 37.592 -393.7)
		(size 0.7112)
		(drill 0.4064)
		(layers "F.Cu" "B.Cu")
		(net "P12V")
	)
	(via
		(at 50.165 -122.301)
		(size 0.7112)
		(drill 0.3556)
		(layers "F.Cu" "B.Cu")
		(net "P12V")
	)
	(via
		(at 13.843 -399.796)
		(size 0.7112)
		(drill 0.4064)
		(layers "F.Cu" "B.Cu")
		(net "P12V")
	)
	(via
		(at 32.766 -393.446)
		(size 0.7112)
		(drill 0.4064)
		(layers "F.Cu" "B.Cu")
		(net "P12V")
	)
	(via
		(at 39.9034 -127)
		(size 0.7112)
		(drill 0.4064)
		(layers "F.Cu" "B.Cu")
		(net "P12V")
	)
	(via
		(at 23.2156 -270.2814)
		(size 0.7112)
		(drill 0.4064)
		(layers "F.Cu" "B.Cu")
		(net "P12V")
	)
	(via
		(at 48.768 -126.492)
		(size 0.7112)
		(drill 0.4064)
		(layers "F.Cu" "B.Cu")
		(net "P12V")
	)
	(via
		(at 30.988 -390.652)
		(size 0.7112)
		(drill 0.4064)
		(layers "F.Cu" "B.Cu")
		(net "P12V")
	)
	(via
		(at 39.624 -398.78)
		(size 0.7112)
		(drill 0.4064)
		(layers "F.Cu" "B.Cu")
		(net "P12V")
	)
	(via
		(at 29.464 -400.304)
		(size 0.7112)
		(drill 0.4064)
		(layers "F.Cu" "B.Cu")
		(net "P12V")
	)
	(via
		(at 11.684 -131.064)
		(size 0.5588)
		(drill 0.3048)
		(layers "F.Cu" "B.Cu")
		(net "P12V")
	)
	(via
		(at 34.925 -131.445)
		(size 0.7112)
		(drill 0.4064)
		(layers "F.Cu" "B.Cu")
		(net "P12V")
	)
	(via
		(at 11.811 -129.794)
		(size 0.5588)
		(drill 0.3048)
		(layers "F.Cu" "B.Cu")
		(net "P12V")
	)
	(via
		(at 39.2684 -147.701)
		(size 0.5588)
		(drill 0.3048)
		(layers "F.Cu" "B.Cu")
		(net "P12V")
	)
	(via
		(at 23.1902 -134.1628)
		(size 0.5588)
		(drill 0.3048)
		(layers "F.Cu" "B.Cu")
		(net "P12V")
	)
	(via
		(at 37.592 -388.112)
		(size 0.7112)
		(drill 0.4064)
		(layers "F.Cu" "B.Cu")
		(net "P12V")
	)
	(via
		(at 49.1744 -131.8514)
		(size 0.7112)
		(drill 0.4064)
		(layers "F.Cu" "B.Cu")
		(net "P12V")
	)
	(via
		(at 30.48 -131.445)
		(size 0.7112)
		(drill 0.4064)
		(layers "F.Cu" "B.Cu")
		(net "P12V")
	)
	(via
		(at 44.323 -383.413)
		(size 0.7112)
		(drill 0.4064)
		(layers "F.Cu" "B.Cu")
		(net "P12V")
	)
	(via
		(at 50.8254 -130.4544)
		(size 0.7112)
		(drill 0.4064)
		(layers "F.Cu" "B.Cu")
		(net "P12V")
	)
	(via
		(at 25.908 -392.176)
		(size 0.7112)
		(drill 0.4064)
		(layers "F.Cu" "B.Cu")
		(net "P12V")
	)
	(via
		(at 38.1 -400.304)
		(size 0.7112)
		(drill 0.4064)
		(layers "F.Cu" "B.Cu")
		(net "P12V")
	)
	(via
		(at 24.2316 -270.2814)
		(size 0.7112)
		(drill 0.4064)
		(layers "F.Cu" "B.Cu")
		(net "P12V")
	)
	(via
		(at 32.512 -398.272)
		(size 0.7112)
		(drill 0.4064)
		(layers "F.Cu" "B.Cu")
		(net "P12V")
	)
	(via
		(at 32.766 -127.381)
		(size 0.7112)
		(drill 0.4064)
		(layers "F.Cu" "B.Cu")
		(net "P12V")
	)
	(via
		(at 34.544 -388.112)
		(size 0.7112)
		(drill 0.4064)
		(layers "F.Cu" "B.Cu")
		(net "P12V")
	)
	(via
		(at 18.0594 -297.434)
		(size 0.5588)
		(drill 0.3048)
		(layers "F.Cu" "B.Cu")
		(net "P12V")
	)
	(via
		(at 34.544 -396.748)
		(size 0.7112)
		(drill 0.4064)
		(layers "F.Cu" "B.Cu")
		(net "P12V")
	)
	(via
		(at 34.798 -125.222)
		(size 0.7112)
		(drill 0.4064)
		(layers "F.Cu" "B.Cu")
		(net "P12V")
	)
	(via
		(at 25.4 -125.476)
		(size 0.7112)
		(drill 0.4064)
		(layers "F.Cu" "B.Cu")
		(net "P12V")
	)
	(via
		(at 50.673 -124.3076)
		(size 0.7112)
		(drill 0.4064)
		(layers "F.Cu" "B.Cu")
		(net "P12V")
	)
	(via
		(at 30.48 -129.413)
		(size 0.7112)
		(drill 0.4064)
		(layers "F.Cu" "B.Cu")
		(net "P12V")
	)
	(via
		(at 32.766 -123.317)
		(size 0.7112)
		(drill 0.4064)
		(layers "F.Cu" "B.Cu")
		(net "P12V")
	)
	(via
		(at 25.4 -123.952)
		(size 0.7112)
		(drill 0.4064)
		(layers "F.Cu" "B.Cu")
		(net "P12V")
	)
	(via
		(at 29.845 -385.953)
		(size 0.7112)
		(drill 0.3556)
		(layers "F.Cu" "B.Cu")
		(net "P12V")
	)
	(via
		(at 18.7706 -390.1186)
		(size 0.7112)
		(drill 0.4064)
		(layers "F.Cu" "B.Cu")
		(net "P12V")
	)
	(via
		(at 23.876 -398.272)
		(size 0.7112)
		(drill 0.4064)
		(layers "F.Cu" "B.Cu")
		(net "P12V")
	)
	(via
		(at 32.766 -395.097)
		(size 0.7112)
		(drill 0.4064)
		(layers "F.Cu" "B.Cu")
		(net "P12V")
	)
	(via
		(at 9.8552 -450.85)
		(size 0.7112)
		(drill 0.4064)
		(layers "F.Cu" "B.Cu")
		(net "P12V")
	)
	(via
		(at 11.684 -124.587)
		(size 0.7112)
		(drill 0.4064)
		(layers "F.Cu" "B.Cu")
		(net "P12V")
	)
	(via
		(at 23.876 -384.556)
		(size 0.7112)
		(drill 0.4064)
		(layers "F.Cu" "B.Cu")
		(net "P12V")
	)
	(via
		(at 39.116 -397.256)
		(size 0.7112)
		(drill 0.4064)
		(layers "F.Cu" "B.Cu")
		(net "P12V")
	)
	(via
		(at 3.5306 -433.3748)
		(size 0.7112)
		(drill 0.4064)
		(layers "F.Cu" "B.Cu")
		(net "P12V")
	)
	(via
		(at 30.9372 -398.761966)
		(size 0.7112)
		(drill 0.4064)
		(layers "F.Cu" "B.Cu")
		(net "P12V")
	)
	(via
		(at 36.576 -125.349)
		(size 0.7112)
		(drill 0.4064)
		(layers "F.Cu" "B.Cu")
		(net "P12V")
	)
	(via
		(at 28.1432 -124.1044)
		(size 0.7112)
		(drill 0.4064)
		(layers "F.Cu" "B.Cu")
		(net "P12V")
	)
	(via
		(at 23.622 -27.178)
		(size 0.5588)
		(drill 0.3048)
		(layers "F.Cu" "B.Cu")
		(net "P12V")
	)
	(via
		(at 12.7254 -125.222)
		(size 0.7112)
		(drill 0.4064)
		(layers "F.Cu" "B.Cu")
		(net "P12V")
	)
	(via
		(at 23.241 -261.747)
		(size 0.7112)
		(drill 0.3556)
		(layers "F.Cu" "B.Cu")
		(net "P12V")
	)
	(via
		(at 18.288 -384.556)
		(size 0.7112)
		(drill 0.4064)
		(layers "F.Cu" "B.Cu")
		(net "P12V")
	)
	(via
		(at 20.828 -122.8344)
		(size 0.7112)
		(drill 0.4064)
		(layers "F.Cu" "B.Cu")
		(net "P12V")
	)
	(via
		(at 44.0944 -126.6952)
		(size 0.7112)
		(drill 0.4064)
		(layers "F.Cu" "B.Cu")
		(net "P12V")
	)
	(via
		(at 32.766 -132.969)
		(size 0.7112)
		(drill 0.4064)
		(layers "F.Cu" "B.Cu")
		(net "P12V")
	)
	(via
		(at 50.8762 -126.5174)
		(size 0.7112)
		(drill 0.4064)
		(layers "F.Cu" "B.Cu")
		(net "P12V")
	)
	(via
		(at 39.624 -400.304)
		(size 0.7112)
		(drill 0.4064)
		(layers "F.Cu" "B.Cu")
		(net "P12V")
	)
	(via
		(at 10.5664 -443.7126)
		(size 0.7112)
		(drill 0.4064)
		(layers "F.Cu" "B.Cu")
		(net "P12V")
	)
	(via
		(at 23.114 -24.638)
		(size 0.5588)
		(drill 0.3048)
		(layers "F.Cu" "B.Cu")
		(net "P12V")
	)
	(via
		(at 30.988 -397.256)
		(size 0.7112)
		(drill 0.4064)
		(layers "F.Cu" "B.Cu")
		(net "P12V")
	)
	(via
		(at 16.383 -13.462)
		(size 0.5588)
		(drill 0.3048)
		(layers "F.Cu" "B.Cu")
		(net "P12V")
	)
	(via
		(at 44.069 -128.524)
		(size 0.7112)
		(drill 0.4064)
		(layers "F.Cu" "B.Cu")
		(net "P12V")
	)
	(via
		(at 8.0264 -260.1722)
		(size 0.7112)
		(drill 0.4064)
		(layers "F.Cu" "B.Cu")
		(net "P12V")
	)
	(via
		(at 13.7922 -391.4648)
		(size 0.7112)
		(drill 0.4064)
		(layers "F.Cu" "B.Cu")
		(net "P12V")
	)
	(via
		(at 29.337 -15.113)
		(size 0.5588)
		(drill 0.3048)
		(layers "F.Cu" "B.Cu")
		(net "P12V")
	)
	(via
		(at 34.798 -129.54)
		(size 0.7112)
		(drill 0.4064)
		(layers "F.Cu" "B.Cu")
		(net "P12V")
	)
	(via
		(at 20.1676 -132.5372)
		(size 0.7112)
		(drill 0.4064)
		(layers "F.Cu" "B.Cu")
		(net "P12V")
	)
	(via
		(at 29.704792 -480.568)
		(size 0.7112)
		(drill 0.4064)
		(layers "F.Cu" "B.Cu")
		(net "P12V")
	)
	(via
		(at 23.241 -22.479)
		(size 0.5588)
		(drill 0.3048)
		(layers "F.Cu" "B.Cu")
		(net "P12V")
	)
	(via
		(at 48.768 -124.46)
		(size 0.7112)
		(drill 0.4064)
		(layers "F.Cu" "B.Cu")
		(net "P12V")
	)
	(via
		(at 31.623 -480.670362)
		(size 0.7112)
		(drill 0.4064)
		(layers "F.Cu" "B.Cu")
		(net "P12V")
	)
	(via
		(at 10.993374 -171.447714)
		(size 0.7112)
		(drill 0.4064)
		(layers "F.Cu" "B.Cu")
		(net "P12V")
	)
	(via
		(at 19.939 -128.7018)
		(size 0.7112)
		(drill 0.4064)
		(layers "F.Cu" "B.Cu")
		(net "P12V")
	)
	(via
		(at 28.1432 -130.2004)
		(size 0.7112)
		(drill 0.4064)
		(layers "F.Cu" "B.Cu")
		(net "P12V")
	)
	(via
		(at 28.956 -395.732)
		(size 0.7112)
		(drill 0.4064)
		(layers "F.Cu" "B.Cu")
		(net "P12V")
	)
	(via
		(at 30.48 -127.381)
		(size 0.7112)
		(drill 0.4064)
		(layers "F.Cu" "B.Cu")
		(net "P12V")
	)
	(via
		(at 27.178 -203.8096)
		(size 0.7112)
		(drill 0.4064)
		(layers "F.Cu" "B.Cu")
		(net "P12V")
	)
	(via
		(at 23.1775 -178.9938)
		(size 0.5588)
		(drill 0.3048)
		(layers "F.Cu" "B.Cu")
		(net "P12V")
	)
	(via
		(at 31.623 -387.096)
		(size 0.7112)
		(drill 0.4064)
		(layers "F.Cu" "B.Cu")
		(net "P12V")
	)
	(via
		(at 37.592 -391.668)
		(size 0.7112)
		(drill 0.4064)
		(layers "F.Cu" "B.Cu")
		(net "P12V")
	)
	(via
		(at 47.371 -128.524)
		(size 0.7112)
		(drill 0.4064)
		(layers "F.Cu" "B.Cu")
		(net "P12V")
	)
	(via
		(at 47.371 -130.429)
		(size 0.7112)
		(drill 0.4064)
		(layers "F.Cu" "B.Cu")
		(net "P12V")
	)
	(via
		(at 19.8628 -127.254)
		(size 0.7112)
		(drill 0.4064)
		(layers "F.Cu" "B.Cu")
		(net "P12V")
	)
	(via
		(at 12.61491 -163.304982)
		(size 0.7112)
		(drill 0.3556)
		(layers "F.Cu" "B.Cu")
		(net "P12V")
	)
	(via
		(at 40.9956 -392.049)
		(size 0.7112)
		(drill 0.4064)
		(layers "F.Cu" "B.Cu")
		(net "P12V")
	)
	(via
		(at 25.908 -396.748)
		(size 0.7112)
		(drill 0.4064)
		(layers "F.Cu" "B.Cu")
		(net "P12V")
	)
	(via
		(at 27.813 -15.748)
		(size 0.5588)
		(drill 0.3048)
		(layers "F.Cu" "B.Cu")
		(net "P12V")
	)
	(via
		(at 25.4 -127)
		(size 0.7112)
		(drill 0.4064)
		(layers "F.Cu" "B.Cu")
		(net "P12V")
	)
	(via
		(at 25.4 -131.8514)
		(size 0.7112)
		(drill 0.4064)
		(layers "F.Cu" "B.Cu")
		(net "P12V")
	)
	(via
		(at 12.2936 -443.7126)
		(size 0.7112)
		(drill 0.4064)
		(layers "F.Cu" "B.Cu")
		(net "P12V")
	)
	(via
		(at 39.37 -285.75)
		(size 0.7112)
		(drill 0.4064)
		(layers "F.Cu" "B.Cu")
		(net "P12V")
	)
	(via
		(at 18.2372 -128.7526)
		(size 0.7112)
		(drill 0.4064)
		(layers "F.Cu" "B.Cu")
		(net "P12V")
	)
	(via
		(at 43.18 -394.97)
		(size 0.7112)
		(drill 0.4064)
		(layers "F.Cu" "B.Cu")
		(net "P12V")
	)
	(via
		(at 27.686 -205.613)
		(size 0.7112)
		(drill 0.3556)
		(layers "F.Cu" "B.Cu")
		(net "P12V")
	)
	(via
		(at 14.605 -396.748)
		(size 0.7112)
		(drill 0.4064)
		(layers "F.Cu" "B.Cu")
		(net "P12V")
	)
	(via
		(at 42.799 -389.509)
		(size 0.7112)
		(drill 0.4064)
		(layers "F.Cu" "B.Cu")
		(net "P12V")
	)
	(via
		(at 34.544 -391.668)
		(size 0.7112)
		(drill 0.4064)
		(layers "F.Cu" "B.Cu")
		(net "P12V")
	)
	(via
		(at 42.9768 -122.6312)
		(size 0.7112)
		(drill 0.4064)
		(layers "F.Cu" "B.Cu")
		(net "P12V")
	)
	(via
		(at 35.524694 -479.923094)
		(size 0.7112)
		(drill 0.3556)
		(layers "F.Cu" "B.Cu")
		(net "P12V")
	)
	(via
		(at 48.768 -128.524)
		(size 0.7112)
		(drill 0.4064)
		(layers "F.Cu" "B.Cu")
		(net "P12V")
	)
	(via
		(at 40.4495 -149.9235)
		(size 0.5588)
		(drill 0.3048)
		(layers "F.Cu" "B.Cu")
		(net "P12V")
	)
	(via
		(at 34.544 -398.272)
		(size 0.7112)
		(drill 0.4064)
		(layers "F.Cu" "B.Cu")
		(net "P12V")
	)
	(via
		(at 50.7492 -128.524)
		(size 0.7112)
		(drill 0.4064)
		(layers "F.Cu" "B.Cu")
		(net "P12V")
	)
	(via
		(at 33.528 -480.568)
		(size 0.7112)
		(drill 0.4064)
		(layers "F.Cu" "B.Cu")
		(net "P12V")
	)
	(via
		(at 37.6682 -372.11)
		(size 0.7112)
		(drill 0.4064)
		(layers "F.Cu" "B.Cu")
		(net "P12V")
	)
	(via
		(at 43.053 -396.621)
		(size 0.7112)
		(drill 0.4064)
		(layers "F.Cu" "B.Cu")
		(net "P12V")
	)
	(via
		(at 37.592 -395.732)
		(size 0.7112)
		(drill 0.4064)
		(layers "F.Cu" "B.Cu")
		(net "P12V")
	)
	(via
		(at 48.3108 -132.9436)
		(size 0.7112)
		(drill 0.4064)
		(layers "F.Cu" "B.Cu")
		(net "P12V")
	)
	(via
		(at 48.768 -130.429)
		(size 0.7112)
		(drill 0.4064)
		(layers "F.Cu" "B.Cu")
		(net "P12V")
	)
	(via
		(at 11.007598 -165.13683)
		(size 0.7112)
		(drill 0.3556)
		(layers "F.Cu" "B.Cu")
		(net "P12V")
	)
	(via
		(at 25.273 -15.494)
		(size 0.5588)
		(drill 0.3048)
		(layers "F.Cu" "B.Cu")
		(net "P12V")
	)
	(via
		(at 30.48 -123.317)
		(size 0.7112)
		(drill 0.4064)
		(layers "F.Cu" "B.Cu")
		(net "P12V")
	)
	(via
		(at 37.846 -132.715)
		(size 0.7112)
		(drill 0.3556)
		(layers "F.Cu" "B.Cu")
		(net "P12V")
	)
	(via
		(at 37.592 -397.256)
		(size 0.7112)
		(drill 0.4064)
		(layers "F.Cu" "B.Cu")
		(net "P12V")
	)
	(via
		(at 34.671 -123.317)
		(size 0.7112)
		(drill 0.4064)
		(layers "F.Cu" "B.Cu")
		(net "P12V")
	)
	(via
		(at 18.2626 -127.254)
		(size 0.7112)
		(drill 0.4064)
		(layers "F.Cu" "B.Cu")
		(net "P12V")
	)
	(via
		(at 36.576 -123.490228)
		(size 0.7112)
		(drill 0.4064)
		(layers "F.Cu" "B.Cu")
		(net "P12V")
	)
	(via
		(at 22.3266 -386.9436)
		(size 0.7112)
		(drill 0.4064)
		(layers "F.Cu" "B.Cu")
		(net "P12V")
	)
	(via
		(at 20.851876 -282.575)
		(size 0.5588)
		(drill 0.3048)
		(layers "F.Cu" "B.Cu")
		(net "P12V")
	)
	(via
		(at 28.321 -390.525)
		(size 0.7112)
		(drill 0.4064)
		(layers "F.Cu" "B.Cu")
		(net "P12V")
	)
	(via
		(at 30.988 -395.732)
		(size 0.7112)
		(drill 0.4064)
		(layers "F.Cu" "B.Cu")
		(net "P12V")
	)
	(via
		(at 25.908 -395.224)
		(size 0.7112)
		(drill 0.4064)
		(layers "F.Cu" "B.Cu")
		(net "P12V")
	)
	(via
		(at 47.244 -287.782)
		(size 0.7112)
		(drill 0.3556)
		(layers "F.Cu" "B.Cu")
		(net "P12V")
	)
	(via
		(at 5.4864 -84.7852)
		(size 0.5588)
		(drill 0.3048)
		(layers "F.Cu" "B.Cu")
		(net "P12V")
	)
	(via
		(at 15.113 -391.414)
		(size 0.7112)
		(drill 0.4064)
		(layers "F.Cu" "B.Cu")
		(net "P12V")
	)
	(via
		(at 30.48 -125.349)
		(size 0.7112)
		(drill 0.4064)
		(layers "F.Cu" "B.Cu")
		(net "P12V")
	)
	(via
		(at 39.8272 -130.9116)
		(size 0.7112)
		(drill 0.4064)
		(layers "F.Cu" "B.Cu")
		(net "P12V")
	)
	(via
		(at 42.799 -387.604)
		(size 0.7112)
		(drill 0.4064)
		(layers "F.Cu" "B.Cu")
		(net "P12V")
	)
	(segment
		(start 23.1902 -134.1628)
		(end 23.1902 -134.162546)
		(width 0.508)
		(layer "B.Cu")
		(net "P12V")
	)
	(segment
		(start 23.1902 -134.162546)
		(end 23.622 -133.730746)
		(width 0.508)
		(layer "B.Cu")
		(net "P12V")
	)
	(segment
		(start 42.9768 -122.6312)
		(end 42.9768 -124.4092)
		(width 0.508)
		(layer "B.Cu")
		(net "P12V")
	)
	(segment
		(start 23.622 -127.367792)
		(end 20.828 -124.573792)
		(width 0.508)
		(layer "B.Cu")
		(net "P12V")
	)
	(segment
		(start 20.828 -124.573792)
		(end 20.828 -122.8344)
		(width 0.508)
		(layer "B.Cu")
		(net "P12V")
	)
	(segment
		(start 42.9768 -124.4092)
		(end 42.1894 -125.1966)
		(width 0.508)
		(layer "B.Cu")
		(net "P12V")
	)
	(segment
		(start 23.622 -133.730746)
		(end 23.622 -127.367792)
		(width 0.508)
		(layer "B.Cu")
		(net "P12V")
	)
	(segment
		(start 42.1894 -125.1966)
		(end 42.1894 -134.0866)
		(width 0.508)
		(layer "B.Cu")
		(net "P12V")
	)
	(segment
		(start 22.71649 -160.721548)
		(end 23.638002 -159.800036)
		(width 0.1397)
		(layer "F.Cu")
		(net "NCT7904_GND")
	)
	(segment
		(start 22.71649 -161.297366)
		(end 22.71649 -160.721548)
		(width 0.1397)
		(layer "F.Cu")
		(net "NCT7904_GND")
	)
	(segment
		(start 23.638002 -159.784034)
		(end 23.638002 -159.800036)
		(width 0.1397)
		(layer "F.Cu")
		(net "NCT7904_GND")
	)
	(segment
		(start 23.82266 -159.599376)
		(end 23.638002 -159.784034)
		(width 0.1397)
		(layer "F.Cu")
		(net "NCT7904_GND")
	)
	(segment
		(start 26.12009 -159.599376)
		(end 23.82266 -159.599376)
		(width 0.1397)
		(layer "F.Cu")
		(net "NCT7904_GND")
	)
	(via
		(at 23.638002 -159.800036)
		(size 0.7112)
		(drill 0.3556)
		(layers "F.Cu" "B.Cu")
		(net "NCT7904_GND")
	)
	(segment
		(start 28.405582 -372.965218)
		(end 29.068014 -372.302786)
		(width 0.254)
		(layer "F.Cu")
		(net "ADM1276_VCC")
	)
	(segment
		(start 27.2034 -374.523)
		(end 28.405582 -373.320818)
		(width 0.254)
		(layer "F.Cu")
		(net "ADM1276_VCC")
	)
	(segment
		(start 27.11958 -377.44908)
		(end 27.305 -377.6345)
		(width 0.254)
		(layer "F.Cu")
		(net "ADM1276_VCC")
	)
	(segment
		(start 27.178 -374.523)
		(end 27.2034 -374.523)
		(width 0.254)
		(layer "F.Cu")
		(net "ADM1276_VCC")
	)
	(segment
		(start 28.405582 -373.295418)
		(end 28.405582 -372.965218)
		(width 0.254)
		(layer "F.Cu")
		(net "ADM1276_VCC")
	)
	(segment
		(start 27.11958 -376.08256)
		(end 27.11958 -377.44908)
		(width 0.254)
		(layer "F.Cu")
		(net "ADM1276_VCC")
	)
	(segment
		(start 29.068014 -372.302786)
		(end 29.068014 -371.2464)
		(width 0.254)
		(layer "F.Cu")
		(net "ADM1276_VCC")
	)
	(segment
		(start 27.11958 -374.58142)
		(end 27.11958 -376.08256)
		(width 0.254)
		(layer "F.Cu")
		(net "ADM1276_VCC")
	)
	(segment
		(start 27.178 -374.523)
		(end 27.11958 -374.58142)
		(width 0.254)
		(layer "F.Cu")
		(net "ADM1276_VCC")
	)
	(segment
		(start 28.405582 -373.320818)
		(end 28.405582 -373.295418)
		(width 0.254)
		(layer "F.Cu")
		(net "ADM1276_VCC")
	)
	(via
		(at 28.405582 -373.295418)
		(size 0.7112)
		(drill 0.3556)
		(layers "F.Cu" "B.Cu")
		(net "ADM1276_VCC")
	)
	(segment
		(start 25.0952 -157.5054)
		(end 25.188926 -157.599126)
		(width 0.1397)
		(layer "F.Cu")
		(net "NCT7904_CASEOPEN")
	)
	(segment
		(start 25.292812 -153.865834)
		(end 25.0952 -154.063446)
		(width 0.1397)
		(layer "F.Cu")
		(net "NCT7904_CASEOPEN")
	)
	(segment
		(start 25.292812 -153.820114)
		(end 25.292812 -153.865834)
		(width 0.1397)
		(layer "F.Cu")
		(net "NCT7904_CASEOPEN")
	)
	(segment
		(start 25.097232 -152.162256)
		(end 25.097232 -153.624534)
		(width 0.1397)
		(layer "F.Cu")
		(net "NCT7904_CASEOPEN")
	)
	(segment
		(start 24.70531 -151.770334)
		(end 25.097232 -152.162256)
		(width 0.1397)
		(layer "F.Cu")
		(net "NCT7904_CASEOPEN")
	)
	(segment
		(start 25.0952 -154.063446)
		(end 25.0952 -157.5054)
		(width 0.1397)
		(layer "F.Cu")
		(net "NCT7904_CASEOPEN")
	)
	(segment
		(start 25.097232 -153.624534)
		(end 25.292812 -153.820114)
		(width 0.1397)
		(layer "F.Cu")
		(net "NCT7904_CASEOPEN")
	)
	(segment
		(start 25.188926 -157.599126)
		(end 26.12009 -157.599126)
		(width 0.1397)
		(layer "F.Cu")
		(net "NCT7904_CASEOPEN")
	)
	(via
		(at 25.292812 -153.865834)
		(size 0.7112)
		(drill 0.3556)
		(layers "F.Cu" "B.Cu")
		(net "NCT7904_CASEOPEN")
	)
	(segment
		(start 12.5984 -146.5453)
		(end 11.4935 -146.5453)
		(width 0.1397)
		(layer "F.Cu")
		(net "FANIN_10")
	)
	(segment
		(start 11.4935 -146.5453)
		(end 11.4554 -146.5834)
		(width 0.1397)
		(layer "F.Cu")
		(net "FANIN_10")
	)
	(segment
		(start 28.11145 -165.035992)
		(end 28.11145 -164.091366)
		(width 0.1397)
		(layer "F.Cu")
		(net "FANIN_10")
	)
	(segment
		(start 14.4272 -146.5453)
		(end 12.5984 -146.5453)
		(width 0.1397)
		(layer "F.Cu")
		(net "FANIN_10")
	)
	(segment
		(start 27.4828 -166.57955)
		(end 27.4828 -165.664642)
		(width 0.1397)
		(layer "F.Cu")
		(net "FANIN_10")
	)
	(segment
		(start 27.4828 -165.664642)
		(end 28.11145 -165.035992)
		(width 0.1397)
		(layer "F.Cu")
		(net "FANIN_10")
	)
	(via
		(at 14.4272 -146.5453)
		(size 0.7112)
		(drill 0.4064)
		(layers "F.Cu" "B.Cu")
		(net "FANIN_10")
	)
	(via
		(at 27.4828 -166.57955)
		(size 0.7112)
		(drill 0.4064)
		(layers "F.Cu" "B.Cu")
		(net "FANIN_10")
	)
	(via
		(at 27.0256 -164.6682)
		(size 0.7112)
		(drill 0.3556)
		(layers "F.Cu" "B.Cu")
		(net "FANIN_10")
	)
	(segment
		(start 27.051 -164.6682)
		(end 27.0256 -164.6682)
		(width 0.1397)
		(layer "B.Cu")
		(net "FANIN_10")
	)
	(segment
		(start 17.8562 -155.2448)
		(end 27.0256 -164.4142)
		(width 0.1397)
		(layer "B.Cu")
		(net "FANIN_10")
	)
	(segment
		(start 17.8562 -151.4094)
		(end 17.8562 -155.2448)
		(width 0.1397)
		(layer "B.Cu")
		(net "FANIN_10")
	)
	(segment
		(start 27.4828 -166.57955)
		(end 27.4828 -165.1)
		(width 0.1397)
		(layer "B.Cu")
		(net "FANIN_10")
	)
	(segment
		(start 27.4828 -165.1)
		(end 27.051 -164.6682)
		(width 0.1397)
		(layer "B.Cu")
		(net "FANIN_10")
	)
	(segment
		(start 14.4272 -147.9804)
		(end 17.8562 -151.4094)
		(width 0.1397)
		(layer "B.Cu")
		(net "FANIN_10")
	)
	(segment
		(start 14.4272 -146.5453)
		(end 14.4272 -147.9804)
		(width 0.1397)
		(layer "B.Cu")
		(net "FANIN_10")
	)
	(segment
		(start 27.0256 -164.4142)
		(end 27.0256 -164.6682)
		(width 0.1397)
		(layer "B.Cu")
		(net "FANIN_10")
	)
	(segment
		(start 18.7198 -150.114)
		(end 19.9009 -150.114)
		(width 0.1397)
		(layer "F.Cu")
		(net "FANIN_9")
	)
	(segment
		(start 28.6512 -165.753542)
		(end 29.11221 -165.292532)
		(width 0.1397)
		(layer "F.Cu")
		(net "FANIN_9")
	)
	(segment
		(start 29.11221 -165.292532)
		(end 29.11221 -164.091366)
		(width 0.1397)
		(layer "F.Cu")
		(net "FANIN_9")
	)
	(segment
		(start 19.9009 -150.114)
		(end 19.9136 -150.1267)
		(width 0.1397)
		(layer "F.Cu")
		(net "FANIN_9")
	)
	(segment
		(start 18.5166 -151.4602)
		(end 19.558 -151.4602)
		(width 0.1397)
		(layer "F.Cu")
		(net "FANIN_9")
	)
	(segment
		(start 28.6512 -165.989)
		(end 28.6512 -165.753542)
		(width 0.1397)
		(layer "F.Cu")
		(net "FANIN_9")
	)
	(segment
		(start 18.415 -151.3586)
		(end 18.5166 -151.4602)
		(width 0.1397)
		(layer "F.Cu")
		(net "FANIN_9")
	)
	(segment
		(start 19.558 -151.4602)
		(end 19.9136 -151.1046)
		(width 0.1397)
		(layer "F.Cu")
		(net "FANIN_9")
	)
	(segment
		(start 19.9136 -151.1046)
		(end 19.9136 -150.1267)
		(width 0.1397)
		(layer "F.Cu")
		(net "FANIN_9")
	)
	(via
		(at 21.0566 -157.6324)
		(size 0.7112)
		(drill 0.3556)
		(layers "F.Cu" "B.Cu")
		(net "FANIN_9")
	)
	(via
		(at 28.6512 -165.989)
		(size 0.7112)
		(drill 0.4064)
		(layers "F.Cu" "B.Cu")
		(net "FANIN_9")
	)
	(via
		(at 18.415 -151.3586)
		(size 0.7112)
		(drill 0.4064)
		(layers "F.Cu" "B.Cu")
		(net "FANIN_9")
	)
	(segment
		(start 21.0566 -157.6324)
		(end 20.9296 -157.6324)
		(width 0.1397)
		(layer "B.Cu")
		(net "FANIN_9")
	)
	(segment
		(start 20.9296 -157.6324)
		(end 18.5928 -155.2956)
		(width 0.1397)
		(layer "B.Cu")
		(net "FANIN_9")
	)
	(segment
		(start 28.6512 -165.989)
		(end 28.6512 -165.2524)
		(width 0.1397)
		(layer "B.Cu")
		(net "FANIN_9")
	)
	(segment
		(start 28.6512 -165.2524)
		(end 21.0566 -157.6578)
		(width 0.1397)
		(layer "B.Cu")
		(net "FANIN_9")
	)
	(segment
		(start 21.0566 -157.6578)
		(end 21.0566 -157.6324)
		(width 0.1397)
		(layer "B.Cu")
		(net "FANIN_9")
	)
	(segment
		(start 18.5928 -155.2956)
		(end 18.5928 -151.5364)
		(width 0.1397)
		(layer "B.Cu")
		(net "FANIN_9")
	)
	(segment
		(start 18.5928 -151.5364)
		(end 18.415 -151.3586)
		(width 0.1397)
		(layer "B.Cu")
		(net "FANIN_9")
	)
	(segment
		(start 43.52798 -164.043106)
		(end 43.52798 -165.14318)
		(width 0.1397)
		(layer "F.Cu")
		(net "OSC_TRI_S")
	)
	(segment
		(start 45.81271 -164.038534)
		(end 45.81271 -164.24529)
		(width 0.1397)
		(layer "F.Cu")
		(net "OSC_TRI_S")
	)
	(segment
		(start 45.81271 -164.24529)
		(end 44.2214 -165.8366)
		(width 0.1397)
		(layer "F.Cu")
		(net "OSC_TRI_S")
	)
	(segment
		(start 43.52798 -165.14318)
		(end 44.2214 -165.8366)
		(width 0.1397)
		(layer "F.Cu")
		(net "OSC_TRI_S")
	)
	(via
		(at 44.2214 -165.8366)
		(size 0.7112)
		(drill 0.3556)
		(layers "F.Cu" "B.Cu")
		(net "OSC_TRI_S")
	)
	(segment
		(start 12.680696 -38.928294)
		(end 12.836906 -38.928294)
		(width 0.1397)
		(layer "F.Cu")
		(net "PWM_EXP_2B")
	)
	(segment
		(start 12.836906 -38.928294)
		(end 14.80185 -36.96335)
		(width 0.1397)
		(layer "F.Cu")
		(net "PWM_EXP_2B")
	)
	(segment
		(start 23.674324 -170.826176)
		(end 24.0665 -170.434)
		(width 0.1397)
		(layer "F.Cu")
		(net "PWM_EXP_2B")
	)
	(segment
		(start 24.1681 -170.3324)
		(end 24.0665 -170.434)
		(width 0.1397)
		(layer "F.Cu")
		(net "PWM_EXP_2B")
	)
	(segment
		(start 14.80185 -36.96335)
		(end 16.408654 -36.96335)
		(width 0.1397)
		(layer "F.Cu")
		(net "PWM_EXP_2B")
	)
	(segment
		(start 23.674324 -172.06341)
		(end 23.674324 -170.826176)
		(width 0.1397)
		(layer "F.Cu")
		(net "PWM_EXP_2B")
	)
	(segment
		(start 25.5524 -170.3324)
		(end 24.1681 -170.3324)
		(width 0.1397)
		(layer "F.Cu")
		(net "PWM_EXP_2B")
	)
	(segment
		(start 16.408654 -36.96335)
		(end 18.891504 -39.4462)
		(width 0.1397)
		(layer "F.Cu")
		(net "PWM_EXP_2B")
	)
	(segment
		(start 18.891504 -39.4462)
		(end 19.1262 -39.4462)
		(width 0.1397)
		(layer "F.Cu")
		(net "PWM_EXP_2B")
	)
	(via
		(at 25.5524 -166.7764)
		(size 0.7112)
		(drill 0.3556)
		(layers "F.Cu" "B.Cu")
		(net "PWM_EXP_2B")
	)
	(via
		(at 19.1262 -39.4462)
		(size 0.5588)
		(drill 0.3048)
		(layers "F.Cu" "B.Cu")
		(net "PWM_EXP_2B")
	)
	(via
		(at 12.680696 -38.928294)
		(size 0.5588)
		(drill 0.3048)
		(layers "F.Cu" "B.Cu")
		(net "PWM_EXP_2B")
	)
	(via
		(at 25.5524 -170.3324)
		(size 0.7112)
		(drill 0.4064)
		(layers "F.Cu" "B.Cu")
		(net "PWM_EXP_2B")
	)
	(segment
		(start 12.680696 -42.259504)
		(end 12.1412 -42.799)
		(width 0.1397)
		(layer "B.Cu")
		(net "PWM_EXP_2B")
	)
	(segment
		(start 37.999924 -51.919886)
		(end 36.502086 -51.919886)
		(width 0.1397)
		(layer "B.Cu")
		(net "PWM_EXP_2B")
	)
	(segment
		(start 21.4376 -43.359578)
		(end 21.4376 -43.295062)
		(width 0.1397)
		(layer "B.Cu")
		(net "PWM_EXP_2B")
	)
	(segment
		(start 12.1412 -42.799)
		(end 12.1412 -46.6852)
		(width 0.1397)
		(layer "B.Cu")
		(net "PWM_EXP_2B")
	)
	(segment
		(start 12.1412 -46.6852)
		(end 11.01725 -47.80915)
		(width 0.1397)
		(layer "B.Cu")
		(net "PWM_EXP_2B")
	)
	(segment
		(start 8.800592 -109.8169)
		(end 8.800592 -112.0267)
		(width 0.1397)
		(layer "B.Cu")
		(net "PWM_EXP_2B")
	)
	(segment
		(start 8.800846 -112.229646)
		(end 10.070084 -113.498884)
		(width 0.1397)
		(layer "B.Cu")
		(net "PWM_EXP_2B")
	)
	(segment
		(start 25.5524 -166.7764)
		(end 26.035 -167.259)
		(width 0.1397)
		(layer "B.Cu")
		(net "PWM_EXP_2B")
	)
	(segment
		(start 8.8265 -124.428758)
		(end 8.8265 -133.4897)
		(width 0.1397)
		(layer "B.Cu")
		(net "PWM_EXP_2B")
	)
	(segment
		(start 19.1262 -41.048178)
		(end 19.1262 -39.4462)
		(width 0.1397)
		(layer "B.Cu")
		(net "PWM_EXP_2B")
	)
	(segment
		(start 9.8552 -63.14313)
		(end 9.8552 -67.2846)
		(width 0.1397)
		(layer "B.Cu")
		(net "PWM_EXP_2B")
	)
	(segment
		(start 12.03833 -60.96)
		(end 9.8552 -63.14313)
		(width 0.1397)
		(layer "B.Cu")
		(net "PWM_EXP_2B")
	)
	(segment
		(start 9.2456 -67.8942)
		(end 9.2456 -91.44)
		(width 0.1397)
		(layer "B.Cu")
		(net "PWM_EXP_2B")
	)
	(segment
		(start 8.825992 -124.060204)
		(end 8.826246 -124.060458)
		(width 0.1397)
		(layer "B.Cu")
		(net "PWM_EXP_2B")
	)
	(segment
		(start 11.01725 -47.80915)
		(end 11.01725 -51.78425)
		(width 0.1397)
		(layer "B.Cu")
		(net "PWM_EXP_2B")
	)
	(segment
		(start 9.8552 -67.2846)
		(end 9.2456 -67.8942)
		(width 0.1397)
		(layer "B.Cu")
		(net "PWM_EXP_2B")
	)
	(segment
		(start 11.8999 -136.5631)
		(end 11.8999 -146.0881)
		(width 0.1397)
		(layer "B.Cu")
		(net "PWM_EXP_2B")
	)
	(segment
		(start 20.881594 -42.739056)
		(end 20.817078 -42.739056)
		(width 0.1397)
		(layer "B.Cu")
		(net "PWM_EXP_2B")
	)
	(segment
		(start 8.8265 -133.4897)
		(end 11.8999 -136.5631)
		(width 0.1397)
		(layer "B.Cu")
		(net "PWM_EXP_2B")
	)
	(segment
		(start 25.5524 -163.6014)
		(end 25.5524 -166.7764)
		(width 0.1397)
		(layer "B.Cu")
		(net "PWM_EXP_2B")
	)
	(segment
		(start 29.2862 -44.704)
		(end 22.782022 -44.704)
		(width 0.1397)
		(layer "B.Cu")
		(net "PWM_EXP_2B")
	)
	(segment
		(start 26.035 -167.259)
		(end 26.035 -169.8498)
		(width 0.1397)
		(layer "B.Cu")
		(net "PWM_EXP_2B")
	)
	(segment
		(start 10.070084 -113.498884)
		(end 10.070084 -122.079512)
		(width 0.1397)
		(layer "B.Cu")
		(net "PWM_EXP_2B")
	)
	(segment
		(start 8.800592 -112.0267)
		(end 8.800846 -112.026954)
		(width 0.1397)
		(layer "B.Cu")
		(net "PWM_EXP_2B")
	)
	(segment
		(start 22.782022 -44.704)
		(end 21.4376 -43.359578)
		(width 0.1397)
		(layer "B.Cu")
		(net "PWM_EXP_2B")
	)
	(segment
		(start 8.825992 -123.323604)
		(end 8.825992 -124.060204)
		(width 0.1397)
		(layer "B.Cu")
		(net "PWM_EXP_2B")
	)
	(segment
		(start 8.800846 -109.816646)
		(end 8.800592 -109.8169)
		(width 0.1397)
		(layer "B.Cu")
		(net "PWM_EXP_2B")
	)
	(segment
		(start 17.3736 -151.5618)
		(end 17.3736 -155.4226)
		(width 0.1397)
		(layer "B.Cu")
		(net "PWM_EXP_2B")
	)
	(segment
		(start 12.03833 -52.80533)
		(end 12.03833 -60.96)
		(width 0.1397)
		(layer "B.Cu")
		(net "PWM_EXP_2B")
	)
	(segment
		(start 8.800846 -91.884754)
		(end 8.800846 -109.816646)
		(width 0.1397)
		(layer "B.Cu")
		(net "PWM_EXP_2B")
	)
	(segment
		(start 8.826246 -124.060458)
		(end 8.826246 -124.428504)
		(width 0.1397)
		(layer "B.Cu")
		(net "PWM_EXP_2B")
	)
	(segment
		(start 21.4376 -43.295062)
		(end 20.881594 -42.739056)
		(width 0.1397)
		(layer "B.Cu")
		(net "PWM_EXP_2B")
	)
	(segment
		(start 9.2456 -91.44)
		(end 8.800846 -91.884754)
		(width 0.1397)
		(layer "B.Cu")
		(net "PWM_EXP_2B")
	)
	(segment
		(start 10.070084 -122.079512)
		(end 8.825992 -123.323604)
		(width 0.1397)
		(layer "B.Cu")
		(net "PWM_EXP_2B")
	)
	(segment
		(start 11.01725 -51.78425)
		(end 12.03833 -52.80533)
		(width 0.1397)
		(layer "B.Cu")
		(net "PWM_EXP_2B")
	)
	(segment
		(start 8.826246 -124.428504)
		(end 8.8265 -124.428758)
		(width 0.1397)
		(layer "B.Cu")
		(net "PWM_EXP_2B")
	)
	(segment
		(start 26.035 -169.8498)
		(end 25.5524 -170.3324)
		(width 0.1397)
		(layer "B.Cu")
		(net "PWM_EXP_2B")
	)
	(segment
		(start 17.3736 -155.4226)
		(end 25.5524 -163.6014)
		(width 0.1397)
		(layer "B.Cu")
		(net "PWM_EXP_2B")
	)
	(segment
		(start 20.817078 -42.739056)
		(end 19.1262 -41.048178)
		(width 0.1397)
		(layer "B.Cu")
		(net "PWM_EXP_2B")
	)
	(segment
		(start 11.8999 -146.0881)
		(end 17.3736 -151.5618)
		(width 0.1397)
		(layer "B.Cu")
		(net "PWM_EXP_2B")
	)
	(segment
		(start 12.680696 -38.928294)
		(end 12.680696 -42.259504)
		(width 0.1397)
		(layer "B.Cu")
		(net "PWM_EXP_2B")
	)
	(segment
		(start 36.502086 -51.919886)
		(end 29.2862 -44.704)
		(width 0.1397)
		(layer "B.Cu")
		(net "PWM_EXP_2B")
	)
	(segment
		(start 8.800846 -112.026954)
		(end 8.800846 -112.229646)
		(width 0.1397)
		(layer "B.Cu")
		(net "PWM_EXP_2B")
	)
	(segment
		(start 31.645352 -175.475138)
		(end 31.980124 -175.80991)
		(width 0.1397)
		(layer "F.Cu")
		(net "PWM_EXP_2A")
	)
	(segment
		(start 30.658308 -175.475138)
		(end 31.645352 -175.475138)
		(width 0.1397)
		(layer "F.Cu")
		(net "PWM_EXP_2A")
	)
	(segment
		(start 30.260036 -175.87341)
		(end 30.658308 -175.475138)
		(width 0.1397)
		(layer "F.Cu")
		(net "PWM_EXP_2A")
	)
	(segment
		(start 28.779724 -175.87341)
		(end 30.260036 -175.87341)
		(width 0.1397)
		(layer "F.Cu")
		(net "PWM_EXP_2A")
	)
	(via
		(at 30.658308 -175.475138)
		(size 0.7112)
		(drill 0.4064)
		(layers "F.Cu" "B.Cu")
		(net "PWM_EXP_2A")
	)
	(segment
		(start 21.420836 -62.461394)
		(end 21.420836 -62.396878)
		(width 0.1397)
		(layer "B.Cu")
		(net "PWM_EXP_2A")
	)
	(segment
		(start 22.908514 -60.9092)
		(end 35.3822 -60.9092)
		(width 0.1397)
		(layer "B.Cu")
		(net "PWM_EXP_2A")
	)
	(segment
		(start 13.16355 -72.1614)
		(end 13.16355 -68.90385)
		(width 0.1397)
		(layer "B.Cu")
		(net "PWM_EXP_2A")
	)
	(segment
		(start 12.172696 -92.99575)
		(end 12.17295 -92.99575)
		(width 0.1397)
		(layer "B.Cu")
		(net "PWM_EXP_2A")
	)
	(segment
		(start 15.4559 -124.51715)
		(end 13.1953 -122.25655)
		(width 0.1397)
		(layer "B.Cu")
		(net "PWM_EXP_2A")
	)
	(segment
		(start 31.41345 -174.719996)
		(end 31.41345 -169.11955)
		(width 0.1397)
		(layer "B.Cu")
		(net "PWM_EXP_2A")
	)
	(segment
		(start 22.02307 -150.87473)
		(end 22.57425 -150.32355)
		(width 0.1397)
		(layer "B.Cu")
		(net "PWM_EXP_2A")
	)
	(segment
		(start 20.116292 -62.99835)
		(end 20.118578 -63.000636)
		(width 0.1397)
		(layer "B.Cu")
		(net "PWM_EXP_2A")
	)
	(segment
		(start 20.8534 -148.195792)
		(end 20.8534 -146.2532)
		(width 0.1397)
		(layer "B.Cu")
		(net "PWM_EXP_2A")
	)
	(segment
		(start 12.17295 -92.99575)
		(end 12.3698 -92.7989)
		(width 0.1397)
		(layer "B.Cu")
		(net "PWM_EXP_2A")
	)
	(segment
		(start 12.3698 -92.7989)
		(end 12.3698 -72.95515)
		(width 0.1397)
		(layer "B.Cu")
		(net "PWM_EXP_2A")
	)
	(segment
		(start 35.3822 -60.9092)
		(end 35.7886 -60.5028)
		(width 0.1397)
		(layer "B.Cu")
		(net "PWM_EXP_2A")
	)
	(segment
		(start 39.57701 -60.5028)
		(end 40.539924 -59.539886)
		(width 0.1397)
		(layer "B.Cu")
		(net "PWM_EXP_2A")
	)
	(segment
		(start 11.9126 -110.369096)
		(end 11.9126 -93.255846)
		(width 0.1397)
		(layer "B.Cu")
		(net "PWM_EXP_2A")
	)
	(segment
		(start 22.57425 -150.32355)
		(end 22.57425 -149.916642)
		(width 0.1397)
		(layer "B.Cu")
		(net "PWM_EXP_2A")
	)
	(segment
		(start 20.8534 -146.2532)
		(end 15.4559 -140.8557)
		(width 0.1397)
		(layer "B.Cu")
		(net "PWM_EXP_2A")
	)
	(segment
		(start 17.17675 -64.89065)
		(end 17.17675 -63.493396)
		(width 0.1397)
		(layer "B.Cu")
		(net "PWM_EXP_2A")
	)
	(segment
		(start 22.02307 -153.746962)
		(end 22.02307 -150.87473)
		(width 0.1397)
		(layer "B.Cu")
		(net "PWM_EXP_2A")
	)
	(segment
		(start 20.118578 -63.000636)
		(end 20.881594 -63.000636)
		(width 0.1397)
		(layer "B.Cu")
		(net "PWM_EXP_2A")
	)
	(segment
		(start 22.57425 -149.916642)
		(end 20.8534 -148.195792)
		(width 0.1397)
		(layer "B.Cu")
		(net "PWM_EXP_2A")
	)
	(segment
		(start 11.912346 -110.73765)
		(end 11.912346 -110.36935)
		(width 0.1397)
		(layer "B.Cu")
		(net "PWM_EXP_2A")
	)
	(segment
		(start 20.881594 -63.000636)
		(end 21.420836 -62.461394)
		(width 0.1397)
		(layer "B.Cu")
		(net "PWM_EXP_2A")
	)
	(segment
		(start 12.3698 -72.95515)
		(end 13.16355 -72.1614)
		(width 0.1397)
		(layer "B.Cu")
		(net "PWM_EXP_2A")
	)
	(segment
		(start 33.36925 -165.093142)
		(end 22.02307 -153.746962)
		(width 0.1397)
		(layer "B.Cu")
		(net "PWM_EXP_2A")
	)
	(segment
		(start 11.912346 -110.36935)
		(end 11.9126 -110.369096)
		(width 0.1397)
		(layer "B.Cu")
		(net "PWM_EXP_2A")
	)
	(segment
		(start 17.671796 -62.99835)
		(end 20.116292 -62.99835)
		(width 0.1397)
		(layer "B.Cu")
		(net "PWM_EXP_2A")
	)
	(segment
		(start 15.4559 -140.8557)
		(end 15.4559 -124.51715)
		(width 0.1397)
		(layer "B.Cu")
		(net "PWM_EXP_2A")
	)
	(segment
		(start 35.7886 -60.5028)
		(end 39.57701 -60.5028)
		(width 0.1397)
		(layer "B.Cu")
		(net "PWM_EXP_2A")
	)
	(segment
		(start 21.420836 -62.396878)
		(end 22.908514 -60.9092)
		(width 0.1397)
		(layer "B.Cu")
		(net "PWM_EXP_2A")
	)
	(segment
		(start 31.41345 -169.11955)
		(end 33.36925 -167.16375)
		(width 0.1397)
		(layer "B.Cu")
		(net "PWM_EXP_2A")
	)
	(segment
		(start 11.9126 -93.255846)
		(end 12.172696 -92.99575)
		(width 0.1397)
		(layer "B.Cu")
		(net "PWM_EXP_2A")
	)
	(segment
		(start 33.36925 -167.16375)
		(end 33.36925 -165.093142)
		(width 0.1397)
		(layer "B.Cu")
		(net "PWM_EXP_2A")
	)
	(segment
		(start 13.1953 -122.25655)
		(end 13.1953 -112.020604)
		(width 0.1397)
		(layer "B.Cu")
		(net "PWM_EXP_2A")
	)
	(segment
		(start 13.16355 -68.90385)
		(end 17.17675 -64.89065)
		(width 0.1397)
		(layer "B.Cu")
		(net "PWM_EXP_2A")
	)
	(segment
		(start 17.17675 -63.493396)
		(end 17.671796 -62.99835)
		(width 0.1397)
		(layer "B.Cu")
		(net "PWM_EXP_2A")
	)
	(segment
		(start 13.1953 -112.020604)
		(end 11.912346 -110.73765)
		(width 0.1397)
		(layer "B.Cu")
		(net "PWM_EXP_2A")
	)
	(segment
		(start 30.658308 -175.475138)
		(end 31.41345 -174.719996)
		(width 0.1397)
		(layer "B.Cu")
		(net "PWM_EXP_2A")
	)
	(segment
		(start 21.3233 -216.637616)
		(end 21.322284 -216.6366)
		(width 0.508)
		(layer "F.Cu")
		(net "P3V3")
	)
	(segment
		(start 45.83811 -163.124134)
		(end 45.81271 -163.149534)
		(width 0.508)
		(layer "F.Cu")
		(net "P3V3")
	)
	(segment
		(start 7.3406 -69.1642)
		(end 6.7183 -69.7865)
		(width 0.508)
		(layer "F.Cu")
		(net "P3V3")
	)
	(segment
		(start 10.922 -177.8)
		(end 9.939274 -176.817274)
		(width 0.4064)
		(layer "F.Cu")
		(net "P3V3")
	)
	(segment
		(start 23.6855 -169.5958)
		(end 24.1808 -169.1005)
		(width 0.508)
		(layer "F.Cu")
		(net "P3V3")
	)
	(segment
		(start 46.6598 -160.8582)
		(end 46.6598 -156.213556)
		(width 0.508)
		(layer "F.Cu")
		(net "P3V3")
	)
	(segment
		(start 24.765 -145.291048)
		(end 24.765 -147.7518)
		(width 0.508)
		(layer "F.Cu")
		(net "P3V3")
	)
	(segment
		(start 33.2232 -249.3264)
		(end 34.85896 -249.3264)
		(width 0.3048)
		(layer "F.Cu")
		(net "P3V3")
	)
	(segment
		(start 42.672 -248.285)
		(end 42.672 -252.73)
		(width 0.508)
		(layer "F.Cu")
		(net "P3V3")
	)
	(segment
		(start 14.052042 -177.8)
		(end 10.922 -177.8)
		(width 0.4064)
		(layer "F.Cu")
		(net "P3V3")
	)
	(segment
		(start 14.5796 -171.9199)
		(end 15.5956 -171.9199)
		(width 0.508)
		(layer "F.Cu")
		(net "P3V3")
	)
	(segment
		(start 30.904434 -237.821724)
		(end 32.385 -237.821724)
		(width 0.508)
		(layer "F.Cu")
		(net "P3V3")
	)
	(segment
		(start 34.6964 -147.7772)
		(end 34.6964 -145.846292)
		(width 0.508)
		(layer "F.Cu")
		(net "P3V3")
	)
	(segment
		(start 27.2542 -250.444)
		(end 27.2542 -251.6632)
		(width 0.508)
		(layer "F.Cu")
		(net "P3V3")
	)
	(segment
		(start 28.448 -251.6632)
		(end 28.94584 -251.16536)
		(width 0.3556)
		(layer "F.Cu")
		(net "P3V3")
	)
	(segment
		(start 7.4422 -174.0154)
		(end 9.2456 -172.212)
		(width 0.508)
		(layer "F.Cu")
		(net "P3V3")
	)
	(segment
		(start 28.540456 -248.751344)
		(end 27.2542 -250.0376)
		(width 0.508)
		(layer "F.Cu")
		(net "P3V3")
	)
	(segment
		(start 14.651736 -177.200306)
		(end 14.052042 -177.8)
		(width 0.4064)
		(layer "F.Cu")
		(net "P3V3")
	)
	(segment
		(start 15.9004 -61.9125)
		(end 16.1544 -61.6585)
		(width 0.508)
		(layer "F.Cu")
		(net "P3V3")
	)
	(segment
		(start 18.269966 -175.133)
		(end 17.91589 -174.778924)
		(width 0.508)
		(layer "F.Cu")
		(net "P3V3")
	)
	(segment
		(start 15.935706 -177.200306)
		(end 14.651736 -177.200306)
		(width 0.508)
		(layer "F.Cu")
		(net "P3V3")
	)
	(segment
		(start 37.5412 -254.8255)
		(end 37.5666 -254.8001)
		(width 0.508)
		(layer "F.Cu")
		(net "P3V3")
	)
	(segment
		(start 26.802334 -143.253714)
		(end 24.765 -145.291048)
		(width 0.508)
		(layer "F.Cu")
		(net "P3V3")
	)
	(segment
		(start 21.3233 -218.821)
		(end 21.3233 -217.7288)
		(width 0.508)
		(layer "F.Cu")
		(net "P3V3")
	)
	(segment
		(start 17.0688 -179.1208)
		(end 17.0942 -179.0954)
		(width 0.508)
		(layer "F.Cu")
		(net "P3V3")
	)
	(segment
		(start 34.85896 -249.3264)
		(end 34.88436 -249.3518)
		(width 0.3048)
		(layer "F.Cu")
		(net "P3V3")
	)
	(segment
		(start 6.1214 -174.0154)
		(end 7.3406 -174.0154)
		(width 0.508)
		(layer "F.Cu")
		(net "P3V3")
	)
	(segment
		(start 14.7955 -175.40224)
		(end 14.7955 -177.056542)
		(width 0.4064)
		(layer "F.Cu")
		(net "P3V3")
	)
	(segment
		(start 32.131 -247.396)
		(end 32.131 -248.296684)
		(width 0.508)
		(layer "F.Cu")
		(net "P3V3")
	)
	(segment
		(start 19.882612 -173.9392)
		(end 19.831812 -173.8884)
		(width 0.508)
		(layer "F.Cu")
		(net "P3V3")
	)
	(segment
		(start 19.583654 -236.702346)
		(end 10.414 -236.702346)
		(width 1.016)
		(layer "F.Cu")
		(net "P3V3")
	)
	(segment
		(start 27.1018 -170.4594)
		(end 26.2382 -169.5958)
		(width 0.508)
		(layer "F.Cu")
		(net "P3V3")
	)
	(segment
		(start 43.566588 -161.282634)
		(end 43.52798 -161.244026)
		(width 0.508)
		(layer "F.Cu")
		(net "P3V3")
	)
	(segment
		(start 15.9512 -60.071)
		(end 16.2306 -60.071)
		(width 0.508)
		(layer "F.Cu")
		(net "P3V3")
	)
	(segment
		(start 36.5252 -254.8255)
		(end 37.5412 -254.8255)
		(width 0.508)
		(layer "F.Cu")
		(net "P3V3")
	)
	(segment
		(start 9.9822 -280.8732)
		(end 9.9314 -280.924)
		(width 0.508)
		(layer "F.Cu")
		(net "P3V3")
	)
	(segment
		(start 22.352 -169.5958)
		(end 23.6855 -169.5958)
		(width 0.508)
		(layer "F.Cu")
		(net "P3V3")
	)
	(segment
		(start 32.5628 -248.666)
		(end 31.761684 -248.666)
		(width 0.508)
		(layer "F.Cu")
		(net "P3V3")
	)
	(segment
		(start 25.8572 -234.0102)
		(end 22.2758 -234.0102)
		(width 1.016)
		(layer "F.Cu")
		(net "P3V3")
	)
	(segment
		(start 42.672 -241.554)
		(end 42.672 -248.285)
		(width 0.508)
		(layer "F.Cu")
		(net "P3V3")
	)
	(segment
		(start 19.714718 -175.152304)
		(end 19.17065 -175.152304)
		(width 0.508)
		(layer "F.Cu")
		(net "P3V3")
	)
	(segment
		(start 45.83811 -161.282634)
		(end 43.566588 -161.282634)
		(width 0.508)
		(layer "F.Cu")
		(net "P3V3")
	)
	(segment
		(start 20.4851 -174.3456)
		(end 20.0787 -173.9392)
		(width 0.508)
		(layer "F.Cu")
		(net "P3V3")
	)
	(segment
		(start 40.26789 -151.39289)
		(end 39.1922 -150.3172)
		(width 0.508)
		(layer "F.Cu")
		(net "P3V3")
	)
	(segment
		(start 19.831812 -173.8884)
		(end 19.7104 -173.8884)
		(width 0.508)
		(layer "F.Cu")
		(net "P3V3")
	)
	(segment
		(start 9.939274 -176.242726)
		(end 10.77976 -175.40224)
		(width 0.4064)
		(layer "F.Cu")
		(net "P3V3")
	)
	(segment
		(start 42.672 -248.285)
		(end 41.148508 -246.761508)
		(width 0.508)
		(layer "F.Cu")
		(net "P3V3")
	)
	(segment
		(start 16.2306 -60.071)
		(end 16.51 -59.7916)
		(width 0.508)
		(layer "F.Cu")
		(net "P3V3")
	)
	(segment
		(start 19.940524 -175.37811)
		(end 19.714718 -175.152304)
		(width 0.508)
		(layer "F.Cu")
		(net "P3V3")
	)
	(segment
		(start 6.5024 -81.6102)
		(end 6.477 -81.5848)
		(width 0.508)
		(layer "F.Cu")
		(net "P3V3")
	)
	(segment
		(start 19.304 -172.6438)
		(end 22.352 -169.5958)
		(width 0.508)
		(layer "F.Cu")
		(net "P3V3")
	)
	(segment
		(start 32.131 -248.296684)
		(end 31.761684 -248.666)
		(width 0.508)
		(layer "F.Cu")
		(net "P3V3")
	)
	(segment
		(start 31.761684 -248.666)
		(end 31.67634 -248.751344)
		(width 0.508)
		(layer "F.Cu")
		(net "P3V3")
	)
	(segment
		(start 15.9004 -62.4205)
		(end 15.9004 -61.9125)
		(width 0.508)
		(layer "F.Cu")
		(net "P3V3")
	)
	(segment
		(start 16.002 -68.0085)
		(end 17.2085 -68.0085)
		(width 0.508)
		(layer "F.Cu")
		(net "P3V3")
	)
	(segment
		(start 46.235366 -161.282634)
		(end 46.6598 -160.8582)
		(width 0.508)
		(layer "F.Cu")
		(net "P3V3")
	)
	(segment
		(start 23.63851 -148.87829)
		(end 23.63851 -150.881334)
		(width 0.508)
		(layer "F.Cu")
		(net "P3V3")
	)
	(segment
		(start 21.322284 -214.4014)
		(end 21.322284 -215.519)
		(width 0.508)
		(layer "F.Cu")
		(net "P3V3")
	)
	(segment
		(start 11.40714 -58.8772)
		(end 14.2875 -58.8772)
		(width 0.508)
		(layer "F.Cu")
		(net "P3V3")
	)
	(segment
		(start 14.5796 -171.9199)
		(end 14.5796 -172.816266)
		(width 0.508)
		(layer "F.Cu")
		(net "P3V3")
	)
	(segment
		(start 27.2542 -251.6632)
		(end 28.448 -251.6632)
		(width 0.508)
		(layer "F.Cu")
		(net "P3V3")
	)
	(segment
		(start 14.5796 -172.816266)
		(end 14.40434 -172.991526)
		(width 0.508)
		(layer "F.Cu")
		(net "P3V3")
	)
	(segment
		(start 32.78251 -172.439076)
		(end 34.659316 -172.439076)
		(width 0.508)
		(layer "F.Cu")
		(net "P3V3")
	)
	(segment
		(start 24.6761 -169.5958)
		(end 24.1808 -169.1005)
		(width 0.508)
		(layer "F.Cu")
		(net "P3V3")
	)
	(segment
		(start 41.529 -253.4285)
		(end 40.513 -253.4285)
		(width 0.508)
		(layer "F.Cu")
		(net "P3V3")
	)
	(segment
		(start 16.67129 -174.778924)
		(end 16.0274 -174.135034)
		(width 0.508)
		(layer "F.Cu")
		(net "P3V3")
	)
	(segment
		(start 26.543 -236.9058)
		(end 26.543 -234.696)
		(width 1.016)
		(layer "F.Cu")
		(net "P3V3")
	)
	(segment
		(start 33.2232 -250.3932)
		(end 32.9946 -250.6218)
		(width 0.254)
		(layer "F.Cu")
		(net "P3V3")
	)
	(segment
		(start 41.3385 -240.2205)
		(end 42.672 -241.554)
		(width 0.508)
		(layer "F.Cu")
		(net "P3V3")
	)
	(segment
		(start 36.480242 -168.178734)
		(end 34.99231 -168.178734)
		(width 0.508)
		(layer "F.Cu")
		(net "P3V3")
	)
	(segment
		(start 46.284134 -154.969972)
		(end 44.171362 -152.8572)
		(width 0.508)
		(layer "F.Cu")
		(net "P3V3")
	)
	(segment
		(start 33.351724 -236.855)
		(end 35.8902 -236.855)
		(width 0.508)
		(layer "F.Cu")
		(net "P3V3")
	)
	(segment
		(start 14.2875 -58.8772)
		(end 14.585696 -59.175396)
		(width 0.508)
		(layer "F.Cu")
		(net "P3V3")
	)
	(segment
		(start 36.933886 -168.678352)
		(end 36.933886 -168.632378)
		(width 0.508)
		(layer "F.Cu")
		(net "P3V3")
	)
	(segment
		(start 21.3233 -219.8878)
		(end 21.3233 -218.821)
		(width 0.508)
		(layer "F.Cu")
		(net "P3V3")
	)
	(segment
		(start 16.68145 -70.41515)
		(end 16.68145 -69.25945)
		(width 0.508)
		(layer "F.Cu")
		(net "P3V3")
	)
	(segment
		(start 15.494 -60.0837)
		(end 15.9385 -60.0837)
		(width 0.508)
		(layer "F.Cu")
		(net "P3V3")
	)
	(segment
		(start 39.878 -240.2205)
		(end 38.862 -240.2205)
		(width 0.508)
		(layer "F.Cu")
		(net "P3V3")
	)
	(segment
		(start 32.103822 -143.253714)
		(end 26.802334 -143.253714)
		(width 0.508)
		(layer "F.Cu")
		(net "P3V3")
	)
	(segment
		(start 8.3058 -65.2653)
		(end 7.1247 -65.2653)
		(width 0.508)
		(layer "F.Cu")
		(net "P3V3")
	)
	(segment
		(start 11.8491 -225.9076)
		(end 12.5984 -225.9076)
		(width 0.508)
		(layer "F.Cu")
		(net "P3V3")
	)
	(segment
		(start 20.4216 -235.8644)
		(end 20.4216 -235.868464)
		(width 1.016)
		(layer "F.Cu")
		(net "P3V3")
	)
	(segment
		(start 37.5666 -254.8001)
		(end 38.608 -254.8001)
		(width 0.508)
		(layer "F.Cu")
		(net "P3V3")
	)
	(segment
		(start 36.83 -237.7948)
		(end 36.83 -240.2205)
		(width 0.508)
		(layer "F.Cu")
		(net "P3V3")
	)
	(segment
		(start 39.1922 -150.3172)
		(end 37.2364 -150.3172)
		(width 0.508)
		(layer "F.Cu")
		(net "P3V3")
	)
	(segment
		(start 11.0236 -226.7331)
		(end 11.8491 -225.9076)
		(width 0.508)
		(layer "F.Cu")
		(net "P3V3")
	)
	(segment
		(start 8.3185 -69.1642)
		(end 7.3406 -69.1642)
		(width 0.508)
		(layer "F.Cu")
		(net "P3V3")
	)
	(segment
		(start 15.5956 -172.339)
		(end 15.5956 -171.9199)
		(width 0.508)
		(layer "F.Cu")
		(net "P3V3")
	)
	(segment
		(start 15.3289 -71.12)
		(end 15.9766 -71.12)
		(width 0.508)
		(layer "F.Cu")
		(net "P3V3")
	)
	(segment
		(start 21.3233 -219.8878)
		(end 21.3233 -220.752416)
		(width 0.508)
		(layer "F.Cu")
		(net "P3V3")
	)
	(segment
		(start 14.7955 -177.056542)
		(end 14.651736 -177.200306)
		(width 0.4064)
		(layer "F.Cu")
		(net "P3V3")
	)
	(segment
		(start 37.846 -240.2205)
		(end 36.83 -240.2205)
		(width 0.508)
		(layer "F.Cu")
		(net "P3V3")
	)
	(segment
		(start 14.605 -214.503)
		(end 14.7066 -214.4014)
		(width 0.508)
		(layer "F.Cu")
		(net "P3V3")
	)
	(segment
		(start 19.17065 -175.152304)
		(end 19.151346 -175.133)
		(width 0.508)
		(layer "F.Cu")
		(net "P3V3")
	)
	(segment
		(start 44.171362 -152.8572)
		(end 40.795956 -152.8572)
		(width 0.508)
		(layer "F.Cu")
		(net "P3V3")
	)
	(segment
		(start 19.841464 -236.4486)
		(end 19.8374 -236.4486)
		(width 1.016)
		(layer "F.Cu")
		(net "P3V3")
	)
	(segment
		(start 35.8902 -236.855)
		(end 36.83 -237.7948)
		(width 0.508)
		(layer "F.Cu")
		(net "P3V3")
	)
	(segment
		(start 17.9324 -63.627)
		(end 17.9324 -62.7634)
		(width 0.508)
		(layer "F.Cu")
		(net "P3V3")
	)
	(segment
		(start 16.002 -68.58)
		(end 16.002 -68.0085)
		(width 0.508)
		(layer "F.Cu")
		(net "P3V3")
	)
	(segment
		(start 17.2085 -68.0085)
		(end 17.272 -68.072)
		(width 0.508)
		(layer "F.Cu")
		(net "P3V3")
	)
	(segment
		(start 34.6964 -145.846292)
		(end 32.103822 -143.253714)
		(width 0.508)
		(layer "F.Cu")
		(net "P3V3")
	)
	(segment
		(start 32.765492 -246.761508)
		(end 32.131 -247.396)
		(width 0.508)
		(layer "F.Cu")
		(net "P3V3")
	)
	(segment
		(start 39.878 -240.2205)
		(end 41.3385 -240.2205)
		(width 0.508)
		(layer "F.Cu")
		(net "P3V3")
	)
	(segment
		(start 21.3233 -220.752416)
		(end 22.225 -221.654116)
		(width 0.508)
		(layer "F.Cu")
		(net "P3V3")
	)
	(segment
		(start 16.68145 -69.25945)
		(end 16.002 -68.58)
		(width 0.508)
		(layer "F.Cu")
		(net "P3V3")
	)
	(segment
		(start 16.98625 -173.000924)
		(end 16.98625 -174.463964)
		(width 0.3048)
		(layer "F.Cu")
		(net "P3V3")
	)
	(segment
		(start 17.0942 -179.0954)
		(end 17.0942 -178.3588)
		(width 0.508)
		(layer "F.Cu")
		(net "P3V3")
	)
	(segment
		(start 32.385 -237.821724)
		(end 33.351724 -236.855)
		(width 0.508)
		(layer "F.Cu")
		(net "P3V3")
	)
	(segment
		(start 10.77976 -175.40224)
		(end 10.8585 -175.40224)
		(width 0.4064)
		(layer "F.Cu")
		(net "P3V3")
	)
	(segment
		(start 19.8374 -236.4486)
		(end 19.583654 -236.702346)
		(width 1.016)
		(layer "F.Cu")
		(net "P3V3")
	)
	(segment
		(start 39.116 -254.8255)
		(end 40.513 -253.4285)
		(width 0.508)
		(layer "F.Cu")
		(net "P3V3")
	)
	(segment
		(start 7.3406 -174.0154)
		(end 7.4422 -174.0154)
		(width 0.508)
		(layer "F.Cu")
		(net "P3V3")
	)
	(segment
		(start 31.67634 -248.751344)
		(end 28.540456 -248.751344)
		(width 0.508)
		(layer "F.Cu")
		(net "P3V3")
	)
	(segment
		(start 45.83811 -161.282634)
		(end 46.235366 -161.282634)
		(width 0.508)
		(layer "F.Cu")
		(net "P3V3")
	)
	(segment
		(start 16.98625 -174.463964)
		(end 16.67129 -174.778924)
		(width 0.3048)
		(layer "F.Cu")
		(net "P3V3")
	)
	(segment
		(start 40.795956 -152.8572)
		(end 40.26789 -153.385266)
		(width 0.508)
		(layer "F.Cu")
		(net "P3V3")
	)
	(segment
		(start 27.6098 -170.4594)
		(end 27.1018 -170.4594)
		(width 0.508)
		(layer "F.Cu")
		(net "P3V3")
	)
	(segment
		(start 36.933886 -168.632378)
		(end 36.480242 -168.178734)
		(width 0.508)
		(layer "F.Cu")
		(net "P3V3")
	)
	(segment
		(start 26.543 -234.696)
		(end 25.8572 -234.0102)
		(width 1.016)
		(layer "F.Cu")
		(net "P3V3")
	)
	(segment
		(start 28.779724 -172.06341)
		(end 28.779724 -171.629324)
		(width 0.508)
		(layer "F.Cu")
		(net "P3V3")
	)
	(segment
		(start 28.779724 -171.629324)
		(end 27.6098 -170.4594)
		(width 0.508)
		(layer "F.Cu")
		(net "P3V3")
	)
	(segment
		(start 15.9385 -60.0837)
		(end 15.9512 -60.071)
		(width 0.508)
		(layer "F.Cu")
		(net "P3V3")
	)
	(segment
		(start 4.7117 -417.6522)
		(end 3.3782 -417.6522)
		(width 0.508)
		(layer "F.Cu")
		(net "P3V3")
	)
	(segment
		(start 20.0787 -173.9392)
		(end 19.882612 -173.9392)
		(width 0.508)
		(layer "F.Cu")
		(net "P3V3")
	)
	(segment
		(start 38.6334 -254.8255)
		(end 39.116 -254.8255)
		(width 0.508)
		(layer "F.Cu")
		(net "P3V3")
	)
	(segment
		(start 19.940524 -175.156622)
		(end 20.4851 -174.612046)
		(width 0.508)
		(layer "F.Cu")
		(net "P3V3")
	)
	(segment
		(start 31.36011 -172.439076)
		(end 30.984444 -172.06341)
		(width 0.508)
		(layer "F.Cu")
		(net "P3V3")
	)
	(segment
		(start 45.83811 -161.282634)
		(end 45.83811 -163.124134)
		(width 0.508)
		(layer "F.Cu")
		(net "P3V3")
	)
	(segment
		(start 20.4216 -235.868464)
		(end 19.841464 -236.4486)
		(width 1.016)
		(layer "F.Cu")
		(net "P3V3")
	)
	(segment
		(start 46.284134 -155.83789)
		(end 46.284134 -154.969972)
		(width 0.508)
		(layer "F.Cu")
		(net "P3V3")
	)
	(segment
		(start 33.2232 -249.3264)
		(end 32.5628 -248.666)
		(width 0.508)
		(layer "F.Cu")
		(net "P3V3")
	)
	(segment
		(start 16.0274 -174.135034)
		(end 16.0274 -172.7708)
		(width 0.508)
		(layer "F.Cu")
		(net "P3V3")
	)
	(segment
		(start 20.4851 -174.612046)
		(end 20.4851 -174.3456)
		(width 0.508)
		(layer "F.Cu")
		(net "P3V3")
	)
	(segment
		(start 4.191 -429.9712)
		(end 5.1181 -429.9712)
		(width 0.508)
		(layer "F.Cu")
		(net "P3V3")
	)
	(segment
		(start 36.969192 -170.1292)
		(end 36.969192 -168.713658)
		(width 0.508)
		(layer "F.Cu")
		(net "P3V3")
	)
	(segment
		(start 46.531276 -163.549076)
		(end 46.531276 -164.847524)
		(width 0.508)
		(layer "F.Cu")
		(net "P3V3")
	)
	(segment
		(start 30.984444 -172.06341)
		(end 28.779724 -172.06341)
		(width 0.508)
		(layer "F.Cu")
		(net "P3V3")
	)
	(segment
		(start 46.531276 -164.847524)
		(end 41.2496 -170.1292)
		(width 0.508)
		(layer "F.Cu")
		(net "P3V3")
	)
	(segment
		(start 10.85088 -59.43346)
		(end 11.40714 -58.8772)
		(width 0.508)
		(layer "F.Cu")
		(net "P3V3")
	)
	(segment
		(start 19.304 -173.482)
		(end 19.304 -172.6438)
		(width 0.508)
		(layer "F.Cu")
		(net "P3V3")
	)
	(segment
		(start 26.2382 -169.5958)
		(end 24.6761 -169.5958)
		(width 0.508)
		(layer "F.Cu")
		(net "P3V3")
	)
	(segment
		(start 19.940524 -175.37811)
		(end 19.940524 -175.156622)
		(width 0.508)
		(layer "F.Cu")
		(net "P3V3")
	)
	(segment
		(start 9.939274 -176.817274)
		(end 9.939274 -176.242726)
		(width 0.4064)
		(layer "F.Cu")
		(net "P3V3")
	)
	(segment
		(start 24.4983 -220.600016)
		(end 25.60955 -220.600016)
		(width 0.3556)
		(layer "F.Cu")
		(net "P3V3")
	)
	(segment
		(start 22.1742 -296.0878)
		(end 22.606 -296.5196)
		(width 1.016)
		(layer "F.Cu")
		(net "P3V3")
	)
	(segment
		(start 22.2758 -234.0102)
		(end 20.4216 -235.8644)
		(width 1.016)
		(layer "F.Cu")
		(net "P3V3")
	)
	(segment
		(start 15.9766 -71.12)
		(end 16.68145 -70.41515)
		(width 0.508)
		(layer "F.Cu")
		(net "P3V3")
	)
	(segment
		(start 46.131734 -163.149534)
		(end 46.531276 -163.549076)
		(width 0.508)
		(layer "F.Cu")
		(net "P3V3")
	)
	(segment
		(start 41.9735 -253.4285)
		(end 41.529 -253.4285)
		(width 0.508)
		(layer "F.Cu")
		(net "P3V3")
	)
	(segment
		(start 24.765 -147.7518)
		(end 23.63851 -148.87829)
		(width 0.508)
		(layer "F.Cu")
		(net "P3V3")
	)
	(segment
		(start 33.2232 -249.3264)
		(end 33.2232 -250.3932)
		(width 0.254)
		(layer "F.Cu")
		(net "P3V3")
	)
	(segment
		(start 21.322284 -215.519)
		(end 21.322284 -216.6366)
		(width 0.508)
		(layer "F.Cu")
		(net "P3V3")
	)
	(segment
		(start 18.3388 -179.1208)
		(end 17.0688 -179.1208)
		(width 0.508)
		(layer "F.Cu")
		(net "P3V3")
	)
	(segment
		(start 16.5608 -52.7939)
		(end 15.6464 -52.7939)
		(width 0.508)
		(layer "F.Cu")
		(net "P3V3")
	)
	(segment
		(start 27.2542 -250.0376)
		(end 27.2542 -250.444)
		(width 0.508)
		(layer "F.Cu")
		(net "P3V3")
	)
	(segment
		(start 17.0942 -178.3588)
		(end 15.935706 -177.200306)
		(width 0.508)
		(layer "F.Cu")
		(net "P3V3")
	)
	(segment
		(start 7.3787 -81.6102)
		(end 6.5024 -81.6102)
		(width 0.508)
		(layer "F.Cu")
		(net "P3V3")
	)
	(segment
		(start 23.4442 -221.654116)
		(end 24.4983 -220.600016)
		(width 0.3556)
		(layer "F.Cu")
		(net "P3V3")
	)
	(segment
		(start 23.4442 -221.654116)
		(end 22.225 -221.654116)
		(width 0.508)
		(layer "F.Cu")
		(net "P3V3")
	)
	(segment
		(start 9.9314 -280.924)
		(end 7.0485 -280.924)
		(width 0.508)
		(layer "F.Cu")
		(net "P3V3")
	)
	(segment
		(start 37.2364 -150.3172)
		(end 34.6964 -147.7772)
		(width 0.508)
		(layer "F.Cu")
		(net "P3V3")
	)
	(segment
		(start 17.9324 -62.7634)
		(end 16.51 -61.341)
		(width 0.508)
		(layer "F.Cu")
		(net "P3V3")
	)
	(segment
		(start 14.7066 -214.4014)
		(end 21.322284 -214.4014)
		(width 0.508)
		(layer "F.Cu")
		(net "P3V3")
	)
	(segment
		(start 15.494 -60.0837)
		(end 14.585696 -59.175396)
		(width 0.508)
		(layer "F.Cu")
		(net "P3V3")
	)
	(segment
		(start 42.672 -252.73)
		(end 41.9735 -253.4285)
		(width 0.508)
		(layer "F.Cu")
		(net "P3V3")
	)
	(segment
		(start 12.319 -172.212)
		(end 13.462 -171.069)
		(width 0.508)
		(layer "F.Cu")
		(net "P3V3")
	)
	(segment
		(start 16.383 -296.0878)
		(end 22.1742 -296.0878)
		(width 1.016)
		(layer "F.Cu")
		(net "P3V3")
	)
	(segment
		(start 41.2496 -170.1292)
		(end 36.969192 -170.1292)
		(width 0.508)
		(layer "F.Cu")
		(net "P3V3")
	)
	(segment
		(start 46.6598 -156.213556)
		(end 46.284134 -155.83789)
		(width 0.508)
		(layer "F.Cu")
		(net "P3V3")
	)
	(segment
		(start 34.659316 -172.439076)
		(end 36.969192 -170.1292)
		(width 0.508)
		(layer "F.Cu")
		(net "P3V3")
	)
	(segment
		(start 16.1925 -61.6585)
		(end 16.51 -61.341)
		(width 0.508)
		(layer "F.Cu")
		(net "P3V3")
	)
	(segment
		(start 3.3782 -429.1584)
		(end 4.191 -429.9712)
		(width 0.508)
		(layer "F.Cu")
		(net "P3V3")
	)
	(segment
		(start 36.969192 -168.713658)
		(end 36.933886 -168.678352)
		(width 0.508)
		(layer "F.Cu")
		(net "P3V3")
	)
	(segment
		(start 21.3233 -217.7288)
		(end 21.3233 -216.637616)
		(width 0.508)
		(layer "F.Cu")
		(net "P3V3")
	)
	(segment
		(start 16.0274 -172.7708)
		(end 15.5956 -172.339)
		(width 0.508)
		(layer "F.Cu")
		(net "P3V3")
	)
	(segment
		(start 16.1544 -61.6585)
		(end 16.1925 -61.6585)
		(width 0.508)
		(layer "F.Cu")
		(net "P3V3")
	)
	(segment
		(start 19.151346 -175.133)
		(end 18.269966 -175.133)
		(width 0.508)
		(layer "F.Cu")
		(net "P3V3")
	)
	(segment
		(start 45.81271 -163.149534)
		(end 46.131734 -163.149534)
		(width 0.508)
		(layer "F.Cu")
		(net "P3V3")
	)
	(segment
		(start 41.148508 -246.761508)
		(end 32.765492 -246.761508)
		(width 0.508)
		(layer "F.Cu")
		(net "P3V3")
	)
	(segment
		(start 32.78251 -172.439076)
		(end 31.36011 -172.439076)
		(width 0.508)
		(layer "F.Cu")
		(net "P3V3")
	)
	(segment
		(start 14.6685 -55.118)
		(end 13.8176 -55.118)
		(width 0.508)
		(layer "F.Cu")
		(net "P3V3")
	)
	(segment
		(start 38.608 -254.8001)
		(end 38.6334 -254.8255)
		(width 0.508)
		(layer "F.Cu")
		(net "P3V3")
	)
	(segment
		(start 16.67129 -174.778924)
		(end 17.91589 -174.778924)
		(width 0.508)
		(layer "F.Cu")
		(net "P3V3")
	)
	(segment
		(start 28.94584 -251.16536)
		(end 28.94584 -250.2408)
		(width 0.3556)
		(layer "F.Cu")
		(net "P3V3")
	)
	(segment
		(start 19.7104 -173.8884)
		(end 19.304 -173.482)
		(width 0.508)
		(layer "F.Cu")
		(net "P3V3")
	)
	(segment
		(start 40.26789 -153.385266)
		(end 40.26789 -151.39289)
		(width 0.508)
		(layer "F.Cu")
		(net "P3V3")
	)
	(segment
		(start 9.2456 -172.212)
		(end 12.319 -172.212)
		(width 0.508)
		(layer "F.Cu")
		(net "P3V3")
	)
	(segment
		(start 37.846 -240.2205)
		(end 38.862 -240.2205)
		(width 0.508)
		(layer "F.Cu")
		(net "P3V3")
	)
	(via
		(at 26.797 -359.41)
		(size 0.7112)
		(drill 0.4064)
		(layers "F.Cu" "B.Cu")
		(net "P3V3")
	)
	(via
		(at 6.7183 -69.7865)
		(size 0.5588)
		(drill 0.3048)
		(layers "F.Cu" "B.Cu")
		(net "P3V3")
	)
	(via
		(at 17.9324 -63.627)
		(size 0.5588)
		(drill 0.3048)
		(layers "F.Cu" "B.Cu")
		(net "P3V3")
	)
	(via
		(at 14.4272 -211.074)
		(size 0.7112)
		(drill 0.3556)
		(layers "F.Cu" "B.Cu")
		(net "P3V3")
	)
	(via
		(at 12.5984 -225.9076)
		(size 0.5588)
		(drill 0.3048)
		(layers "F.Cu" "B.Cu")
		(net "P3V3")
	)
	(via
		(at 14.651736 -177.200306)
		(size 0.5588)
		(drill 0.3048)
		(layers "F.Cu" "B.Cu")
		(net "P3V3")
	)
	(via
		(at 16.51 -59.7916)
		(size 0.5588)
		(drill 0.3048)
		(layers "F.Cu" "B.Cu")
		(net "P3V3")
	)
	(via
		(at 14.585696 -59.175396)
		(size 0.5588)
		(drill 0.3048)
		(layers "F.Cu" "B.Cu")
		(net "P3V3")
	)
	(via
		(at 3.3782 -429.1584)
		(size 0.5588)
		(drill 0.3048)
		(layers "F.Cu" "B.Cu")
		(net "P3V3")
	)
	(via
		(at 9.9822 -280.8732)
		(size 0.7112)
		(drill 0.4064)
		(layers "F.Cu" "B.Cu")
		(net "P3V3")
	)
	(via
		(at 13.462 -171.069)
		(size 0.5588)
		(drill 0.3048)
		(layers "F.Cu" "B.Cu")
		(net "P3V3")
	)
	(via
		(at 13.8176 -55.118)
		(size 0.5588)
		(drill 0.3048)
		(layers "F.Cu" "B.Cu")
		(net "P3V3")
	)
	(via
		(at 13.208 -220.345)
		(size 0.7112)
		(drill 0.3556)
		(layers "F.Cu" "B.Cu")
		(net "P3V3")
	)
	(via
		(at 10.414 -236.702346)
		(size 0.7112)
		(drill 0.4064)
		(layers "F.Cu" "B.Cu")
		(net "P3V3")
	)
	(via
		(at 14.40434 -172.991526)
		(size 0.7112)
		(drill 0.4064)
		(layers "F.Cu" "B.Cu")
		(net "P3V3")
	)
	(via
		(at 7.1247 -65.2653)
		(size 0.7112)
		(drill 0.4064)
		(layers "F.Cu" "B.Cu")
		(net "P3V3")
	)
	(via
		(at 14.4272 -175.514)
		(size 0.7112)
		(drill 0.3556)
		(layers "F.Cu" "B.Cu")
		(net "P3V3")
	)
	(via
		(at 3.3782 -417.6522)
		(size 0.5588)
		(drill 0.3048)
		(layers "F.Cu" "B.Cu")
		(net "P3V3")
	)
	(via
		(at 6.477 -81.5848)
		(size 0.5588)
		(drill 0.3048)
		(layers "F.Cu" "B.Cu")
		(net "P3V3")
	)
	(via
		(at 16.383 -296.0878)
		(size 0.7112)
		(drill 0.4064)
		(layers "F.Cu" "B.Cu")
		(net "P3V3")
	)
	(via
		(at 16.5608 -52.7939)
		(size 0.5588)
		(drill 0.3048)
		(layers "F.Cu" "B.Cu")
		(net "P3V3")
	)
	(via
		(at 14.605 -214.503)
		(size 0.5588)
		(drill 0.3048)
		(layers "F.Cu" "B.Cu")
		(net "P3V3")
	)
	(via
		(at 17.272 -68.072)
		(size 0.5588)
		(drill 0.3048)
		(layers "F.Cu" "B.Cu")
		(net "P3V3")
	)
	(via
		(at 22.606 -296.5196)
		(size 0.7112)
		(drill 0.4064)
		(layers "F.Cu" "B.Cu")
		(net "P3V3")
	)
	(via
		(at 10.85088 -59.43346)
		(size 0.5588)
		(drill 0.3048)
		(layers "F.Cu" "B.Cu")
		(net "P3V3")
	)
	(via
		(at 16.51 -61.341)
		(size 0.5588)
		(drill 0.3048)
		(layers "F.Cu" "B.Cu")
		(net "P3V3")
	)
	(segment
		(start 16.51 -61.341)
		(end 16.51 -59.7916)
		(width 0.508)
		(layer "B.Cu")
		(net "P3V3")
	)
	(segment
		(start 14.40434 -175.49114)
		(end 14.40434 -172.991526)
		(width 1.016)
		(layer "B.Cu")
		(net "P3V3")
	)
	(segment
		(start 13.208 -220.345)
		(end 13.208 -223.8502)
		(width 1.016)
		(layer "B.Cu")
		(net "P3V3")
	)
	(segment
		(start 17.8054 -63.754)
		(end 17.8054 -67.5386)
		(width 0.508)
		(layer "B.Cu")
		(net "P3V3")
	)
	(segment
		(start 13.462 -172.049186)
		(end 14.40434 -172.991526)
		(width 0.508)
		(layer "B.Cu")
		(net "P3V3")
	)
	(segment
		(start 14.4272 -211.074)
		(end 14.4272 -177.424842)
		(width 1.016)
		(layer "B.Cu")
		(net "P3V3")
	)
	(segment
		(start 2.342134 -378.287534)
		(end 2.8702 -378.8156)
		(width 0.508)
		(layer "B.Cu")
		(net "P3V3")
	)
	(segment
		(start 7.1374 -121.3612)
		(end 7.1374 -134.1374)
		(width 0.508)
		(layer "B.Cu")
		(net "P3V3")
	)
	(segment
		(start 9.9822 -280.8732)
		(end 10.58545 -280.26995)
		(width 1.016)
		(layer "B.Cu")
		(net "P3V3")
	)
	(segment
		(start 6.698996 -69.805804)
		(end 6.698742 -69.805804)
		(width 0.508)
		(layer "B.Cu")
		(net "P3V3")
	)
	(segment
		(start 17.8054 -67.5386)
		(end 17.272 -68.072)
		(width 0.508)
		(layer "B.Cu")
		(net "P3V3")
	)
	(segment
		(start 14.605 -214.503)
		(end 13.208 -215.9)
		(width 1.016)
		(layer "B.Cu")
		(net "P3V3")
	)
	(segment
		(start 26.8732 -319.358264)
		(end 24.8666 -317.351664)
		(width 1.016)
		(layer "B.Cu")
		(net "P3V3")
	)
	(segment
		(start 4.678934 -83.382866)
		(end 4.678934 -113.777014)
		(width 0.508)
		(layer "B.Cu")
		(net "P3V3")
	)
	(segment
		(start 6.7183 -69.7865)
		(end 6.698996 -69.805804)
		(width 0.508)
		(layer "B.Cu")
		(net "P3V3")
	)
	(segment
		(start 14.4272 -175.514)
		(end 14.651736 -175.738536)
		(width 1.016)
		(layer "B.Cu")
		(net "P3V3")
	)
	(segment
		(start 3.3782 -417.6522)
		(end 3.3782 -429.1584)
		(width 0.508)
		(layer "B.Cu")
		(net "P3V3")
	)
	(segment
		(start 15.621 -295.3258)
		(end 16.383 -296.0878)
		(width 1.016)
		(layer "B.Cu")
		(net "P3V3")
	)
	(segment
		(start 12.5984 -229.475792)
		(end 10.58545 -231.488742)
		(width 1.016)
		(layer "B.Cu")
		(net "P3V3")
	)
	(segment
		(start 15.621 -290.576)
		(end 15.621 -295.3258)
		(width 1.016)
		(layer "B.Cu")
		(net "P3V3")
	)
	(segment
		(start 17.9324 -63.627)
		(end 17.8054 -63.754)
		(width 0.508)
		(layer "B.Cu")
		(net "P3V3")
	)
	(segment
		(start 14.585696 -55.886096)
		(end 13.8176 -55.118)
		(width 0.508)
		(layer "B.Cu")
		(net "P3V3")
	)
	(segment
		(start 16.1417 -52.7939)
		(end 13.8176 -55.118)
		(width 0.508)
		(layer "B.Cu")
		(net "P3V3")
	)
	(segment
		(start 16.2306 -296.2402)
		(end 16.2306 -336.8294)
		(width 0.508)
		(layer "B.Cu")
		(net "P3V3")
	)
	(segment
		(start 12.5984 -225.9076)
		(end 12.5984 -229.475792)
		(width 1.016)
		(layer "B.Cu")
		(net "P3V3")
	)
	(segment
		(start 13.462 -171.069)
		(end 13.462 -172.049186)
		(width 0.508)
		(layer "B.Cu")
		(net "P3V3")
	)
	(segment
		(start 2.8702 -417.1442)
		(end 3.3782 -417.6522)
		(width 0.508)
		(layer "B.Cu")
		(net "P3V3")
	)
	(segment
		(start 6.9342 -69.5706)
		(end 6.7183 -69.7865)
		(width 0.508)
		(layer "B.Cu")
		(net "P3V3")
	)
	(segment
		(start 10.85088 -59.43346)
		(end 7.1247 -63.15964)
		(width 0.508)
		(layer "B.Cu")
		(net "P3V3")
	)
	(segment
		(start 9.9822 -280.8732)
		(end 10.5156 -281.4066)
		(width 1.016)
		(layer "B.Cu")
		(net "P3V3")
	)
	(segment
		(start 10.16 -147.066)
		(end 13.462 -150.368)
		(width 0.508)
		(layer "B.Cu")
		(net "P3V3")
	)
	(segment
		(start 6.477 -81.5848)
		(end 4.678934 -83.382866)
		(width 0.508)
		(layer "B.Cu")
		(net "P3V3")
	)
	(segment
		(start 24.8666 -317.351664)
		(end 24.8666 -298.7802)
		(width 1.016)
		(layer "B.Cu")
		(net "P3V3")
	)
	(segment
		(start 13.462 -150.368)
		(end 13.462 -171.069)
		(width 0.508)
		(layer "B.Cu")
		(net "P3V3")
	)
	(segment
		(start 10.5156 -285.4706)
		(end 15.621 -290.576)
		(width 1.016)
		(layer "B.Cu")
		(net "P3V3")
	)
	(segment
		(start 26.797 -359.41)
		(end 26.8732 -359.3338)
		(width 1.016)
		(layer "B.Cu")
		(net "P3V3")
	)
	(segment
		(start 10.58545 -231.488742)
		(end 10.58545 -236.530896)
		(width 1.016)
		(layer "B.Cu")
		(net "P3V3")
	)
	(segment
		(start 14.4272 -211.074)
		(end 14.4272 -214.3252)
		(width 1.016)
		(layer "B.Cu")
		(net "P3V3")
	)
	(segment
		(start 6.0706 -70.433946)
		(end 6.0706 -81.1784)
		(width 0.508)
		(layer "B.Cu")
		(net "P3V3")
	)
	(segment
		(start 14.651736 -175.738536)
		(end 14.651736 -177.200306)
		(width 1.016)
		(layer "B.Cu")
		(net "P3V3")
	)
	(segment
		(start 6.9342 -65.4558)
		(end 6.9342 -69.5706)
		(width 0.508)
		(layer "B.Cu")
		(net "P3V3")
	)
	(segment
		(start 10.16 -137.16)
		(end 10.16 -147.066)
		(width 0.508)
		(layer "B.Cu")
		(net "P3V3")
	)
	(segment
		(start 7.1247 -65.2653)
		(end 6.9342 -65.4558)
		(width 0.508)
		(layer "B.Cu")
		(net "P3V3")
	)
	(segment
		(start 10.58545 -280.26995)
		(end 10.58545 -236.873796)
		(width 1.016)
		(layer "B.Cu")
		(net "P3V3")
	)
	(segment
		(start 14.4272 -175.514)
		(end 14.40434 -175.49114)
		(width 1.016)
		(layer "B.Cu")
		(net "P3V3")
	)
	(segment
		(start 16.5608 -52.7939)
		(end 16.1417 -52.7939)
		(width 0.508)
		(layer "B.Cu")
		(net "P3V3")
	)
	(segment
		(start 13.208 -223.8502)
		(end 12.5984 -224.4598)
		(width 1.016)
		(layer "B.Cu")
		(net "P3V3")
	)
	(segment
		(start 13.208 -215.9)
		(end 13.208 -220.345)
		(width 1.016)
		(layer "B.Cu")
		(net "P3V3")
	)
	(segment
		(start 12.5984 -224.4598)
		(end 12.5984 -225.9076)
		(width 1.016)
		(layer "B.Cu")
		(net "P3V3")
	)
	(segment
		(start 14.585696 -59.175396)
		(end 14.585696 -55.886096)
		(width 0.508)
		(layer "B.Cu")
		(net "P3V3")
	)
	(segment
		(start 4.678934 -113.777014)
		(end 4.204716 -114.251232)
		(width 0.508)
		(layer "B.Cu")
		(net "P3V3")
	)
	(segment
		(start 16.383 -296.0878)
		(end 16.2306 -296.2402)
		(width 0.508)
		(layer "B.Cu")
		(net "P3V3")
	)
	(segment
		(start 16.2306 -336.8294)
		(end 2.342134 -350.717866)
		(width 0.508)
		(layer "B.Cu")
		(net "P3V3")
	)
	(segment
		(start 6.0706 -81.1784)
		(end 6.477 -81.5848)
		(width 0.508)
		(layer "B.Cu")
		(net "P3V3")
	)
	(segment
		(start 10.58545 -236.530896)
		(end 10.414 -236.702346)
		(width 1.016)
		(layer "B.Cu")
		(net "P3V3")
	)
	(segment
		(start 4.204716 -114.251232)
		(end 4.204716 -118.428516)
		(width 0.508)
		(layer "B.Cu")
		(net "P3V3")
	)
	(segment
		(start 6.698742 -69.805804)
		(end 6.0706 -70.433946)
		(width 0.508)
		(layer "B.Cu")
		(net "P3V3")
	)
	(segment
		(start 7.1374 -134.1374)
		(end 10.16 -137.16)
		(width 0.508)
		(layer "B.Cu")
		(net "P3V3")
	)
	(segment
		(start 7.1247 -63.15964)
		(end 7.1247 -65.2653)
		(width 0.508)
		(layer "B.Cu")
		(net "P3V3")
	)
	(segment
		(start 2.8702 -378.8156)
		(end 2.8702 -417.1442)
		(width 0.508)
		(layer "B.Cu")
		(net "P3V3")
	)
	(segment
		(start 10.58545 -236.873796)
		(end 10.414 -236.702346)
		(width 1.016)
		(layer "B.Cu")
		(net "P3V3")
	)
	(segment
		(start 10.5156 -281.4066)
		(end 10.5156 -285.4706)
		(width 1.016)
		(layer "B.Cu")
		(net "P3V3")
	)
	(segment
		(start 14.4272 -214.3252)
		(end 14.605 -214.503)
		(width 1.016)
		(layer "B.Cu")
		(net "P3V3")
	)
	(segment
		(start 24.8666 -298.7802)
		(end 22.606 -296.5196)
		(width 1.016)
		(layer "B.Cu")
		(net "P3V3")
	)
	(segment
		(start 26.8732 -359.3338)
		(end 26.8732 -319.358264)
		(width 1.016)
		(layer "B.Cu")
		(net "P3V3")
	)
	(segment
		(start 14.4272 -177.424842)
		(end 14.651736 -177.200306)
		(width 1.016)
		(layer "B.Cu")
		(net "P3V3")
	)
	(segment
		(start 2.342134 -350.717866)
		(end 2.342134 -378.287534)
		(width 0.508)
		(layer "B.Cu")
		(net "P3V3")
	)
	(segment
		(start 4.204716 -118.428516)
		(end 7.1374 -121.3612)
		(width 0.508)
		(layer "B.Cu")
		(net "P3V3")
	)
	(segment
		(start 28.779724 -174.60341)
		(end 30.245304 -174.60341)
		(width 0.1397)
		(layer "F.Cu")
		(net "PWM_EXP_1B")
	)
	(segment
		(start 30.245304 -174.60341)
		(end 30.348682 -174.500032)
		(width 0.1397)
		(layer "F.Cu")
		(net "PWM_EXP_1B")
	)
	(segment
		(start 31.686246 -174.500032)
		(end 31.954724 -174.76851)
		(width 0.1397)
		(layer "F.Cu")
		(net "PWM_EXP_1B")
	)
	(segment
		(start 30.348682 -174.500032)
		(end 30.372304 -174.500032)
		(width 0.1397)
		(layer "F.Cu")
		(net "PWM_EXP_1B")
	)
	(segment
		(start 30.372304 -174.500032)
		(end 31.686246 -174.500032)
		(width 0.1397)
		(layer "F.Cu")
		(net "PWM_EXP_1B")
	)
	(via
		(at 30.372304 -174.500032)
		(size 0.7112)
		(drill 0.4064)
		(layers "F.Cu" "B.Cu")
		(net "PWM_EXP_1B")
	)
	(segment
		(start 11.023346 -109.460792)
		(end 11.0236 -109.460538)
		(width 0.1397)
		(layer "B.Cu")
		(net "PWM_EXP_1B")
	)
	(segment
		(start 30.372304 -174.500032)
		(end 29.67355 -173.801278)
		(width 0.1397)
		(layer "B.Cu")
		(net "PWM_EXP_1B")
	)
	(segment
		(start 17.13865 -54.984142)
		(end 20.202906 -51.919886)
		(width 0.1397)
		(layer "B.Cu")
		(net "PWM_EXP_1B")
	)
	(segment
		(start 29.67355 -173.801278)
		(end 29.67355 -169.58945)
		(width 0.1397)
		(layer "B.Cu")
		(net "PWM_EXP_1B")
	)
	(segment
		(start 32.48025 -166.78275)
		(end 32.48025 -165.461442)
		(width 0.1397)
		(layer "B.Cu")
		(net "PWM_EXP_1B")
	)
	(segment
		(start 17.13865 -61.638688)
		(end 17.13865 -54.984142)
		(width 0.1397)
		(layer "B.Cu")
		(net "PWM_EXP_1B")
	)
	(segment
		(start 11.0236 -109.460538)
		(end 11.0236 -92.887292)
		(width 0.1397)
		(layer "B.Cu")
		(net "PWM_EXP_1B")
	)
	(segment
		(start 32.48025 -165.461442)
		(end 20.8788 -153.859992)
		(width 0.1397)
		(layer "B.Cu")
		(net "PWM_EXP_1B")
	)
	(segment
		(start 20.202906 -51.919886)
		(end 20.500086 -51.919886)
		(width 0.1397)
		(layer "B.Cu")
		(net "PWM_EXP_1B")
	)
	(segment
		(start 14.5669 -124.88545)
		(end 12.3063 -122.62485)
		(width 0.1397)
		(layer "B.Cu")
		(net "PWM_EXP_1B")
	)
	(segment
		(start 20.8788 -153.859992)
		(end 20.8788 -150.3934)
		(width 0.1397)
		(layer "B.Cu")
		(net "PWM_EXP_1B")
	)
	(segment
		(start 11.4808 -92.430092)
		(end 11.4808 -72.091296)
		(width 0.1397)
		(layer "B.Cu")
		(net "PWM_EXP_1B")
	)
	(segment
		(start 16.8656 -144.8816)
		(end 14.5669 -142.5829)
		(width 0.1397)
		(layer "B.Cu")
		(net "PWM_EXP_1B")
	)
	(segment
		(start 14.5669 -142.5829)
		(end 14.5669 -124.88545)
		(width 0.1397)
		(layer "B.Cu")
		(net "PWM_EXP_1B")
	)
	(segment
		(start 12.274296 -71.2978)
		(end 12.274296 -67.481704)
		(width 0.1397)
		(layer "B.Cu")
		(net "PWM_EXP_1B")
	)
	(segment
		(start 14.4526 -64.324738)
		(end 17.13865 -61.638688)
		(width 0.1397)
		(layer "B.Cu")
		(net "PWM_EXP_1B")
	)
	(segment
		(start 20.8788 -150.3934)
		(end 16.8656 -146.3802)
		(width 0.1397)
		(layer "B.Cu")
		(net "PWM_EXP_1B")
	)
	(segment
		(start 11.0236 -92.887292)
		(end 11.4808 -92.430092)
		(width 0.1397)
		(layer "B.Cu")
		(net "PWM_EXP_1B")
	)
	(segment
		(start 29.67355 -169.58945)
		(end 32.48025 -166.78275)
		(width 0.1397)
		(layer "B.Cu")
		(net "PWM_EXP_1B")
	)
	(segment
		(start 11.023346 -110.737396)
		(end 11.023346 -109.460792)
		(width 0.1397)
		(layer "B.Cu")
		(net "PWM_EXP_1B")
	)
	(segment
		(start 12.3063 -122.62485)
		(end 12.3063 -112.389158)
		(width 0.1397)
		(layer "B.Cu")
		(net "PWM_EXP_1B")
	)
	(segment
		(start 12.274296 -67.481704)
		(end 14.4526 -65.3034)
		(width 0.1397)
		(layer "B.Cu")
		(net "PWM_EXP_1B")
	)
	(segment
		(start 14.4526 -65.3034)
		(end 14.4526 -64.324738)
		(width 0.1397)
		(layer "B.Cu")
		(net "PWM_EXP_1B")
	)
	(segment
		(start 11.023092 -111.10595)
		(end 11.023092 -110.73765)
		(width 0.1397)
		(layer "B.Cu")
		(net "PWM_EXP_1B")
	)
	(segment
		(start 16.8656 -146.3802)
		(end 16.8656 -144.8816)
		(width 0.1397)
		(layer "B.Cu")
		(net "PWM_EXP_1B")
	)
	(segment
		(start 12.3063 -112.389158)
		(end 11.023092 -111.10595)
		(width 0.1397)
		(layer "B.Cu")
		(net "PWM_EXP_1B")
	)
	(segment
		(start 11.023092 -110.73765)
		(end 11.023346 -110.737396)
		(width 0.1397)
		(layer "B.Cu")
		(net "PWM_EXP_1B")
	)
	(segment
		(start 11.4808 -72.091296)
		(end 12.274296 -71.2978)
		(width 0.1397)
		(layer "B.Cu")
		(net "PWM_EXP_1B")
	)
	(segment
		(start 28.779724 -173.33341)
		(end 30.58541 -173.33341)
		(width 0.1397)
		(layer "F.Cu")
		(net "PWM_EXP_1A")
	)
	(segment
		(start 30.861 -173.609)
		(end 31.912814 -173.609)
		(width 0.1397)
		(layer "F.Cu")
		(net "PWM_EXP_1A")
	)
	(segment
		(start 30.58541 -173.33341)
		(end 30.861 -173.609)
		(width 0.1397)
		(layer "F.Cu")
		(net "PWM_EXP_1A")
	)
	(segment
		(start 31.912814 -173.609)
		(end 31.954724 -173.65091)
		(width 0.1397)
		(layer "F.Cu")
		(net "PWM_EXP_1A")
	)
	(via
		(at 30.861 -173.609)
		(size 0.7112)
		(drill 0.4064)
		(layers "F.Cu" "B.Cu")
		(net "PWM_EXP_1A")
	)
	(segment
		(start 18.28165 -145.954242)
		(end 20.3962 -148.068792)
		(width 0.1397)
		(layer "B.Cu")
		(net "PWM_EXP_1A")
	)
	(segment
		(start 11.9253 -92.614496)
		(end 11.72845 -92.811346)
		(width 0.1397)
		(layer "B.Cu")
		(net "PWM_EXP_1A")
	)
	(segment
		(start 20.3962 -149.2758)
		(end 21.3614 -150.241)
		(width 0.1397)
		(layer "B.Cu")
		(net "PWM_EXP_1A")
	)
	(segment
		(start 12.7508 -112.204754)
		(end 12.7508 -122.4407)
		(width 0.1397)
		(layer "B.Cu")
		(net "PWM_EXP_1A")
	)
	(segment
		(start 12.718796 -71.7296)
		(end 11.9253 -72.523096)
		(width 0.1397)
		(layer "B.Cu")
		(net "PWM_EXP_1A")
	)
	(segment
		(start 11.467846 -109.644942)
		(end 11.467846 -110.9218)
		(width 0.1397)
		(layer "B.Cu")
		(net "PWM_EXP_1A")
	)
	(segment
		(start 11.728196 -92.811346)
		(end 11.4681 -93.071442)
		(width 0.1397)
		(layer "B.Cu")
		(net "PWM_EXP_1A")
	)
	(segment
		(start 32.92475 -166.97325)
		(end 30.861 -169.037)
		(width 0.1397)
		(layer "B.Cu")
		(net "PWM_EXP_1A")
	)
	(segment
		(start 20.3962 -148.068792)
		(end 20.3962 -149.2758)
		(width 0.1397)
		(layer "B.Cu")
		(net "PWM_EXP_1A")
	)
	(segment
		(start 18.28165 -145.617946)
		(end 18.28165 -145.954242)
		(width 0.1397)
		(layer "B.Cu")
		(net "PWM_EXP_1A")
	)
	(segment
		(start 32.92475 -165.277292)
		(end 32.92475 -166.97325)
		(width 0.1397)
		(layer "B.Cu")
		(net "PWM_EXP_1A")
	)
	(segment
		(start 21.3614 -153.713942)
		(end 32.92475 -165.277292)
		(width 0.1397)
		(layer "B.Cu")
		(net "PWM_EXP_1A")
	)
	(segment
		(start 11.9253 -72.523096)
		(end 11.9253 -92.614496)
		(width 0.1397)
		(layer "B.Cu")
		(net "PWM_EXP_1A")
	)
	(segment
		(start 11.4681 -109.644688)
		(end 11.467846 -109.644942)
		(width 0.1397)
		(layer "B.Cu")
		(net "PWM_EXP_1A")
	)
	(segment
		(start 16.731996 -64.706754)
		(end 12.718796 -68.719954)
		(width 0.1397)
		(layer "B.Cu")
		(net "PWM_EXP_1A")
	)
	(segment
		(start 15.0114 -124.7013)
		(end 15.0114 -142.347696)
		(width 0.1397)
		(layer "B.Cu")
		(net "PWM_EXP_1A")
	)
	(segment
		(start 23.040086 -59.539886)
		(end 21.674836 -60.905136)
		(width 0.1397)
		(layer "B.Cu")
		(net "PWM_EXP_1A")
	)
	(segment
		(start 16.731996 -63.074804)
		(end 16.731996 -64.706754)
		(width 0.1397)
		(layer "B.Cu")
		(net "PWM_EXP_1A")
	)
	(segment
		(start 18.901664 -60.905136)
		(end 16.731996 -63.074804)
		(width 0.1397)
		(layer "B.Cu")
		(net "PWM_EXP_1A")
	)
	(segment
		(start 12.718796 -68.719954)
		(end 12.718796 -71.7296)
		(width 0.1397)
		(layer "B.Cu")
		(net "PWM_EXP_1A")
	)
	(segment
		(start 11.72845 -92.811346)
		(end 11.728196 -92.811346)
		(width 0.1397)
		(layer "B.Cu")
		(net "PWM_EXP_1A")
	)
	(segment
		(start 21.3614 -150.241)
		(end 21.3614 -153.713942)
		(width 0.1397)
		(layer "B.Cu")
		(net "PWM_EXP_1A")
	)
	(segment
		(start 11.4681 -93.071442)
		(end 11.4681 -109.644688)
		(width 0.1397)
		(layer "B.Cu")
		(net "PWM_EXP_1A")
	)
	(segment
		(start 15.0114 -142.347696)
		(end 18.28165 -145.617946)
		(width 0.1397)
		(layer "B.Cu")
		(net "PWM_EXP_1A")
	)
	(segment
		(start 11.467846 -110.9218)
		(end 12.7508 -112.204754)
		(width 0.1397)
		(layer "B.Cu")
		(net "PWM_EXP_1A")
	)
	(segment
		(start 30.861 -169.037)
		(end 30.861 -173.609)
		(width 0.1397)
		(layer "B.Cu")
		(net "PWM_EXP_1A")
	)
	(segment
		(start 21.674836 -60.905136)
		(end 18.901664 -60.905136)
		(width 0.1397)
		(layer "B.Cu")
		(net "PWM_EXP_1A")
	)
	(segment
		(start 12.7508 -122.4407)
		(end 15.0114 -124.7013)
		(width 0.1397)
		(layer "B.Cu")
		(net "PWM_EXP_1A")
	)
	(segment
		(start 31.122366 -242.771676)
		(end 31.122112 -242.771676)
		(width 0.1397)
		(layer "F.Cu")
		(net "FCB_EEPROM_A2")
	)
	(segment
		(start 30.24632 -243.647722)
		(end 31.122366 -242.771676)
		(width 0.1397)
		(layer "F.Cu")
		(net "FCB_EEPROM_A2")
	)
	(segment
		(start 30.24632 -244.602)
		(end 30.24632 -243.647722)
		(width 0.1397)
		(layer "F.Cu")
		(net "FCB_EEPROM_A2")
	)
	(segment
		(start 31.122112 -242.771676)
		(end 30.493716 -242.14328)
		(width 0.1397)
		(layer "F.Cu")
		(net "FCB_EEPROM_A2")
	)
	(segment
		(start 30.493716 -239.121442)
		(end 30.904434 -238.710724)
		(width 0.1397)
		(layer "F.Cu")
		(net "FCB_EEPROM_A2")
	)
	(segment
		(start 30.493716 -242.14328)
		(end 30.493716 -240.1824)
		(width 0.1397)
		(layer "F.Cu")
		(net "FCB_EEPROM_A2")
	)
	(segment
		(start 30.493716 -240.1824)
		(end 30.493716 -239.121442)
		(width 0.1397)
		(layer "F.Cu")
		(net "FCB_EEPROM_A2")
	)
	(via
		(at 30.493716 -240.1824)
		(size 0.7112)
		(drill 0.3556)
		(layers "F.Cu" "B.Cu")
		(net "FCB_EEPROM_A2")
	)
	(segment
		(start 28.6512 -239.8395)
		(end 29.7942 -238.6965)
		(width 0.1397)
		(layer "F.Cu")
		(net "FCB_EEPROM_A1")
	)
	(segment
		(start 29.223716 -241.02187)
		(end 29.223716 -242.202716)
		(width 0.1397)
		(layer "F.Cu")
		(net "FCB_EEPROM_A1")
	)
	(segment
		(start 29.792676 -242.771676)
		(end 29.852366 -242.771676)
		(width 0.1397)
		(layer "F.Cu")
		(net "FCB_EEPROM_A1")
	)
	(segment
		(start 28.6512 -240.449354)
		(end 28.6512 -239.8395)
		(width 0.1397)
		(layer "F.Cu")
		(net "FCB_EEPROM_A1")
	)
	(segment
		(start 28.697936 -240.49609)
		(end 29.223716 -241.02187)
		(width 0.1397)
		(layer "F.Cu")
		(net "FCB_EEPROM_A1")
	)
	(segment
		(start 28.697936 -240.49609)
		(end 28.6512 -240.449354)
		(width 0.1397)
		(layer "F.Cu")
		(net "FCB_EEPROM_A1")
	)
	(segment
		(start 29.59608 -243.027962)
		(end 29.59608 -244.602)
		(width 0.1397)
		(layer "F.Cu")
		(net "FCB_EEPROM_A1")
	)
	(segment
		(start 29.852366 -242.771676)
		(end 29.59608 -243.027962)
		(width 0.1397)
		(layer "F.Cu")
		(net "FCB_EEPROM_A1")
	)
	(segment
		(start 29.223716 -242.202716)
		(end 29.792676 -242.771676)
		(width 0.1397)
		(layer "F.Cu")
		(net "FCB_EEPROM_A1")
	)
	(via
		(at 28.697936 -240.49609)
		(size 0.7112)
		(drill 0.3556)
		(layers "F.Cu" "B.Cu")
		(net "FCB_EEPROM_A1")
	)
	(segment
		(start 26.9367 -240.5253)
		(end 26.9367 -241.6429)
		(width 0.1397)
		(layer "F.Cu")
		(net "FCB_EEPROM_A0")
	)
	(segment
		(start 26.9367 -241.6429)
		(end 27.4828 -242.189)
		(width 0.1397)
		(layer "F.Cu")
		(net "FCB_EEPROM_A0")
	)
	(segment
		(start 28.067 -239.395)
		(end 26.9367 -240.5253)
		(width 0.1397)
		(layer "F.Cu")
		(net "FCB_EEPROM_A0")
	)
	(segment
		(start 28.94584 -243.13515)
		(end 28.94584 -244.602)
		(width 0.1397)
		(layer "F.Cu")
		(net "FCB_EEPROM_A0")
	)
	(segment
		(start 28.067 -238.6965)
		(end 28.067 -239.395)
		(width 0.1397)
		(layer "F.Cu")
		(net "FCB_EEPROM_A0")
	)
	(segment
		(start 28.065476 -242.771676)
		(end 28.582366 -242.771676)
		(width 0.1397)
		(layer "F.Cu")
		(net "FCB_EEPROM_A0")
	)
	(segment
		(start 27.4828 -242.189)
		(end 28.065476 -242.771676)
		(width 0.1397)
		(layer "F.Cu")
		(net "FCB_EEPROM_A0")
	)
	(segment
		(start 28.582366 -242.771676)
		(end 28.94584 -243.13515)
		(width 0.1397)
		(layer "F.Cu")
		(net "FCB_EEPROM_A0")
	)
	(via
		(at 27.4828 -242.189)
		(size 0.7112)
		(drill 0.3556)
		(layers "F.Cu" "B.Cu")
		(net "FCB_EEPROM_A0")
	)
	(segment
		(start 24.0665 -364.4646)
		(end 25.4 -365.7981)
		(width 0.254)
		(layer "F.Cu")
		(net "ADM1276_SS")
	)
	(segment
		(start 25.4 -366.522)
		(end 25.4 -366.815116)
		(width 0.254)
		(layer "F.Cu")
		(net "ADM1276_SS")
	)
	(segment
		(start 26.742898 -368.158014)
		(end 27.2796 -368.158014)
		(width 0.254)
		(layer "F.Cu")
		(net "ADM1276_SS")
	)
	(segment
		(start 25.4 -365.7981)
		(end 25.4 -366.522)
		(width 0.254)
		(layer "F.Cu")
		(net "ADM1276_SS")
	)
	(segment
		(start 25.4 -366.815116)
		(end 26.742898 -368.158014)
		(width 0.254)
		(layer "F.Cu")
		(net "ADM1276_SS")
	)
	(via
		(at 25.4 -366.522)
		(size 0.7112)
		(drill 0.3556)
		(layers "F.Cu" "B.Cu")
		(net "ADM1276_SS")
	)
	(segment
		(start 27.61234 -154.86634)
		(end 26.67 -153.924)
		(width 0.1397)
		(layer "F.Cu")
		(net "NCT7904_VREF")
	)
	(segment
		(start 26.67 -153.924)
		(end 26.67 -153.2128)
		(width 0.1397)
		(layer "F.Cu")
		(net "NCT7904_VREF")
	)
	(segment
		(start 26.67 -152.1333)
		(end 26.289 -151.7523)
		(width 0.1397)
		(layer "F.Cu")
		(net "NCT7904_VREF")
	)
	(segment
		(start 27.61234 -155.607766)
		(end 27.61234 -154.86634)
		(width 0.1397)
		(layer "F.Cu")
		(net "NCT7904_VREF")
	)
	(segment
		(start 26.67 -153.2128)
		(end 26.67 -152.1333)
		(width 0.1397)
		(layer "F.Cu")
		(net "NCT7904_VREF")
	)
	(segment
		(start 37.81933 -157.78226)
		(end 36.002214 -159.599376)
		(width 0.1397)
		(layer "F.Cu")
		(net "NCT7904_PROCHOT")
	)
	(segment
		(start 40.3098 -156.4386)
		(end 38.96614 -157.78226)
		(width 0.1397)
		(layer "F.Cu")
		(net "NCT7904_PROCHOT")
	)
	(segment
		(start 36.002214 -159.599376)
		(end 34.60369 -159.599376)
		(width 0.1397)
		(layer "F.Cu")
		(net "NCT7904_PROCHOT")
	)
	(segment
		(start 38.96614 -157.78226)
		(end 37.81933 -157.78226)
		(width 0.1397)
		(layer "F.Cu")
		(net "NCT7904_PROCHOT")
	)
	(segment
		(start 40.8178 -156.4386)
		(end 40.3098 -156.4386)
		(width 0.1397)
		(layer "F.Cu")
		(net "NCT7904_PROCHOT")
	)
	(segment
		(start 36.420552 -161.099246)
		(end 34.60369 -161.099246)
		(width 0.1397)
		(layer "F.Cu")
		(net "NCT7904_THERMTRIP")
	)
	(segment
		(start 38.118288 -159.40151)
		(end 36.420552 -161.099246)
		(width 0.1397)
		(layer "F.Cu")
		(net "NCT7904_THERMTRIP")
	)
	(segment
		(start 38.361366 -159.40151)
		(end 38.118288 -159.40151)
		(width 0.1397)
		(layer "F.Cu")
		(net "NCT7904_THERMTRIP")
	)
	(segment
		(start 36.20135 -152.544526)
		(end 36.20135 -156.88564)
		(width 0.1397)
		(layer "F.Cu")
		(net "NCT7904_VSEN14")
	)
	(segment
		(start 36.20135 -156.88564)
		(end 35.487864 -157.599126)
		(width 0.1397)
		(layer "F.Cu")
		(net "NCT7904_VSEN14")
	)
	(segment
		(start 36.659566 -152.08631)
		(end 36.20135 -152.544526)
		(width 0.1397)
		(layer "F.Cu")
		(net "NCT7904_VSEN14")
	)
	(segment
		(start 35.487864 -157.599126)
		(end 34.60369 -157.599126)
		(width 0.1397)
		(layer "F.Cu")
		(net "NCT7904_VSEN14")
	)
	(segment
		(start 37.70249 -167.134032)
		(end 37.84473 -167.276272)
		(width 0.1397)
		(layer "F.Cu")
		(net "I2C_C_SCL")
	)
	(segment
		(start 35.280092 -259.320792)
		(end 36.105592 -259.320792)
		(width 0.1397)
		(layer "F.Cu")
		(net "I2C_C_SCL")
	)
	(segment
		(start 37.83965 -258.08305)
		(end 37.83965 -259.029454)
		(width 0.1397)
		(layer "F.Cu")
		(net "I2C_C_SCL")
	)
	(segment
		(start 30.3022 -254.3429)
		(end 35.280092 -259.320792)
		(width 0.1397)
		(layer "F.Cu")
		(net "I2C_C_SCL")
	)
	(segment
		(start 13.7922 -67.3862)
		(end 14.605 -68.199)
		(width 0.1397)
		(layer "F.Cu")
		(net "I2C_C_SCL")
	)
	(segment
		(start 35.3314 -255.5748)
		(end 37.83965 -258.08305)
		(width 0.1397)
		(layer "F.Cu")
		(net "I2C_C_SCL")
	)
	(segment
		(start 37.103304 -259.7658)
		(end 36.5506 -259.7658)
		(width 0.1397)
		(layer "F.Cu")
		(net "I2C_C_SCL")
	)
	(segment
		(start 13.7922 -66.8909)
		(end 13.7922 -67.3862)
		(width 0.1397)
		(layer "F.Cu")
		(net "I2C_C_SCL")
	)
	(segment
		(start 37.83965 -259.029454)
		(end 37.103304 -259.7658)
		(width 0.1397)
		(layer "F.Cu")
		(net "I2C_C_SCL")
	)
	(segment
		(start 32.3977 -360.8578)
		(end 32.385 -360.8705)
		(width 0.1397)
		(layer "F.Cu")
		(net "I2C_C_SCL")
	)
	(segment
		(start 33.9852 -360.8578)
		(end 32.3977 -360.8578)
		(width 0.1397)
		(layer "F.Cu")
		(net "I2C_C_SCL")
	)
	(segment
		(start 34.163 -360.68)
		(end 33.9852 -360.8578)
		(width 0.1397)
		(layer "F.Cu")
		(net "I2C_C_SCL")
	)
	(segment
		(start 36.105592 -259.320792)
		(end 36.5506 -259.7658)
		(width 0.1397)
		(layer "F.Cu")
		(net "I2C_C_SCL")
	)
	(segment
		(start 35.3314 -254.8001)
		(end 35.3314 -255.5748)
		(width 0.1397)
		(layer "F.Cu")
		(net "I2C_C_SCL")
	)
	(segment
		(start 37.70249 -165.958266)
		(end 37.70249 -167.134032)
		(width 0.1397)
		(layer "F.Cu")
		(net "I2C_C_SCL")
	)
	(via
		(at 19.346164 -140.072364)
		(size 0.7112)
		(drill 0.3556)
		(layers "F.Cu" "B.Cu")
		(net "I2C_C_SCL")
	)
	(via
		(at 37.84473 -167.276272)
		(size 0.7112)
		(drill 0.4064)
		(layers "F.Cu" "B.Cu")
		(net "I2C_C_SCL")
	)
	(via
		(at 14.605 -68.199)
		(size 0.5588)
		(drill 0.3048)
		(layers "F.Cu" "B.Cu")
		(net "I2C_C_SCL")
	)
	(via
		(at 34.163 -360.68)
		(size 0.5588)
		(drill 0.3048)
		(layers "F.Cu" "B.Cu")
		(net "I2C_C_SCL")
	)
	(via
		(at 36.5506 -259.7658)
		(size 0.7112)
		(drill 0.4064)
		(layers "F.Cu" "B.Cu")
		(net "I2C_C_SCL")
	)
	(segment
		(start 38.4302 -159.978598)
		(end 39.795196 -158.613602)
		(width 0.1397)
		(layer "B.Cu")
		(net "I2C_C_SCL")
	)
	(segment
		(start 30.0736 -150.4442)
		(end 30.0736 -150.4188)
		(width 0.1397)
		(layer "B.Cu")
		(net "I2C_C_SCL")
	)
	(segment
		(start 13.335 -93.19895)
		(end 12.8778 -93.65615)
		(width 0.1397)
		(layer "B.Cu")
		(net "I2C_C_SCL")
	)
	(segment
		(start 40.3352 -212.1154)
		(end 42.1386 -213.9188)
		(width 0.1397)
		(layer "B.Cu")
		(net "I2C_C_SCL")
	)
	(segment
		(start 37.84473 -169.603928)
		(end 39.99865 -171.757848)
		(width 0.1397)
		(layer "B.Cu")
		(net "I2C_C_SCL")
	)
	(segment
		(start 35.979354 -276.720046)
		(end 35.979354 -273.779234)
		(width 0.1397)
		(layer "B.Cu")
		(net "I2C_C_SCL")
	)
	(segment
		(start 39.9796 -173.2534)
		(end 39.9796 -176.1236)
		(width 0.1397)
		(layer "B.Cu")
		(net "I2C_C_SCL")
	)
	(segment
		(start 39.795196 -156.947108)
		(end 36.816538 -153.96845)
		(width 0.1397)
		(layer "B.Cu")
		(net "I2C_C_SCL")
	)
	(segment
		(start 38.9128 -186.8932)
		(end 38.8366 -186.9694)
		(width 0.1397)
		(layer "B.Cu")
		(net "I2C_C_SCL")
	)
	(segment
		(start 14.6431 -73.1647)
		(end 13.335 -74.4728)
		(width 0.1397)
		(layer "B.Cu")
		(net "I2C_C_SCL")
	)
	(segment
		(start 43.6372 -215.4428)
		(end 43.6372 -251.3838)
		(width 0.1397)
		(layer "B.Cu")
		(net "I2C_C_SCL")
	)
	(segment
		(start 33.921954 -360.438954)
		(end 33.921954 -278.777446)
		(width 0.1397)
		(layer "B.Cu")
		(net "I2C_C_SCL")
	)
	(segment
		(start 38.9128 -186.8678)
		(end 38.9128 -186.8932)
		(width 0.1397)
		(layer "B.Cu")
		(net "I2C_C_SCL")
	)
	(segment
		(start 35.985958 -260.3754)
		(end 36.5506 -259.810758)
		(width 0.1397)
		(layer "B.Cu")
		(net "I2C_C_SCL")
	)
	(segment
		(start 36.7538 -258.2672)
		(end 36.5506 -258.4704)
		(width 0.1397)
		(layer "B.Cu")
		(net "I2C_C_SCL")
	)
	(segment
		(start 37.84473 -167.276272)
		(end 37.84473 -169.603928)
		(width 0.1397)
		(layer "B.Cu")
		(net "I2C_C_SCL")
	)
	(segment
		(start 14.605 -68.199)
		(end 14.6431 -68.2371)
		(width 0.1397)
		(layer "B.Cu")
		(net "I2C_C_SCL")
	)
	(segment
		(start 42.291 -252.7046)
		(end 36.7538 -258.2418)
		(width 0.1397)
		(layer "B.Cu")
		(net "I2C_C_SCL")
	)
	(segment
		(start 35.979862 -273.778726)
		(end 35.979862 -260.489954)
		(width 0.1397)
		(layer "B.Cu")
		(net "I2C_C_SCL")
	)
	(segment
		(start 12.8778 -93.65615)
		(end 12.8778 -110.3376)
		(width 0.1397)
		(layer "B.Cu")
		(net "I2C_C_SCL")
	)
	(segment
		(start 40.3098 -212.1154)
		(end 40.3352 -212.1154)
		(width 0.1397)
		(layer "B.Cu")
		(net "I2C_C_SCL")
	)
	(segment
		(start 33.62325 -153.96845)
		(end 32.4612 -152.8064)
		(width 0.1397)
		(layer "B.Cu")
		(net "I2C_C_SCL")
	)
	(segment
		(start 40.0304 -185.7502)
		(end 38.9128 -186.8678)
		(width 0.1397)
		(layer "B.Cu")
		(net "I2C_C_SCL")
	)
	(segment
		(start 13.335 -74.4728)
		(end 13.335 -93.19895)
		(width 0.1397)
		(layer "B.Cu")
		(net "I2C_C_SCL")
	)
	(segment
		(start 42.1386 -213.9188)
		(end 42.1386 -213.9442)
		(width 0.1397)
		(layer "B.Cu")
		(net "I2C_C_SCL")
	)
	(segment
		(start 12.8778 -110.3376)
		(end 14.1605 -111.6203)
		(width 0.1397)
		(layer "B.Cu")
		(net "I2C_C_SCL")
	)
	(segment
		(start 36.5506 -259.810758)
		(end 36.5506 -259.7658)
		(width 0.1397)
		(layer "B.Cu")
		(net "I2C_C_SCL")
	)
	(segment
		(start 14.6431 -68.2371)
		(end 14.6431 -73.1647)
		(width 0.1397)
		(layer "B.Cu")
		(net "I2C_C_SCL")
	)
	(segment
		(start 42.3164 -252.7046)
		(end 42.291 -252.7046)
		(width 0.1397)
		(layer "B.Cu")
		(net "I2C_C_SCL")
	)
	(segment
		(start 30.0736 -150.4188)
		(end 23.0632 -143.4084)
		(width 0.1397)
		(layer "B.Cu")
		(net "I2C_C_SCL")
	)
	(segment
		(start 40.0304 -185.2422)
		(end 40.0304 -185.7502)
		(width 0.1397)
		(layer "B.Cu")
		(net "I2C_C_SCL")
	)
	(segment
		(start 33.921954 -278.777446)
		(end 35.979354 -276.720046)
		(width 0.1397)
		(layer "B.Cu")
		(net "I2C_C_SCL")
	)
	(segment
		(start 36.816538 -153.96845)
		(end 33.62325 -153.96845)
		(width 0.1397)
		(layer "B.Cu")
		(net "I2C_C_SCL")
	)
	(segment
		(start 35.985958 -260.483604)
		(end 35.985958 -260.3754)
		(width 0.1397)
		(layer "B.Cu")
		(net "I2C_C_SCL")
	)
	(segment
		(start 43.6372 -251.3838)
		(end 42.3164 -252.7046)
		(width 0.1397)
		(layer "B.Cu")
		(net "I2C_C_SCL")
	)
	(segment
		(start 22.6822 -143.4084)
		(end 19.346164 -140.072364)
		(width 0.1397)
		(layer "B.Cu")
		(net "I2C_C_SCL")
	)
	(segment
		(start 14.1605 -111.6203)
		(end 14.1605 -121.8565)
		(width 0.1397)
		(layer "B.Cu")
		(net "I2C_C_SCL")
	)
	(segment
		(start 42.1386 -213.9442)
		(end 43.6372 -215.4428)
		(width 0.1397)
		(layer "B.Cu")
		(net "I2C_C_SCL")
	)
	(segment
		(start 36.5506 -258.4704)
		(end 36.5506 -259.7658)
		(width 0.1397)
		(layer "B.Cu")
		(net "I2C_C_SCL")
	)
	(segment
		(start 39.99865 -173.23435)
		(end 39.9796 -173.2534)
		(width 0.1397)
		(layer "B.Cu")
		(net "I2C_C_SCL")
	)
	(segment
		(start 32.4358 -152.8064)
		(end 30.0736 -150.4442)
		(width 0.1397)
		(layer "B.Cu")
		(net "I2C_C_SCL")
	)
	(segment
		(start 39.99865 -171.757848)
		(end 39.99865 -173.23435)
		(width 0.1397)
		(layer "B.Cu")
		(net "I2C_C_SCL")
	)
	(segment
		(start 34.163 -360.68)
		(end 33.921954 -360.438954)
		(width 0.1397)
		(layer "B.Cu")
		(net "I2C_C_SCL")
	)
	(segment
		(start 35.979862 -260.489954)
		(end 35.98545 -260.484366)
		(width 0.1397)
		(layer "B.Cu")
		(net "I2C_C_SCL")
	)
	(segment
		(start 35.98545 -260.484366)
		(end 35.98545 -260.484112)
		(width 0.1397)
		(layer "B.Cu")
		(net "I2C_C_SCL")
	)
	(segment
		(start 40.022018 -176.166018)
		(end 40.022018 -185.233818)
		(width 0.1397)
		(layer "B.Cu")
		(net "I2C_C_SCL")
	)
	(segment
		(start 38.4302 -166.690802)
		(end 38.4302 -159.978598)
		(width 0.1397)
		(layer "B.Cu")
		(net "I2C_C_SCL")
	)
	(segment
		(start 35.979354 -273.779234)
		(end 35.979862 -273.778726)
		(width 0.1397)
		(layer "B.Cu")
		(net "I2C_C_SCL")
	)
	(segment
		(start 37.84473 -167.276272)
		(end 38.4302 -166.690802)
		(width 0.1397)
		(layer "B.Cu")
		(net "I2C_C_SCL")
	)
	(segment
		(start 16.4211 -137.1473)
		(end 19.346164 -140.072364)
		(width 0.1397)
		(layer "B.Cu")
		(net "I2C_C_SCL")
	)
	(segment
		(start 14.1605 -121.8565)
		(end 16.4211 -124.1171)
		(width 0.1397)
		(layer "B.Cu")
		(net "I2C_C_SCL")
	)
	(segment
		(start 39.795196 -158.613602)
		(end 39.795196 -156.947108)
		(width 0.1397)
		(layer "B.Cu")
		(net "I2C_C_SCL")
	)
	(segment
		(start 38.8366 -210.6422)
		(end 40.3098 -212.1154)
		(width 0.1397)
		(layer "B.Cu")
		(net "I2C_C_SCL")
	)
	(segment
		(start 36.7538 -258.2418)
		(end 36.7538 -258.2672)
		(width 0.1397)
		(layer "B.Cu")
		(net "I2C_C_SCL")
	)
	(segment
		(start 39.9796 -176.1236)
		(end 40.022018 -176.166018)
		(width 0.1397)
		(layer "B.Cu")
		(net "I2C_C_SCL")
	)
	(segment
		(start 16.4211 -124.1171)
		(end 16.4211 -137.1473)
		(width 0.1397)
		(layer "B.Cu")
		(net "I2C_C_SCL")
	)
	(segment
		(start 23.0632 -143.4084)
		(end 22.6822 -143.4084)
		(width 0.1397)
		(layer "B.Cu")
		(net "I2C_C_SCL")
	)
	(segment
		(start 40.022018 -185.233818)
		(end 40.0304 -185.2422)
		(width 0.1397)
		(layer "B.Cu")
		(net "I2C_C_SCL")
	)
	(segment
		(start 38.8366 -186.9694)
		(end 38.8366 -210.6422)
		(width 0.1397)
		(layer "B.Cu")
		(net "I2C_C_SCL")
	)
	(segment
		(start 35.98545 -260.484112)
		(end 35.985958 -260.483604)
		(width 0.1397)
		(layer "B.Cu")
		(net "I2C_C_SCL")
	)
	(segment
		(start 32.4612 -152.8064)
		(end 32.4358 -152.8064)
		(width 0.1397)
		(layer "B.Cu")
		(net "I2C_C_SCL")
	)
	(segment
		(start 35.75685 -156.70149)
		(end 35.358324 -157.100016)
		(width 0.1397)
		(layer "F.Cu")
		(net "NCT7904_VSEN13")
	)
	(segment
		(start 35.75685 -153.672794)
		(end 35.75685 -156.70149)
		(width 0.1397)
		(layer "F.Cu")
		(net "NCT7904_VSEN13")
	)
	(segment
		(start 35.358324 -157.100016)
		(end 34.60369 -157.100016)
		(width 0.1397)
		(layer "F.Cu")
		(net "NCT7904_VSEN13")
	)
	(segment
		(start 35.541966 -153.45791)
		(end 35.75685 -153.672794)
		(width 0.1397)
		(layer "F.Cu")
		(net "NCT7904_VSEN13")
	)
	(segment
		(start 33.11144 -154.407616)
		(end 33.11144 -155.607766)
		(width 0.1397)
		(layer "F.Cu")
		(net "NCT7904_VSEN12")
	)
	(segment
		(start 35.59429 -151.924766)
		(end 33.11144 -154.407616)
		(width 0.1397)
		(layer "F.Cu")
		(net "NCT7904_VSEN12")
	)
	(segment
		(start 35.59429 -150.680166)
		(end 35.59429 -151.924766)
		(width 0.1397)
		(layer "F.Cu")
		(net "NCT7904_VSEN12")
	)
	(segment
		(start 37.0332 -166.355776)
		(end 36.63569 -165.958266)
		(width 0.1397)
		(layer "F.Cu")
		(net "I2C_C_SDA")
	)
	(segment
		(start 34.2646 -359.7148)
		(end 33.655 -360.3244)
		(width 0.1397)
		(layer "F.Cu")
		(net "I2C_C_SDA")
	)
	(segment
		(start 31.5087 -360.8705)
		(end 31.242 -360.8705)
		(width 0.1397)
		(layer "F.Cu")
		(net "I2C_C_SDA")
	)
	(segment
		(start 34.29 -255.397)
		(end 37.2872 -258.3942)
		(width 0.1397)
		(layer "F.Cu")
		(net "I2C_C_SDA")
	)
	(segment
		(start 32.0548 -360.3244)
		(end 31.5087 -360.8705)
		(width 0.1397)
		(layer "F.Cu")
		(net "I2C_C_SDA")
	)
	(segment
		(start 15.24 -69.9516)
		(end 15.24 -67.3227)
		(width 0.1397)
		(layer "F.Cu")
		(net "I2C_C_SDA")
	)
	(segment
		(start 35.762692 -258.800092)
		(end 36.321492 -258.800092)
		(width 0.1397)
		(layer "F.Cu")
		(net "I2C_C_SDA")
	)
	(segment
		(start 15.24 -67.3227)
		(end 14.8082 -66.8909)
		(width 0.1397)
		(layer "F.Cu")
		(net "I2C_C_SDA")
	)
	(segment
		(start 36.322 -258.8006)
		(end 37.2872 -258.8006)
		(width 0.1397)
		(layer "F.Cu")
		(net "I2C_C_SDA")
	)
	(segment
		(start 37.0332 -167.246046)
		(end 37.0332 -166.355776)
		(width 0.1397)
		(layer "F.Cu")
		(net "I2C_C_SDA")
	)
	(segment
		(start 34.442654 -359.7148)
		(end 34.2646 -359.7148)
		(width 0.1397)
		(layer "F.Cu")
		(net "I2C_C_SDA")
	)
	(segment
		(start 31.3182 -254.3429)
		(end 31.3182 -254.3556)
		(width 0.1397)
		(layer "F.Cu")
		(net "I2C_C_SDA")
	)
	(segment
		(start 36.321492 -258.800092)
		(end 36.322 -258.8006)
		(width 0.1397)
		(layer "F.Cu")
		(net "I2C_C_SDA")
	)
	(segment
		(start 15.3162 -70.0278)
		(end 15.24 -69.9516)
		(width 0.1397)
		(layer "F.Cu")
		(net "I2C_C_SDA")
	)
	(segment
		(start 34.29 -254.8255)
		(end 34.29 -255.397)
		(width 0.1397)
		(layer "F.Cu")
		(net "I2C_C_SDA")
	)
	(segment
		(start 31.3182 -254.3556)
		(end 35.762692 -258.800092)
		(width 0.1397)
		(layer "F.Cu")
		(net "I2C_C_SDA")
	)
	(segment
		(start 33.655 -360.3244)
		(end 32.0548 -360.3244)
		(width 0.1397)
		(layer "F.Cu")
		(net "I2C_C_SDA")
	)
	(segment
		(start 37.869368 -168.082214)
		(end 37.0332 -167.246046)
		(width 0.1397)
		(layer "F.Cu")
		(net "I2C_C_SDA")
	)
	(segment
		(start 37.2872 -258.3942)
		(end 37.2872 -258.8006)
		(width 0.1397)
		(layer "F.Cu")
		(net "I2C_C_SDA")
	)
	(segment
		(start 38.463728 -168.082214)
		(end 37.869368 -168.082214)
		(width 0.1397)
		(layer "F.Cu")
		(net "I2C_C_SDA")
	)
	(via
		(at 38.463728 -168.082214)
		(size 0.7112)
		(drill 0.4064)
		(layers "F.Cu" "B.Cu")
		(net "I2C_C_SDA")
	)
	(via
		(at 34.442654 -359.7148)
		(size 0.5588)
		(drill 0.3048)
		(layers "F.Cu" "B.Cu")
		(net "I2C_C_SDA")
	)
	(via
		(at 37.2872 -258.8006)
		(size 0.7112)
		(drill 0.4064)
		(layers "F.Cu" "B.Cu")
		(net "I2C_C_SDA")
	)
	(via
		(at 15.3162 -70.0278)
		(size 0.5588)
		(drill 0.3048)
		(layers "F.Cu" "B.Cu")
		(net "I2C_C_SDA")
	)
	(via
		(at 15.012416 -112.037876)
		(size 0.7112)
		(drill 0.3556)
		(layers "F.Cu" "B.Cu")
		(net "I2C_C_SDA")
	)
	(segment
		(start 40.51935 -171.541948)
		(end 38.463728 -169.486326)
		(width 0.1397)
		(layer "B.Cu")
		(net "I2C_C_SDA")
	)
	(segment
		(start 40.5003 -173.4693)
		(end 40.51935 -173.45025)
		(width 0.1397)
		(layer "B.Cu")
		(net "I2C_C_SDA")
	)
	(segment
		(start 36.50615 -260.700012)
		(end 36.506658 -260.699504)
		(width 0.1397)
		(layer "B.Cu")
		(net "I2C_C_SDA")
	)
	(segment
		(start 40.315896 -155.993592)
		(end 40.315896 -158.829502)
		(width 0.1397)
		(layer "B.Cu")
		(net "I2C_C_SDA")
	)
	(segment
		(start 40.5638 -175.9458)
		(end 40.5003 -175.8823)
		(width 0.1397)
		(layer "B.Cu")
		(net "I2C_C_SDA")
	)
	(segment
		(start 40.5003 -175.8823)
		(end 40.5003 -173.4693)
		(width 0.1397)
		(layer "B.Cu")
		(net "I2C_C_SDA")
	)
	(segment
		(start 36.500054 -273.995134)
		(end 36.500562 -273.994626)
		(width 0.1397)
		(layer "B.Cu")
		(net "I2C_C_SDA")
	)
	(segment
		(start 37.10305 -259.9944)
		(end 37.2618 -259.83565)
		(width 0.1397)
		(layer "B.Cu")
		(net "I2C_C_SDA")
	)
	(segment
		(start 36.500054 -277.113746)
		(end 36.500054 -273.995134)
		(width 0.1397)
		(layer "B.Cu")
		(net "I2C_C_SDA")
	)
	(segment
		(start 37.2618 -258.826)
		(end 37.2872 -258.8006)
		(width 0.1397)
		(layer "B.Cu")
		(net "I2C_C_SDA")
	)
	(segment
		(start 15.012416 -112.037876)
		(end 14.6812 -112.369092)
		(width 0.1397)
		(layer "B.Cu")
		(net "I2C_C_SDA")
	)
	(segment
		(start 40.5638 -185.9788)
		(end 40.5638 -175.9458)
		(width 0.1397)
		(layer "B.Cu")
		(net "I2C_C_SDA")
	)
	(segment
		(start 16.9672 -123.9266)
		(end 16.9672 -136.5758)
		(width 0.1397)
		(layer "B.Cu")
		(net "I2C_C_SDA")
	)
	(segment
		(start 40.51935 -173.45025)
		(end 40.51935 -171.541948)
		(width 0.1397)
		(layer "B.Cu")
		(net "I2C_C_SDA")
	)
	(segment
		(start 38.463728 -169.486326)
		(end 38.463728 -168.082214)
		(width 0.1397)
		(layer "B.Cu")
		(net "I2C_C_SDA")
	)
	(segment
		(start 38.9509 -167.595042)
		(end 38.463728 -168.082214)
		(width 0.1397)
		(layer "B.Cu")
		(net "I2C_C_SDA")
	)
	(segment
		(start 14.6812 -112.369092)
		(end 14.6812 -121.6406)
		(width 0.1397)
		(layer "B.Cu")
		(net "I2C_C_SDA")
	)
	(segment
		(start 15.3162 -73.2282)
		(end 13.8557 -74.6887)
		(width 0.1397)
		(layer "B.Cu")
		(net "I2C_C_SDA")
	)
	(segment
		(start 36.500562 -273.994626)
		(end 36.500562 -260.705854)
		(width 0.1397)
		(layer "B.Cu")
		(net "I2C_C_SDA")
	)
	(segment
		(start 36.50615 -260.700266)
		(end 36.50615 -260.700012)
		(width 0.1397)
		(layer "B.Cu")
		(net "I2C_C_SDA")
	)
	(segment
		(start 32.6517 -152.2603)
		(end 36.582604 -152.2603)
		(width 0.1397)
		(layer "B.Cu")
		(net "I2C_C_SDA")
	)
	(segment
		(start 36.500562 -260.705854)
		(end 36.50615 -260.700266)
		(width 0.1397)
		(layer "B.Cu")
		(net "I2C_C_SDA")
	)
	(segment
		(start 38.9509 -160.194498)
		(end 38.9509 -167.595042)
		(width 0.1397)
		(layer "B.Cu")
		(net "I2C_C_SDA")
	)
	(segment
		(start 36.506658 -260.5913)
		(end 37.10305 -259.994908)
		(width 0.1397)
		(layer "B.Cu")
		(net "I2C_C_SDA")
	)
	(segment
		(start 34.442654 -359.7148)
		(end 34.442654 -279.171146)
		(width 0.1397)
		(layer "B.Cu")
		(net "I2C_C_SDA")
	)
	(segment
		(start 13.3985 -93.87205)
		(end 13.3985 -110.1217)
		(width 0.1397)
		(layer "B.Cu")
		(net "I2C_C_SDA")
	)
	(segment
		(start 40.315896 -158.829502)
		(end 38.9509 -160.194498)
		(width 0.1397)
		(layer "B.Cu")
		(net "I2C_C_SDA")
	)
	(segment
		(start 37.2872 -258.8006)
		(end 37.2872 -258.4704)
		(width 0.1397)
		(layer "B.Cu")
		(net "I2C_C_SDA")
	)
	(segment
		(start 36.506658 -260.699504)
		(end 36.506658 -260.5913)
		(width 0.1397)
		(layer "B.Cu")
		(net "I2C_C_SDA")
	)
	(segment
		(start 37.10305 -259.994908)
		(end 37.10305 -259.9944)
		(width 0.1397)
		(layer "B.Cu")
		(net "I2C_C_SDA")
	)
	(segment
		(start 39.37 -210.4136)
		(end 39.37 -187.1726)
		(width 0.1397)
		(layer "B.Cu")
		(net "I2C_C_SDA")
	)
	(segment
		(start 13.3985 -110.1217)
		(end 15.012416 -111.735616)
		(width 0.1397)
		(layer "B.Cu")
		(net "I2C_C_SDA")
	)
	(segment
		(start 39.37 -187.1726)
		(end 40.5638 -185.9788)
		(width 0.1397)
		(layer "B.Cu")
		(net "I2C_C_SDA")
	)
	(segment
		(start 34.442654 -279.171146)
		(end 36.500054 -277.113746)
		(width 0.1397)
		(layer "B.Cu")
		(net "I2C_C_SDA")
	)
	(segment
		(start 44.1706 -251.587)
		(end 44.1706 -215.2142)
		(width 0.1397)
		(layer "B.Cu")
		(net "I2C_C_SDA")
	)
	(segment
		(start 14.6812 -121.6406)
		(end 16.9672 -123.9266)
		(width 0.1397)
		(layer "B.Cu")
		(net "I2C_C_SDA")
	)
	(segment
		(start 44.1706 -215.2142)
		(end 39.37 -210.4136)
		(width 0.1397)
		(layer "B.Cu")
		(net "I2C_C_SDA")
	)
	(segment
		(start 37.2872 -258.4704)
		(end 44.1706 -251.587)
		(width 0.1397)
		(layer "B.Cu")
		(net "I2C_C_SDA")
	)
	(segment
		(start 15.012416 -111.735616)
		(end 15.012416 -112.037876)
		(width 0.1397)
		(layer "B.Cu")
		(net "I2C_C_SDA")
	)
	(segment
		(start 13.8557 -74.6887)
		(end 13.8557 -93.41485)
		(width 0.1397)
		(layer "B.Cu")
		(net "I2C_C_SDA")
	)
	(segment
		(start 16.9672 -136.5758)
		(end 32.6517 -152.2603)
		(width 0.1397)
		(layer "B.Cu")
		(net "I2C_C_SDA")
	)
	(segment
		(start 13.8557 -93.41485)
		(end 13.3985 -93.87205)
		(width 0.1397)
		(layer "B.Cu")
		(net "I2C_C_SDA")
	)
	(segment
		(start 36.582604 -152.2603)
		(end 40.315896 -155.993592)
		(width 0.1397)
		(layer "B.Cu")
		(net "I2C_C_SDA")
	)
	(segment
		(start 15.3162 -70.0278)
		(end 15.3162 -73.2282)
		(width 0.1397)
		(layer "B.Cu")
		(net "I2C_C_SDA")
	)
	(segment
		(start 37.2618 -259.83565)
		(end 37.2618 -258.826)
		(width 0.1397)
		(layer "B.Cu")
		(net "I2C_C_SDA")
	)
	(segment
		(start 32.61233 -153.789126)
		(end 33.51149 -152.889966)
		(width 0.1397)
		(layer "F.Cu")
		(net "NCT7904_VSEN11")
	)
	(segment
		(start 32.61233 -155.607766)
		(end 32.61233 -153.789126)
		(width 0.1397)
		(layer "F.Cu")
		(net "NCT7904_VSEN11")
	)
	(segment
		(start 32.90824 -152.64003)
		(end 32.90824 -152.648666)
		(width 0.1397)
		(layer "F.Cu")
		(net "NCT7904_VSEN10")
	)
	(segment
		(start 32.11195 -153.444956)
		(end 32.11195 -155.607766)
		(width 0.1397)
		(layer "F.Cu")
		(net "NCT7904_VSEN10")
	)
	(segment
		(start 33.71469 -151.83358)
		(end 32.90824 -152.64003)
		(width 0.1397)
		(layer "F.Cu")
		(net "NCT7904_VSEN10")
	)
	(segment
		(start 33.71469 -150.730966)
		(end 33.71469 -151.83358)
		(width 0.1397)
		(layer "F.Cu")
		(net "NCT7904_VSEN10")
	)
	(segment
		(start 32.90824 -152.648666)
		(end 32.11195 -153.444956)
		(width 0.1397)
		(layer "F.Cu")
		(net "NCT7904_VSEN10")
	)
	(segment
		(start 32.766 -151.638)
		(end 32.766 -152.15362)
		(width 0.1397)
		(layer "F.Cu")
		(net "NCT7904_VSEN9")
	)
	(segment
		(start 32.46374 -152.464516)
		(end 31.61157 -153.316686)
		(width 0.1397)
		(layer "F.Cu")
		(net "NCT7904_VSEN9")
	)
	(segment
		(start 43.2308 -157.504892)
		(end 43.268646 -157.467046)
		(width 0.1397)
		(layer "F.Cu")
		(net "NCT7904_VSEN9")
	)
	(segment
		(start 32.766 -152.15362)
		(end 32.46374 -152.45588)
		(width 0.1397)
		(layer "F.Cu")
		(net "NCT7904_VSEN9")
	)
	(segment
		(start 43.2308 -158.4071)
		(end 43.2308 -157.504892)
		(width 0.1397)
		(layer "F.Cu")
		(net "NCT7904_VSEN9")
	)
	(segment
		(start 31.61157 -153.316686)
		(end 31.61157 -155.607766)
		(width 0.1397)
		(layer "F.Cu")
		(net "NCT7904_VSEN9")
	)
	(segment
		(start 32.46374 -152.45588)
		(end 32.46374 -152.464516)
		(width 0.1397)
		(layer "F.Cu")
		(net "NCT7904_VSEN9")
	)
	(via
		(at 43.268646 -157.467046)
		(size 0.7112)
		(drill 0.4064)
		(layers "F.Cu" "B.Cu")
		(net "NCT7904_VSEN9")
	)
	(via
		(at 32.766 -151.638)
		(size 0.5588)
		(drill 0.3048)
		(layers "F.Cu" "B.Cu")
		(net "NCT7904_VSEN9")
	)
	(via
		(at 34.671 -151.638)
		(size 0.7112)
		(drill 0.3556)
		(layers "F.Cu" "B.Cu")
		(net "NCT7904_VSEN9")
	)
	(segment
		(start 36.7284 -151.638)
		(end 34.671 -151.638)
		(width 0.1397)
		(layer "B.Cu")
		(net "NCT7904_VSEN9")
	)
	(segment
		(start 34.671 -151.638)
		(end 32.766 -151.638)
		(width 0.1397)
		(layer "B.Cu")
		(net "NCT7904_VSEN9")
	)
	(segment
		(start 39.2557 -152.5651)
		(end 37.6555 -152.5651)
		(width 0.1397)
		(layer "B.Cu")
		(net "NCT7904_VSEN9")
	)
	(segment
		(start 43.268646 -157.467046)
		(end 43.268646 -156.578046)
		(width 0.1397)
		(layer "B.Cu")
		(net "NCT7904_VSEN9")
	)
	(segment
		(start 43.268646 -156.578046)
		(end 39.2557 -152.5651)
		(width 0.1397)
		(layer "B.Cu")
		(net "NCT7904_VSEN9")
	)
	(segment
		(start 37.6555 -152.5651)
		(end 36.7284 -151.638)
		(width 0.1397)
		(layer "B.Cu")
		(net "NCT7904_VSEN9")
	)
	(segment
		(start 30.6832 -150.8506)
		(end 31.7246 -149.8092)
		(width 0.1397)
		(layer "F.Cu")
		(net "NCT7904_VSEN7")
	)
	(segment
		(start 30.61208 -155.607766)
		(end 30.61208 -152.14092)
		(width 0.1397)
		(layer "F.Cu")
		(net "NCT7904_VSEN7")
	)
	(segment
		(start 30.61208 -152.14092)
		(end 30.6832 -152.0698)
		(width 0.1397)
		(layer "F.Cu")
		(net "NCT7904_VSEN7")
	)
	(segment
		(start 32.738568 -149.518116)
		(end 31.7246 -149.518116)
		(width 0.1397)
		(layer "F.Cu")
		(net "NCT7904_VSEN7")
	)
	(segment
		(start 31.7246 -149.8092)
		(end 31.7246 -149.518116)
		(width 0.1397)
		(layer "F.Cu")
		(net "NCT7904_VSEN7")
	)
	(segment
		(start 30.6832 -152.0698)
		(end 30.6832 -150.8506)
		(width 0.1397)
		(layer "F.Cu")
		(net "NCT7904_VSEN7")
	)
	(segment
		(start 32.7406 -149.516084)
		(end 32.738568 -149.518116)
		(width 0.1397)
		(layer "F.Cu")
		(net "NCT7904_VSEN7")
	)
	(via
		(at 30.6832 -152.0698)
		(size 0.7112)
		(drill 0.3556)
		(layers "F.Cu" "B.Cu")
		(net "NCT7904_VSEN7")
	)
	(segment
		(start 36.258754 -160.600136)
		(end 38.18763 -158.67126)
		(width 0.1397)
		(layer "F.Cu")
		(net "NCT7904_PECI")
	)
	(segment
		(start 34.60369 -160.600136)
		(end 36.258754 -160.600136)
		(width 0.1397)
		(layer "F.Cu")
		(net "NCT7904_PECI")
	)
	(segment
		(start 39.26586 -158.67126)
		(end 39.8018 -159.2072)
		(width 0.1397)
		(layer "F.Cu")
		(net "NCT7904_PECI")
	)
	(segment
		(start 38.18763 -158.67126)
		(end 39.26586 -158.67126)
		(width 0.1397)
		(layer "F.Cu")
		(net "NCT7904_PECI")
	)
	(segment
		(start 30.8356 -357.6828)
		(end 29.2989 -357.6828)
		(width 0.1397)
		(layer "F.Cu")
		(net "TEMP_ALM#")
	)
	(segment
		(start 32.6898 -357.632)
		(end 32.290766 -357.232966)
		(width 0.1397)
		(layer "F.Cu")
		(net "TEMP_ALM#")
	)
	(segment
		(start 32.85109 -169.198544)
		(end 33.651952 -169.999406)
		(width 0.1397)
		(layer "F.Cu")
		(net "TEMP_ALM#")
	)
	(segment
		(start 29.2989 -357.4542)
		(end 29.2989 -357.6828)
		(width 0.1397)
		(layer "F.Cu")
		(net "TEMP_ALM#")
	)
	(segment
		(start 28.3464 -356.87)
		(end 28.7147 -356.87)
		(width 0.1397)
		(layer "F.Cu")
		(net "TEMP_ALM#")
	)
	(segment
		(start 39.243 -174.5615)
		(end 38.4937 -174.5615)
		(width 0.1397)
		(layer "F.Cu")
		(net "TEMP_ALM#")
	)
	(segment
		(start 23.02002 -152.91308)
		(end 23.48611 -153.37917)
		(width 0.1397)
		(layer "F.Cu")
		(net "TEMP_ALM#")
	)
	(segment
		(start 28.194 -356.7176)
		(end 28.3464 -356.87)
		(width 0.1397)
		(layer "F.Cu")
		(net "TEMP_ALM#")
	)
	(segment
		(start 28.9052 -355.5238)
		(end 28.3464 -355.5238)
		(width 0.1397)
		(layer "F.Cu")
		(net "TEMP_ALM#")
	)
	(segment
		(start 32.290766 -357.232966)
		(end 31.285434 -357.232966)
		(width 0.1397)
		(layer "F.Cu")
		(net "TEMP_ALM#")
	)
	(segment
		(start 35.252152 -169.999406)
		(end 36.232592 -169.018966)
		(width 0.1397)
		(layer "F.Cu")
		(net "TEMP_ALM#")
	)
	(segment
		(start 28.3464 -355.5238)
		(end 28.194 -355.6762)
		(width 0.1397)
		(layer "F.Cu")
		(net "TEMP_ALM#")
	)
	(segment
		(start 31.285434 -357.232966)
		(end 30.8356 -357.6828)
		(width 0.1397)
		(layer "F.Cu")
		(net "TEMP_ALM#")
	)
	(segment
		(start 38.7858 -157.1498)
		(end 39.567866 -156.367734)
		(width 0.1397)
		(layer "F.Cu")
		(net "TEMP_ALM#")
	)
	(segment
		(start 38.7858 -157.175962)
		(end 38.7858 -157.1498)
		(width 0.1397)
		(layer "F.Cu")
		(net "TEMP_ALM#")
	)
	(segment
		(start 38.4937 -174.5615)
		(end 38.36035 -174.69485)
		(width 0.1397)
		(layer "F.Cu")
		(net "TEMP_ALM#")
	)
	(segment
		(start 23.48611 -153.37917)
		(end 23.48611 -154.157934)
		(width 0.1397)
		(layer "F.Cu")
		(net "TEMP_ALM#")
	)
	(segment
		(start 38.36035 -174.69485)
		(end 38.348412 -174.69485)
		(width 0.1397)
		(layer "F.Cu")
		(net "TEMP_ALM#")
	)
	(segment
		(start 39.567866 -156.367734)
		(end 39.567866 -156.22651)
		(width 0.1397)
		(layer "F.Cu")
		(net "TEMP_ALM#")
	)
	(segment
		(start 33.651952 -169.999406)
		(end 35.252152 -169.999406)
		(width 0.1397)
		(layer "F.Cu")
		(net "TEMP_ALM#")
	)
	(segment
		(start 28.194 -355.6762)
		(end 28.194 -356.7176)
		(width 0.1397)
		(layer "F.Cu")
		(net "TEMP_ALM#")
	)
	(segment
		(start 28.7147 -356.87)
		(end 29.2989 -357.4542)
		(width 0.1397)
		(layer "F.Cu")
		(net "TEMP_ALM#")
	)
	(segment
		(start 32.85109 -168.168066)
		(end 32.85109 -169.198544)
		(width 0.1397)
		(layer "F.Cu")
		(net "TEMP_ALM#")
	)
	(via
		(at 37.084 -162.9156)
		(size 0.7112)
		(drill 0.3556)
		(layers "F.Cu" "B.Cu")
		(net "TEMP_ALM#")
	)
	(via
		(at 23.02002 -152.91308)
		(size 0.7112)
		(drill 0.4064)
		(layers "F.Cu" "B.Cu")
		(net "TEMP_ALM#")
	)
	(via
		(at 32.6898 -357.632)
		(size 0.5588)
		(drill 0.3048)
		(layers "F.Cu" "B.Cu")
		(net "TEMP_ALM#")
	)
	(via
		(at 36.232592 -169.018966)
		(size 0.5588)
		(drill 0.3048)
		(layers "F.Cu" "B.Cu")
		(net "TEMP_ALM#")
	)
	(via
		(at 38.348412 -174.69485)
		(size 0.5588)
		(drill 0.3048)
		(layers "F.Cu" "B.Cu")
		(net "TEMP_ALM#")
	)
	(via
		(at 38.7858 -157.175962)
		(size 0.7112)
		(drill 0.4064)
		(layers "F.Cu" "B.Cu")
		(net "TEMP_ALM#")
	)
	(segment
		(start 35.3695 -257.0607)
		(end 40.9194 -251.5108)
		(width 0.1397)
		(layer "B.Cu")
		(net "TEMP_ALM#")
	)
	(segment
		(start 37.084 -168.167558)
		(end 37.084 -162.9156)
		(width 0.1397)
		(layer "B.Cu")
		(net "TEMP_ALM#")
	)
	(segment
		(start 37.80155 -177.50155)
		(end 37.80155 -175.25365)
		(width 0.1397)
		(layer "B.Cu")
		(net "TEMP_ALM#")
	)
	(segment
		(start 42.5577 -215.89365)
		(end 37.7571 -211.09305)
		(width 0.1397)
		(layer "B.Cu")
		(net "TEMP_ALM#")
	)
	(segment
		(start 38.34765 -174.695612)
		(end 38.348412 -174.69485)
		(width 0.1397)
		(layer "B.Cu")
		(net "TEMP_ALM#")
	)
	(segment
		(start 35.751262 -157.175962)
		(end 38.7858 -157.175962)
		(width 0.1397)
		(layer "B.Cu")
		(net "TEMP_ALM#")
	)
	(segment
		(start 34.899854 -276.123146)
		(end 34.899854 -274.226782)
		(width 0.1397)
		(layer "B.Cu")
		(net "TEMP_ALM#")
	)
	(segment
		(start 40.9194 -251.5108)
		(end 41.953942 -251.5108)
		(width 0.1397)
		(layer "B.Cu")
		(net "TEMP_ALM#")
	)
	(segment
		(start 34.8996 -274.226528)
		(end 34.8996 -273.33194)
		(width 0.1397)
		(layer "B.Cu")
		(net "TEMP_ALM#")
	)
	(segment
		(start 23.02002 -152.91308)
		(end 24.79675 -151.13635)
		(width 0.1397)
		(layer "B.Cu")
		(net "TEMP_ALM#")
	)
	(segment
		(start 32.6898 -278.3332)
		(end 34.899854 -276.123146)
		(width 0.1397)
		(layer "B.Cu")
		(net "TEMP_ALM#")
	)
	(segment
		(start 35.3695 -259.2832)
		(end 35.3695 -257.0607)
		(width 0.1397)
		(layer "B.Cu")
		(net "TEMP_ALM#")
	)
	(segment
		(start 37.80155 -175.25365)
		(end 38.34765 -174.70755)
		(width 0.1397)
		(layer "B.Cu")
		(net "TEMP_ALM#")
	)
	(segment
		(start 37.084 -159.5628)
		(end 37.084 -162.9156)
		(width 0.1397)
		(layer "B.Cu")
		(net "TEMP_ALM#")
	)
	(segment
		(start 37.815266 -186.441334)
		(end 37.815266 -177.515266)
		(width 0.1397)
		(layer "B.Cu")
		(net "TEMP_ALM#")
	)
	(segment
		(start 29.71165 -151.13635)
		(end 35.751262 -157.175962)
		(width 0.1397)
		(layer "B.Cu")
		(net "TEMP_ALM#")
	)
	(segment
		(start 38.7858 -157.861)
		(end 37.084 -159.5628)
		(width 0.1397)
		(layer "B.Cu")
		(net "TEMP_ALM#")
	)
	(segment
		(start 38.7858 -157.175962)
		(end 38.7858 -157.861)
		(width 0.1397)
		(layer "B.Cu")
		(net "TEMP_ALM#")
	)
	(segment
		(start 38.34765 -174.70755)
		(end 38.34765 -174.695612)
		(width 0.1397)
		(layer "B.Cu")
		(net "TEMP_ALM#")
	)
	(segment
		(start 34.899854 -273.331686)
		(end 34.899854 -259.752846)
		(width 0.1397)
		(layer "B.Cu")
		(net "TEMP_ALM#")
	)
	(segment
		(start 37.7571 -186.4995)
		(end 37.815266 -186.441334)
		(width 0.1397)
		(layer "B.Cu")
		(net "TEMP_ALM#")
	)
	(segment
		(start 32.6898 -357.632)
		(end 32.6898 -278.3332)
		(width 0.1397)
		(layer "B.Cu")
		(net "TEMP_ALM#")
	)
	(segment
		(start 38.348412 -174.69485)
		(end 38.354 -174.689262)
		(width 0.1397)
		(layer "B.Cu")
		(net "TEMP_ALM#")
	)
	(segment
		(start 42.5577 -250.907042)
		(end 42.5577 -215.89365)
		(width 0.1397)
		(layer "B.Cu")
		(net "TEMP_ALM#")
	)
	(segment
		(start 37.7571 -211.09305)
		(end 37.7571 -186.4995)
		(width 0.1397)
		(layer "B.Cu")
		(net "TEMP_ALM#")
	)
	(segment
		(start 36.232592 -169.018966)
		(end 37.084 -168.167558)
		(width 0.1397)
		(layer "B.Cu")
		(net "TEMP_ALM#")
	)
	(segment
		(start 34.899854 -259.752846)
		(end 35.3695 -259.2832)
		(width 0.1397)
		(layer "B.Cu")
		(net "TEMP_ALM#")
	)
	(segment
		(start 34.899854 -274.226782)
		(end 34.8996 -274.226528)
		(width 0.1397)
		(layer "B.Cu")
		(net "TEMP_ALM#")
	)
	(segment
		(start 24.79675 -151.13635)
		(end 29.71165 -151.13635)
		(width 0.1397)
		(layer "B.Cu")
		(net "TEMP_ALM#")
	)
	(segment
		(start 41.953942 -251.5108)
		(end 42.5577 -250.907042)
		(width 0.1397)
		(layer "B.Cu")
		(net "TEMP_ALM#")
	)
	(segment
		(start 38.354 -171.140374)
		(end 36.232592 -169.018966)
		(width 0.1397)
		(layer "B.Cu")
		(net "TEMP_ALM#")
	)
	(segment
		(start 38.354 -174.689262)
		(end 38.354 -171.140374)
		(width 0.1397)
		(layer "B.Cu")
		(net "TEMP_ALM#")
	)
	(segment
		(start 37.815266 -177.515266)
		(end 37.80155 -177.50155)
		(width 0.1397)
		(layer "B.Cu")
		(net "TEMP_ALM#")
	)
	(segment
		(start 34.8996 -273.33194)
		(end 34.899854 -273.331686)
		(width 0.1397)
		(layer "B.Cu")
		(net "TEMP_ALM#")
	)
	(segment
		(start 19.6088 -178.4223)
		(end 20.8153 -178.4223)
		(width 0.1397)
		(layer "F.Cu")
		(net "FANIN_7")
	)
	(segment
		(start 19.195034 -175.893984)
		(end 19.195034 -175.902366)
		(width 0.1397)
		(layer "F.Cu")
		(net "FANIN_7")
	)
	(segment
		(start 19.195034 -175.902366)
		(end 19.05 -176.0474)
		(width 0.1397)
		(layer "F.Cu")
		(net "FANIN_7")
	)
	(segment
		(start 19.05 -176.0474)
		(end 19.05 -177.8635)
		(width 0.1397)
		(layer "F.Cu")
		(net "FANIN_7")
	)
	(segment
		(start 23.031196 -168.495218)
		(end 23.031196 -168.394126)
		(width 0.1397)
		(layer "F.Cu")
		(net "FANIN_7")
	)
	(segment
		(start 23.2918 -167.157654)
		(end 26.12009 -164.329364)
		(width 0.1397)
		(layer "F.Cu")
		(net "FANIN_7")
	)
	(segment
		(start 20.8153 -178.4223)
		(end 20.828 -178.4096)
		(width 0.1397)
		(layer "F.Cu")
		(net "FANIN_7")
	)
	(segment
		(start 26.12009 -164.329364)
		(end 26.12009 -162.599116)
		(width 0.1397)
		(layer "F.Cu")
		(net "FANIN_7")
	)
	(segment
		(start 23.031196 -168.394126)
		(end 23.2918 -168.133522)
		(width 0.1397)
		(layer "F.Cu")
		(net "FANIN_7")
	)
	(segment
		(start 23.2918 -168.133522)
		(end 23.2918 -167.157654)
		(width 0.1397)
		(layer "F.Cu")
		(net "FANIN_7")
	)
	(segment
		(start 19.05 -177.8635)
		(end 19.6088 -178.4223)
		(width 0.1397)
		(layer "F.Cu")
		(net "FANIN_7")
	)
	(via
		(at 19.195034 -175.893984)
		(size 0.5588)
		(drill 0.3048)
		(layers "F.Cu" "B.Cu")
		(net "FANIN_7")
	)
	(via
		(at 21.336 -171.196)
		(size 0.7112)
		(drill 0.3556)
		(layers "F.Cu" "B.Cu")
		(net "FANIN_7")
	)
	(via
		(at 23.031196 -168.495218)
		(size 0.7112)
		(drill 0.4064)
		(layers "F.Cu" "B.Cu")
		(net "FANIN_7")
	)
	(segment
		(start 21.336 -170.7896)
		(end 23.031196 -169.094404)
		(width 0.1397)
		(layer "B.Cu")
		(net "FANIN_7")
	)
	(segment
		(start 23.031196 -169.094404)
		(end 23.031196 -168.495218)
		(width 0.1397)
		(layer "B.Cu")
		(net "FANIN_7")
	)
	(segment
		(start 18.85315 -174.173642)
		(end 18.85315 -175.5521)
		(width 0.1397)
		(layer "B.Cu")
		(net "FANIN_7")
	)
	(segment
		(start 20.8153 -172.211492)
		(end 18.85315 -174.173642)
		(width 0.1397)
		(layer "B.Cu")
		(net "FANIN_7")
	)
	(segment
		(start 21.336 -171.196)
		(end 20.8153 -171.7167)
		(width 0.1397)
		(layer "B.Cu")
		(net "FANIN_7")
	)
	(segment
		(start 21.336 -171.196)
		(end 21.336 -170.7896)
		(width 0.1397)
		(layer "B.Cu")
		(net "FANIN_7")
	)
	(segment
		(start 20.8153 -171.7167)
		(end 20.8153 -172.211492)
		(width 0.1397)
		(layer "B.Cu")
		(net "FANIN_7")
	)
	(segment
		(start 18.85315 -175.5521)
		(end 19.195034 -175.893984)
		(width 0.1397)
		(layer "B.Cu")
		(net "FANIN_7")
	)
	(segment
		(start 26.12009 -161.099246)
		(end 24.974804 -161.099246)
		(width 0.1397)
		(layer "F.Cu")
		(net "FANIN_6")
	)
	(segment
		(start 13.716 -260.35)
		(end 13.589 -260.477)
		(width 0.1397)
		(layer "F.Cu")
		(net "FANIN_6")
	)
	(segment
		(start 15.6972 -259.5499)
		(end 16.0147 -259.2324)
		(width 0.1397)
		(layer "F.Cu")
		(net "FANIN_6")
	)
	(segment
		(start 15.6972 -260.35)
		(end 15.6972 -259.5499)
		(width 0.1397)
		(layer "F.Cu")
		(net "FANIN_6")
	)
	(segment
		(start 15.6972 -260.35)
		(end 13.716 -260.35)
		(width 0.1397)
		(layer "F.Cu")
		(net "FANIN_6")
	)
	(segment
		(start 21.404072 -167.159432)
		(end 21.404072 -169.054272)
		(width 0.1397)
		(layer "F.Cu")
		(net "FANIN_6")
	)
	(segment
		(start 24.009604 -164.5539)
		(end 24.00935 -164.5539)
		(width 0.1397)
		(layer "F.Cu")
		(net "FANIN_6")
	)
	(segment
		(start 24.2697 -161.80435)
		(end 24.2697 -164.293804)
		(width 0.1397)
		(layer "F.Cu")
		(net "FANIN_6")
	)
	(segment
		(start 24.2697 -164.293804)
		(end 24.009604 -164.5539)
		(width 0.1397)
		(layer "F.Cu")
		(net "FANIN_6")
	)
	(segment
		(start 21.404072 -169.054272)
		(end 21.464016 -169.114216)
		(width 0.1397)
		(layer "F.Cu")
		(net "FANIN_6")
	)
	(segment
		(start 24.974804 -161.099246)
		(end 24.2697 -161.80435)
		(width 0.1397)
		(layer "F.Cu")
		(net "FANIN_6")
	)
	(segment
		(start 23.3045 -165.259004)
		(end 21.404072 -167.159432)
		(width 0.1397)
		(layer "F.Cu")
		(net "FANIN_6")
	)
	(segment
		(start 21.464016 -169.114216)
		(end 21.464016 -169.253662)
		(width 0.1397)
		(layer "F.Cu")
		(net "FANIN_6")
	)
	(segment
		(start 23.3045 -165.25875)
		(end 23.3045 -165.259004)
		(width 0.1397)
		(layer "F.Cu")
		(net "FANIN_6")
	)
	(segment
		(start 24.00935 -164.5539)
		(end 23.3045 -165.25875)
		(width 0.1397)
		(layer "F.Cu")
		(net "FANIN_6")
	)
	(via
		(at 17.018 -230.4542)
		(size 0.7112)
		(drill 0.3556)
		(layers "F.Cu" "B.Cu")
		(net "FANIN_6")
	)
	(via
		(at 13.589 -260.477)
		(size 0.5588)
		(drill 0.3048)
		(layers "F.Cu" "B.Cu")
		(net "FANIN_6")
	)
	(via
		(at 21.464016 -169.253662)
		(size 0.7112)
		(drill 0.4064)
		(layers "F.Cu" "B.Cu")
		(net "FANIN_6")
	)
	(segment
		(start 17.018 -257.340608)
		(end 13.881608 -260.477)
		(width 0.1397)
		(layer "B.Cu")
		(net "FANIN_6")
	)
	(segment
		(start 17.46885 -193.70675)
		(end 17.46885 -209.44205)
		(width 0.1397)
		(layer "B.Cu")
		(net "FANIN_6")
	)
	(segment
		(start 19.1135 -171.2595)
		(end 19.1135 -172.655992)
		(width 0.1397)
		(layer "B.Cu")
		(net "FANIN_6")
	)
	(segment
		(start 19.99615 -170.37685)
		(end 19.1135 -171.2595)
		(width 0.1397)
		(layer "B.Cu")
		(net "FANIN_6")
	)
	(segment
		(start 19.58975 -191.58585)
		(end 17.46885 -193.70675)
		(width 0.1397)
		(layer "B.Cu")
		(net "FANIN_6")
	)
	(segment
		(start 19.58975 -177.591212)
		(end 19.58975 -191.58585)
		(width 0.1397)
		(layer "B.Cu")
		(net "FANIN_6")
	)
	(segment
		(start 17.96415 -175.965612)
		(end 19.58975 -177.591212)
		(width 0.1397)
		(layer "B.Cu")
		(net "FANIN_6")
	)
	(segment
		(start 20.319746 -169.22115)
		(end 19.99615 -169.544746)
		(width 0.1397)
		(layer "B.Cu")
		(net "FANIN_6")
	)
	(segment
		(start 19.1135 -172.655992)
		(end 17.96415 -173.805342)
		(width 0.1397)
		(layer "B.Cu")
		(net "FANIN_6")
	)
	(segment
		(start 17.96415 -173.805342)
		(end 17.96415 -175.965612)
		(width 0.1397)
		(layer "B.Cu")
		(net "FANIN_6")
	)
	(segment
		(start 19.99615 -169.544746)
		(end 19.99615 -170.37685)
		(width 0.1397)
		(layer "B.Cu")
		(net "FANIN_6")
	)
	(segment
		(start 18.01495 -209.98815)
		(end 18.01495 -229.45725)
		(width 0.1397)
		(layer "B.Cu")
		(net "FANIN_6")
	)
	(segment
		(start 13.881608 -260.477)
		(end 13.589 -260.477)
		(width 0.1397)
		(layer "B.Cu")
		(net "FANIN_6")
	)
	(segment
		(start 17.46885 -209.44205)
		(end 18.01495 -209.98815)
		(width 0.1397)
		(layer "B.Cu")
		(net "FANIN_6")
	)
	(segment
		(start 21.431504 -169.22115)
		(end 20.319746 -169.22115)
		(width 0.1397)
		(layer "B.Cu")
		(net "FANIN_6")
	)
	(segment
		(start 18.01495 -229.45725)
		(end 17.018 -230.4542)
		(width 0.1397)
		(layer "B.Cu")
		(net "FANIN_6")
	)
	(segment
		(start 17.018 -230.4542)
		(end 17.018 -257.340608)
		(width 0.1397)
		(layer "B.Cu")
		(net "FANIN_6")
	)
	(segment
		(start 21.464016 -169.253662)
		(end 21.431504 -169.22115)
		(width 0.1397)
		(layer "B.Cu")
		(net "FANIN_6")
	)
	(segment
		(start 25.29586 -162.100006)
		(end 25.1587 -162.237166)
		(width 0.1397)
		(layer "F.Cu")
		(net "FANIN_8")
	)
	(segment
		(start 26.12009 -162.100006)
		(end 25.29586 -162.100006)
		(width 0.1397)
		(layer "F.Cu")
		(net "FANIN_8")
	)
	(segment
		(start 20.6883 -184.7469)
		(end 20.701 -184.7596)
		(width 0.1397)
		(layer "F.Cu")
		(net "FANIN_8")
	)
	(segment
		(start 22.597618 -167.223186)
		(end 22.597618 -167.576246)
		(width 0.1397)
		(layer "F.Cu")
		(net "FANIN_8")
	)
	(segment
		(start 18.7071 -184.7469)
		(end 18.542 -184.912)
		(width 0.1397)
		(layer "F.Cu")
		(net "FANIN_8")
	)
	(segment
		(start 19.558 -184.7469)
		(end 20.6883 -184.7469)
		(width 0.1397)
		(layer "F.Cu")
		(net "FANIN_8")
	)
	(segment
		(start 19.558 -184.7469)
		(end 18.7071 -184.7469)
		(width 0.1397)
		(layer "F.Cu")
		(net "FANIN_8")
	)
	(segment
		(start 25.1587 -162.237166)
		(end 25.1587 -164.662104)
		(width 0.1397)
		(layer "F.Cu")
		(net "FANIN_8")
	)
	(segment
		(start 25.1587 -164.662104)
		(end 22.597618 -167.223186)
		(width 0.1397)
		(layer "F.Cu")
		(net "FANIN_8")
	)
	(via
		(at 21.3106 -167.576246)
		(size 0.7112)
		(drill 0.3556)
		(layers "F.Cu" "B.Cu")
		(net "FANIN_8")
	)
	(via
		(at 18.542 -184.912)
		(size 0.5588)
		(drill 0.3048)
		(layers "F.Cu" "B.Cu")
		(net "FANIN_8")
	)
	(via
		(at 22.597618 -167.576246)
		(size 0.7112)
		(drill 0.4064)
		(layers "F.Cu" "B.Cu")
		(net "FANIN_8")
	)
	(segment
		(start 18.542 -184.7596)
		(end 16.99895 -183.21655)
		(width 0.1397)
		(layer "B.Cu")
		(net "FANIN_8")
	)
	(segment
		(start 16.99895 -183.21655)
		(end 16.99895 -173.5074)
		(width 0.1397)
		(layer "B.Cu")
		(net "FANIN_8")
	)
	(segment
		(start 18.0975 -169.969688)
		(end 20.490942 -167.576246)
		(width 0.1397)
		(layer "B.Cu")
		(net "FANIN_8")
	)
	(segment
		(start 18.542 -184.912)
		(end 18.542 -184.7596)
		(width 0.1397)
		(layer "B.Cu")
		(net "FANIN_8")
	)
	(segment
		(start 16.99895 -173.5074)
		(end 18.0975 -172.40885)
		(width 0.1397)
		(layer "B.Cu")
		(net "FANIN_8")
	)
	(segment
		(start 22.597618 -167.576246)
		(end 21.3106 -167.576246)
		(width 0.1397)
		(layer "B.Cu")
		(net "FANIN_8")
	)
	(segment
		(start 18.0975 -172.40885)
		(end 18.0975 -169.969688)
		(width 0.1397)
		(layer "B.Cu")
		(net "FANIN_8")
	)
	(segment
		(start 20.490942 -167.576246)
		(end 21.3106 -167.576246)
		(width 0.1397)
		(layer "B.Cu")
		(net "FANIN_8")
	)
	(segment
		(start 15.8496 -253.111)
		(end 16.3068 -253.5682)
		(width 0.1397)
		(layer "F.Cu")
		(net "FANIN_5")
	)
	(segment
		(start 21.956522 -167.235632)
		(end 21.956522 -168.364662)
		(width 0.1397)
		(layer "F.Cu")
		(net "FANIN_5")
	)
	(segment
		(start 25.16759 -161.599626)
		(end 24.7142 -162.053016)
		(width 0.1397)
		(layer "F.Cu")
		(net "FANIN_5")
	)
	(segment
		(start 26.12009 -161.599626)
		(end 25.16759 -161.599626)
		(width 0.1397)
		(layer "F.Cu")
		(net "FANIN_5")
	)
	(segment
		(start 24.7142 -162.053016)
		(end 24.7142 -164.477954)
		(width 0.1397)
		(layer "F.Cu")
		(net "FANIN_5")
	)
	(segment
		(start 24.7142 -164.477954)
		(end 21.956522 -167.235632)
		(width 0.1397)
		(layer "F.Cu")
		(net "FANIN_5")
	)
	(segment
		(start 17.4371 -253.9492)
		(end 16.6878 -253.9492)
		(width 0.1397)
		(layer "F.Cu")
		(net "FANIN_5")
	)
	(segment
		(start 13.716 -253.111)
		(end 15.8496 -253.111)
		(width 0.1397)
		(layer "F.Cu")
		(net "FANIN_5")
	)
	(segment
		(start 16.6878 -253.9492)
		(end 16.3068 -253.5682)
		(width 0.1397)
		(layer "F.Cu")
		(net "FANIN_5")
	)
	(via
		(at 13.7668 -235.3818)
		(size 0.7112)
		(drill 0.3556)
		(layers "F.Cu" "B.Cu")
		(net "FANIN_5")
	)
	(via
		(at 13.716 -253.111)
		(size 0.5588)
		(drill 0.3048)
		(layers "F.Cu" "B.Cu")
		(net "FANIN_5")
	)
	(via
		(at 21.956522 -168.364662)
		(size 0.7112)
		(drill 0.4064)
		(layers "F.Cu" "B.Cu")
		(net "FANIN_5")
	)
	(segment
		(start 16.2052 -232.9434)
		(end 13.7668 -235.3818)
		(width 0.1397)
		(layer "B.Cu")
		(net "FANIN_5")
	)
	(segment
		(start 21.919184 -168.402)
		(end 20.510246 -168.402)
		(width 0.1397)
		(layer "B.Cu")
		(net "FANIN_5")
	)
	(segment
		(start 17.51965 -176.149762)
		(end 19.14525 -177.775362)
		(width 0.1397)
		(layer "B.Cu")
		(net "FANIN_5")
	)
	(segment
		(start 13.462 -235.6866)
		(end 13.7668 -235.3818)
		(width 0.1397)
		(layer "B.Cu")
		(net "FANIN_5")
	)
	(segment
		(start 13.462 -252.857)
		(end 13.462 -235.6866)
		(width 0.1397)
		(layer "B.Cu")
		(net "FANIN_5")
	)
	(segment
		(start 19.5453 -169.366946)
		(end 19.5453 -170.1673)
		(width 0.1397)
		(layer "B.Cu")
		(net "FANIN_5")
	)
	(segment
		(start 17.02435 -209.88655)
		(end 17.57045 -210.43265)
		(width 0.1397)
		(layer "B.Cu")
		(net "FANIN_5")
	)
	(segment
		(start 17.57045 -210.43265)
		(end 17.57045 -228.91115)
		(width 0.1397)
		(layer "B.Cu")
		(net "FANIN_5")
	)
	(segment
		(start 13.716 -253.111)
		(end 13.462 -252.857)
		(width 0.1397)
		(layer "B.Cu")
		(net "FANIN_5")
	)
	(segment
		(start 19.5453 -170.1673)
		(end 18.669 -171.0436)
		(width 0.1397)
		(layer "B.Cu")
		(net "FANIN_5")
	)
	(segment
		(start 18.669 -171.0436)
		(end 18.669 -172.466)
		(width 0.1397)
		(layer "B.Cu")
		(net "FANIN_5")
	)
	(segment
		(start 17.57045 -228.91115)
		(end 16.2052 -230.2764)
		(width 0.1397)
		(layer "B.Cu")
		(net "FANIN_5")
	)
	(segment
		(start 19.14525 -177.775362)
		(end 19.14525 -191.38265)
		(width 0.1397)
		(layer "B.Cu")
		(net "FANIN_5")
	)
	(segment
		(start 16.2052 -230.2764)
		(end 16.2052 -232.9434)
		(width 0.1397)
		(layer "B.Cu")
		(net "FANIN_5")
	)
	(segment
		(start 17.51965 -173.61535)
		(end 17.51965 -176.149762)
		(width 0.1397)
		(layer "B.Cu")
		(net "FANIN_5")
	)
	(segment
		(start 20.510246 -168.402)
		(end 19.5453 -169.366946)
		(width 0.1397)
		(layer "B.Cu")
		(net "FANIN_5")
	)
	(segment
		(start 17.02435 -193.50355)
		(end 17.02435 -209.88655)
		(width 0.1397)
		(layer "B.Cu")
		(net "FANIN_5")
	)
	(segment
		(start 18.669 -172.466)
		(end 17.51965 -173.61535)
		(width 0.1397)
		(layer "B.Cu")
		(net "FANIN_5")
	)
	(segment
		(start 19.14525 -191.38265)
		(end 17.02435 -193.50355)
		(width 0.1397)
		(layer "B.Cu")
		(net "FANIN_5")
	)
	(segment
		(start 21.956522 -168.364662)
		(end 21.919184 -168.402)
		(width 0.1397)
		(layer "B.Cu")
		(net "FANIN_5")
	)
	(segment
		(start 27.553666 -160.099756)
		(end 26.12009 -160.099756)
		(width 0.1397)
		(layer "F.Cu")
		(net "FANIN_4")
	)
	(segment
		(start 31.877 -160.4772)
		(end 27.93111 -160.4772)
		(width 0.1397)
		(layer "F.Cu")
		(net "FANIN_4")
	)
	(segment
		(start 19.560032 -289.040062)
		(end 19.558508 -289.038538)
		(width 0.1397)
		(layer "F.Cu")
		(net "FANIN_4")
	)
	(segment
		(start 33.30829 -162.446716)
		(end 33.30829 -161.90849)
		(width 0.1397)
		(layer "F.Cu")
		(net "FANIN_4")
	)
	(segment
		(start 27.93111 -160.4772)
		(end 27.553666 -160.099756)
		(width 0.1397)
		(layer "F.Cu")
		(net "FANIN_4")
	)
	(segment
		(start 19.258026 -289.33902)
		(end 19.558508 -289.038538)
		(width 0.1397)
		(layer "F.Cu")
		(net "FANIN_4")
	)
	(segment
		(start 19.802094 -291.602414)
		(end 19.258026 -291.058346)
		(width 0.1397)
		(layer "F.Cu")
		(net "FANIN_4")
	)
	(segment
		(start 19.258026 -291.058346)
		(end 19.258026 -289.33902)
		(width 0.1397)
		(layer "F.Cu")
		(net "FANIN_4")
	)
	(segment
		(start 20.675092 -289.040062)
		(end 19.560032 -289.040062)
		(width 0.1397)
		(layer "F.Cu")
		(net "FANIN_4")
	)
	(segment
		(start 33.30829 -161.90849)
		(end 31.877 -160.4772)
		(width 0.1397)
		(layer "F.Cu")
		(net "FANIN_4")
	)
	(segment
		(start 19.886168 -291.602414)
		(end 19.802094 -291.602414)
		(width 0.1397)
		(layer "F.Cu")
		(net "FANIN_4")
	)
	(via
		(at 33.55594 -172.301662)
		(size 0.7112)
		(drill 0.3556)
		(layers "F.Cu" "B.Cu")
		(net "FANIN_4")
	)
	(via
		(at 19.886168 -291.602414)
		(size 0.7112)
		(drill 0.4064)
		(layers "F.Cu" "B.Cu")
		(net "FANIN_4")
	)
	(via
		(at 33.30829 -162.446716)
		(size 0.5588)
		(drill 0.3048)
		(layers "F.Cu" "B.Cu")
		(net "FANIN_4")
	)
	(segment
		(start 38.89375 -250.05665)
		(end 38.89375 -244.82425)
		(width 0.1397)
		(layer "B.Cu")
		(net "FANIN_4")
	)
	(segment
		(start 19.886168 -291.602414)
		(end 21.463 -290.025582)
		(width 0.1397)
		(layer "B.Cu")
		(net "FANIN_4")
	)
	(segment
		(start 32.677354 -272.410936)
		(end 32.677354 -258.432046)
		(width 0.1397)
		(layer "B.Cu")
		(net "FANIN_4")
	)
	(segment
		(start 38.89375 -244.82425)
		(end 39.751 -243.967)
		(width 0.1397)
		(layer "B.Cu")
		(net "FANIN_4")
	)
	(segment
		(start 34.37255 -173.118272)
		(end 33.55594 -172.301662)
		(width 0.1397)
		(layer "B.Cu")
		(net "FANIN_4")
	)
	(segment
		(start 33.30829 -162.446716)
		(end 34.25825 -163.396676)
		(width 0.1397)
		(layer "B.Cu")
		(net "FANIN_4")
	)
	(segment
		(start 32.893 -258.2164)
		(end 32.893 -256.0574)
		(width 0.1397)
		(layer "B.Cu")
		(net "FANIN_4")
	)
	(segment
		(start 32.6771 -274.7899)
		(end 32.6771 -272.41119)
		(width 0.1397)
		(layer "B.Cu")
		(net "FANIN_4")
	)
	(segment
		(start 33.247076 -168.555924)
		(end 33.247076 -171.981876)
		(width 0.1397)
		(layer "B.Cu")
		(net "FANIN_4")
	)
	(segment
		(start 39.751 -240.557558)
		(end 38.43655 -239.243108)
		(width 0.1397)
		(layer "B.Cu")
		(net "FANIN_4")
	)
	(segment
		(start 34.25825 -163.396676)
		(end 34.25825 -167.54475)
		(width 0.1397)
		(layer "B.Cu")
		(net "FANIN_4")
	)
	(segment
		(start 21.463 -290.025582)
		(end 21.463 -286.004)
		(width 0.1397)
		(layer "B.Cu")
		(net "FANIN_4")
	)
	(segment
		(start 32.893 -256.0574)
		(end 38.89375 -250.05665)
		(width 0.1397)
		(layer "B.Cu")
		(net "FANIN_4")
	)
	(segment
		(start 33.55594 -172.29074)
		(end 33.55594 -172.301662)
		(width 0.1397)
		(layer "B.Cu")
		(net "FANIN_4")
	)
	(segment
		(start 34.25825 -167.54475)
		(end 33.247076 -168.555924)
		(width 0.1397)
		(layer "B.Cu")
		(net "FANIN_4")
	)
	(segment
		(start 32.6771 -272.41119)
		(end 32.677354 -272.410936)
		(width 0.1397)
		(layer "B.Cu")
		(net "FANIN_4")
	)
	(segment
		(start 34.37255 -210.90255)
		(end 34.37255 -173.118272)
		(width 0.1397)
		(layer "B.Cu")
		(net "FANIN_4")
	)
	(segment
		(start 39.751 -243.967)
		(end 39.751 -240.557558)
		(width 0.1397)
		(layer "B.Cu")
		(net "FANIN_4")
	)
	(segment
		(start 33.247076 -171.981876)
		(end 33.55594 -172.29074)
		(width 0.1397)
		(layer "B.Cu")
		(net "FANIN_4")
	)
	(segment
		(start 21.463 -286.004)
		(end 32.6771 -274.7899)
		(width 0.1397)
		(layer "B.Cu")
		(net "FANIN_4")
	)
	(segment
		(start 38.43655 -239.243108)
		(end 38.43655 -214.96655)
		(width 0.1397)
		(layer "B.Cu")
		(net "FANIN_4")
	)
	(segment
		(start 38.43655 -214.96655)
		(end 34.37255 -210.90255)
		(width 0.1397)
		(layer "B.Cu")
		(net "FANIN_4")
	)
	(segment
		(start 32.677354 -258.432046)
		(end 32.893 -258.2164)
		(width 0.1397)
		(layer "B.Cu")
		(net "FANIN_4")
	)
	(segment
		(start 17.094708 -287.90646)
		(end 17.094708 -288.746692)
		(width 0.1397)
		(layer "F.Cu")
		(net "FANIN_3")
	)
	(segment
		(start 16.052292 -289.192462)
		(end 16.053308 -289.191446)
		(width 0.1397)
		(layer "F.Cu")
		(net "FANIN_3")
	)
	(segment
		(start 16.053308 -289.191446)
		(end 16.053308 -288.073338)
		(width 0.1397)
		(layer "F.Cu")
		(net "FANIN_3")
	)
	(segment
		(start 17.094708 -288.746692)
		(end 16.648938 -289.192462)
		(width 0.1397)
		(layer "F.Cu")
		(net "FANIN_3")
	)
	(segment
		(start 23.8252 -161.6202)
		(end 23.8252 -164.1094)
		(width 0.1397)
		(layer "F.Cu")
		(net "FANIN_3")
	)
	(segment
		(start 16.648938 -289.192462)
		(end 16.052292 -289.192462)
		(width 0.1397)
		(layer "F.Cu")
		(net "FANIN_3")
	)
	(segment
		(start 26.12009 -160.600136)
		(end 24.845264 -160.600136)
		(width 0.1397)
		(layer "F.Cu")
		(net "FANIN_3")
	)
	(segment
		(start 23.8252 -164.1094)
		(end 20.5994 -167.3352)
		(width 0.1397)
		(layer "F.Cu")
		(net "FANIN_3")
	)
	(segment
		(start 20.5994 -169.7228)
		(end 20.5486 -169.7736)
		(width 0.1397)
		(layer "F.Cu")
		(net "FANIN_3")
	)
	(segment
		(start 20.5994 -167.3352)
		(end 20.5994 -169.7228)
		(width 0.1397)
		(layer "F.Cu")
		(net "FANIN_3")
	)
	(segment
		(start 24.845264 -160.600136)
		(end 23.8252 -161.6202)
		(width 0.1397)
		(layer "F.Cu")
		(net "FANIN_3")
	)
	(via
		(at 17.094708 -287.90646)
		(size 0.7112)
		(drill 0.4064)
		(layers "F.Cu" "B.Cu")
		(net "FANIN_3")
	)
	(via
		(at 20.5486 -169.7736)
		(size 0.7112)
		(drill 0.4064)
		(layers "F.Cu" "B.Cu")
		(net "FANIN_3")
	)
	(via
		(at 20.066 -171.577)
		(size 0.7112)
		(drill 0.3556)
		(layers "F.Cu" "B.Cu")
		(net "FANIN_3")
	)
	(segment
		(start 17.91335 -209.22615)
		(end 17.91335 -194.11315)
		(width 0.1397)
		(layer "B.Cu")
		(net "FANIN_3")
	)
	(segment
		(start 17.91335 -194.11315)
		(end 20.413726 -191.612774)
		(width 0.1397)
		(layer "B.Cu")
		(net "FANIN_3")
	)
	(segment
		(start 18.45945 -286.541718)
		(end 18.45945 -209.77225)
		(width 0.1397)
		(layer "B.Cu")
		(net "FANIN_3")
	)
	(segment
		(start 20.5486 -169.7736)
		(end 20.5486 -171.0944)
		(width 0.1397)
		(layer "B.Cu")
		(net "FANIN_3")
	)
	(segment
		(start 19.401282 -176.77384)
		(end 18.40865 -175.781208)
		(width 0.1397)
		(layer "B.Cu")
		(net "FANIN_3")
	)
	(segment
		(start 18.40865 -173.989492)
		(end 20.066 -172.332142)
		(width 0.1397)
		(layer "B.Cu")
		(net "FANIN_3")
	)
	(segment
		(start 20.066 -172.332142)
		(end 20.066 -171.577)
		(width 0.1397)
		(layer "B.Cu")
		(net "FANIN_3")
	)
	(segment
		(start 17.094708 -287.90646)
		(end 18.45945 -286.541718)
		(width 0.1397)
		(layer "B.Cu")
		(net "FANIN_3")
	)
	(segment
		(start 20.5486 -171.0944)
		(end 20.066 -171.577)
		(width 0.1397)
		(layer "B.Cu")
		(net "FANIN_3")
	)
	(segment
		(start 20.134834 -176.77384)
		(end 19.401282 -176.77384)
		(width 0.1397)
		(layer "B.Cu")
		(net "FANIN_3")
	)
	(segment
		(start 18.40865 -175.781208)
		(end 18.40865 -173.989492)
		(width 0.1397)
		(layer "B.Cu")
		(net "FANIN_3")
	)
	(segment
		(start 20.413726 -191.612774)
		(end 20.413726 -177.052732)
		(width 0.1397)
		(layer "B.Cu")
		(net "FANIN_3")
	)
	(segment
		(start 18.45945 -209.77225)
		(end 17.91335 -209.22615)
		(width 0.1397)
		(layer "B.Cu")
		(net "FANIN_3")
	)
	(segment
		(start 20.413726 -177.052732)
		(end 20.134834 -176.77384)
		(width 0.1397)
		(layer "B.Cu")
		(net "FANIN_3")
	)
	(segment
		(start 13.8303 -448.2338)
		(end 12.5349 -449.5292)
		(width 0.1397)
		(layer "F.Cu")
		(net "FANIN_2")
	)
	(segment
		(start 13.843 -448.2338)
		(end 13.8303 -448.2338)
		(width 0.1397)
		(layer "F.Cu")
		(net "FANIN_2")
	)
	(segment
		(start 35.2806 -166.1668)
		(end 33.8582 -166.1668)
		(width 0.1397)
		(layer "F.Cu")
		(net "FANIN_2")
	)
	(segment
		(start 11.5062 -451.1802)
		(end 12.4079 -450.2785)
		(width 0.1397)
		(layer "F.Cu")
		(net "FANIN_2")
	)
	(segment
		(start 12.4079 -449.6562)
		(end 12.5349 -449.5292)
		(width 0.1397)
		(layer "F.Cu")
		(net "FANIN_2")
	)
	(segment
		(start 32.61233 -164.92093)
		(end 32.61233 -164.091366)
		(width 0.1397)
		(layer "F.Cu")
		(net "FANIN_2")
	)
	(segment
		(start 35.3568 -166.0906)
		(end 35.2806 -166.1668)
		(width 0.1397)
		(layer "F.Cu")
		(net "FANIN_2")
	)
	(segment
		(start 12.4079 -450.2785)
		(end 12.4079 -449.6562)
		(width 0.1397)
		(layer "F.Cu")
		(net "FANIN_2")
	)
	(segment
		(start 33.8582 -166.1668)
		(end 32.61233 -164.92093)
		(width 0.1397)
		(layer "F.Cu")
		(net "FANIN_2")
	)
	(via
		(at 35.3568 -166.0906)
		(size 0.5588)
		(drill 0.3048)
		(layers "F.Cu" "B.Cu")
		(net "FANIN_2")
	)
	(via
		(at 36.0172 -171.7802)
		(size 0.7112)
		(drill 0.3556)
		(layers "F.Cu" "B.Cu")
		(net "FANIN_2")
	)
	(via
		(at 11.5062 -451.1802)
		(size 0.5588)
		(drill 0.3048)
		(layers "F.Cu" "B.Cu")
		(net "FANIN_2")
	)
	(segment
		(start 22.479 -286.3342)
		(end 33.5661 -275.2471)
		(width 0.1397)
		(layer "B.Cu")
		(net "FANIN_2")
	)
	(segment
		(start 5.421884 -380.556516)
		(end 7.44855 -378.52985)
		(width 0.1397)
		(layer "B.Cu")
		(net "FANIN_2")
	)
	(segment
		(start 34.0106 -256.286)
		(end 40.4114 -249.8852)
		(width 0.1397)
		(layer "B.Cu")
		(net "FANIN_2")
	)
	(segment
		(start 35.615626 -210.857846)
		(end 35.615626 -174.010574)
		(width 0.1397)
		(layer "B.Cu")
		(net "FANIN_2")
	)
	(segment
		(start 33.5661 -275.2471)
		(end 33.5661 -272.77949)
		(width 0.1397)
		(layer "B.Cu")
		(net "FANIN_2")
	)
	(segment
		(start 33.566354 -272.779236)
		(end 33.566354 -259.041646)
		(width 0.1397)
		(layer "B.Cu")
		(net "FANIN_2")
	)
	(segment
		(start 39.33825 -214.5792)
		(end 39.33698 -214.5792)
		(width 0.1397)
		(layer "B.Cu")
		(net "FANIN_2")
	)
	(segment
		(start 33.566354 -259.041646)
		(end 34.0106 -258.5974)
		(width 0.1397)
		(layer "B.Cu")
		(net "FANIN_2")
	)
	(segment
		(start 5.421884 -415.123376)
		(end 5.421884 -380.556516)
		(width 0.1397)
		(layer "B.Cu")
		(net "FANIN_2")
	)
	(segment
		(start 40.4114 -246.4308)
		(end 41.1607 -245.6815)
		(width 0.1397)
		(layer "B.Cu")
		(net "FANIN_2")
	)
	(segment
		(start 33.5661 -272.77949)
		(end 33.566354 -272.779236)
		(width 0.1397)
		(layer "B.Cu")
		(net "FANIN_2")
	)
	(segment
		(start 41.1607 -216.40165)
		(end 39.33825 -214.5792)
		(width 0.1397)
		(layer "B.Cu")
		(net "FANIN_2")
	)
	(segment
		(start 7.44855 -366.281208)
		(end 10.222484 -363.507274)
		(width 0.1397)
		(layer "B.Cu")
		(net "FANIN_2")
	)
	(segment
		(start 7.44855 -378.52985)
		(end 7.44855 -366.281208)
		(width 0.1397)
		(layer "B.Cu")
		(net "FANIN_2")
	)
	(segment
		(start 34.791142 -170.554142)
		(end 36.0172 -171.7802)
		(width 0.1397)
		(layer "B.Cu")
		(net "FANIN_2")
	)
	(segment
		(start 35.615626 -174.010574)
		(end 36.0172 -173.609)
		(width 0.1397)
		(layer "B.Cu")
		(net "FANIN_2")
	)
	(segment
		(start 9.271 -449.4022)
		(end 6.337554 -446.468754)
		(width 0.1397)
		(layer "B.Cu")
		(net "FANIN_2")
	)
	(segment
		(start 35.3568 -167.9448)
		(end 34.791142 -168.510458)
		(width 0.1397)
		(layer "B.Cu")
		(net "FANIN_2")
	)
	(segment
		(start 10.222484 -363.507274)
		(end 10.222484 -358.839516)
		(width 0.1397)
		(layer "B.Cu")
		(net "FANIN_2")
	)
	(segment
		(start 34.0106 -258.5974)
		(end 34.0106 -256.286)
		(width 0.1397)
		(layer "B.Cu")
		(net "FANIN_2")
	)
	(segment
		(start 10.7188 -348.996)
		(end 21.209 -338.5058)
		(width 0.1397)
		(layer "B.Cu")
		(net "FANIN_2")
	)
	(segment
		(start 11.5062 -451.1802)
		(end 9.7282 -449.4022)
		(width 0.1397)
		(layer "B.Cu")
		(net "FANIN_2")
	)
	(segment
		(start 6.337554 -416.039046)
		(end 5.421884 -415.123376)
		(width 0.1397)
		(layer "B.Cu")
		(net "FANIN_2")
	)
	(segment
		(start 21.209 -291.973)
		(end 22.479 -290.703)
		(width 0.1397)
		(layer "B.Cu")
		(net "FANIN_2")
	)
	(segment
		(start 22.479 -290.703)
		(end 22.479 -286.3342)
		(width 0.1397)
		(layer "B.Cu")
		(net "FANIN_2")
	)
	(segment
		(start 41.1607 -245.6815)
		(end 41.1607 -216.40165)
		(width 0.1397)
		(layer "B.Cu")
		(net "FANIN_2")
	)
	(segment
		(start 36.0172 -173.609)
		(end 36.0172 -171.7802)
		(width 0.1397)
		(layer "B.Cu")
		(net "FANIN_2")
	)
	(segment
		(start 40.4114 -249.8852)
		(end 40.4114 -246.4308)
		(width 0.1397)
		(layer "B.Cu")
		(net "FANIN_2")
	)
	(segment
		(start 35.3568 -166.0906)
		(end 35.3568 -167.9448)
		(width 0.1397)
		(layer "B.Cu")
		(net "FANIN_2")
	)
	(segment
		(start 39.33698 -214.5792)
		(end 35.615626 -210.857846)
		(width 0.1397)
		(layer "B.Cu")
		(net "FANIN_2")
	)
	(segment
		(start 10.222484 -358.839516)
		(end 10.7188 -358.3432)
		(width 0.1397)
		(layer "B.Cu")
		(net "FANIN_2")
	)
	(segment
		(start 21.209 -338.5058)
		(end 21.209 -291.973)
		(width 0.1397)
		(layer "B.Cu")
		(net "FANIN_2")
	)
	(segment
		(start 10.7188 -358.3432)
		(end 10.7188 -348.996)
		(width 0.1397)
		(layer "B.Cu")
		(net "FANIN_2")
	)
	(segment
		(start 6.337554 -446.468754)
		(end 6.337554 -416.039046)
		(width 0.1397)
		(layer "B.Cu")
		(net "FANIN_2")
	)
	(segment
		(start 34.791142 -168.510458)
		(end 34.791142 -170.554142)
		(width 0.1397)
		(layer "B.Cu")
		(net "FANIN_2")
	)
	(segment
		(start 9.7282 -449.4022)
		(end 9.271 -449.4022)
		(width 0.1397)
		(layer "B.Cu")
		(net "FANIN_2")
	)
	(segment
		(start 7.0612 -449.5546)
		(end 6.0071 -449.5546)
		(width 0.1397)
		(layer "F.Cu")
		(net "FANIN_1")
	)
	(segment
		(start 6.0071 -449.5546)
		(end 5.9309 -449.4784)
		(width 0.1397)
		(layer "F.Cu")
		(net "FANIN_1")
	)
	(segment
		(start 33.528254 -165.201854)
		(end 33.11144 -164.78504)
		(width 0.1397)
		(layer "F.Cu")
		(net "FANIN_1")
	)
	(segment
		(start 35.2806 -165.1254)
		(end 35.204146 -165.201854)
		(width 0.1397)
		(layer "F.Cu")
		(net "FANIN_1")
	)
	(segment
		(start 35.204146 -165.201854)
		(end 33.528254 -165.201854)
		(width 0.1397)
		(layer "F.Cu")
		(net "FANIN_1")
	)
	(segment
		(start 7.0612 -449.5546)
		(end 7.0612 -448.7164)
		(width 0.1397)
		(layer "F.Cu")
		(net "FANIN_1")
	)
	(segment
		(start 33.11144 -164.78504)
		(end 33.11144 -164.091366)
		(width 0.1397)
		(layer "F.Cu")
		(net "FANIN_1")
	)
	(segment
		(start 7.0612 -448.7164)
		(end 6.35 -448.0052)
		(width 0.1397)
		(layer "F.Cu")
		(net "FANIN_1")
	)
	(via
		(at 6.35 -448.0052)
		(size 0.5588)
		(drill 0.3048)
		(layers "F.Cu" "B.Cu")
		(net "FANIN_1")
	)
	(via
		(at 35.2806 -165.1254)
		(size 0.5588)
		(drill 0.3048)
		(layers "F.Cu" "B.Cu")
		(net "FANIN_1")
	)
	(via
		(at 34.925 -173.355)
		(size 0.7112)
		(drill 0.3556)
		(layers "F.Cu" "B.Cu")
		(net "FANIN_1")
	)
	(segment
		(start 33.1216 -272.59534)
		(end 33.1216 -274.9804)
		(width 0.1397)
		(layer "B.Cu")
		(net "FANIN_1")
	)
	(segment
		(start 34.925 -171.323)
		(end 34.925 -173.355)
		(width 0.1397)
		(layer "B.Cu")
		(net "FANIN_1")
	)
	(segment
		(start 33.121854 -272.595086)
		(end 33.1216 -272.59534)
		(width 0.1397)
		(layer "B.Cu")
		(net "FANIN_1")
	)
	(segment
		(start 9.3218 -349.5802)
		(end 9.3218 -358.1654)
		(width 0.1397)
		(layer "B.Cu")
		(net "FANIN_1")
	)
	(segment
		(start 33.71215 -168.72585)
		(end 33.71215 -170.11015)
		(width 0.1397)
		(layer "B.Cu")
		(net "FANIN_1")
	)
	(segment
		(start 39.9034 -249.7074)
		(end 33.464246 -256.146554)
		(width 0.1397)
		(layer "B.Cu")
		(net "FANIN_1")
	)
	(segment
		(start 4.977384 -415.56813)
		(end 5.8928 -416.483546)
		(width 0.1397)
		(layer "B.Cu")
		(net "FANIN_1")
	)
	(segment
		(start 5.8928 -416.483546)
		(end 5.8928 -447.548)
		(width 0.1397)
		(layer "B.Cu")
		(net "FANIN_1")
	)
	(segment
		(start 20.5486 -338.3534)
		(end 9.3218 -349.5802)
		(width 0.1397)
		(layer "B.Cu")
		(net "FANIN_1")
	)
	(segment
		(start 34.8742 -167.5638)
		(end 33.71215 -168.72585)
		(width 0.1397)
		(layer "B.Cu")
		(net "FANIN_1")
	)
	(segment
		(start 35.2806 -165.1254)
		(end 34.8742 -165.5318)
		(width 0.1397)
		(layer "B.Cu")
		(net "FANIN_1")
	)
	(segment
		(start 20.5486 -291.7444)
		(end 20.5486 -338.3534)
		(width 0.1397)
		(layer "B.Cu")
		(net "FANIN_1")
	)
	(segment
		(start 33.71215 -170.11015)
		(end 34.925 -171.323)
		(width 0.1397)
		(layer "B.Cu")
		(net "FANIN_1")
	)
	(segment
		(start 33.1216 -274.9804)
		(end 21.971 -286.131)
		(width 0.1397)
		(layer "B.Cu")
		(net "FANIN_1")
	)
	(segment
		(start 35.02025 -210.91525)
		(end 39.1414 -215.0364)
		(width 0.1397)
		(layer "B.Cu")
		(net "FANIN_1")
	)
	(segment
		(start 39.1414 -215.0364)
		(end 39.1668 -215.0364)
		(width 0.1397)
		(layer "B.Cu")
		(net "FANIN_1")
	)
	(segment
		(start 21.971 -290.322)
		(end 20.5486 -291.7444)
		(width 0.1397)
		(layer "B.Cu")
		(net "FANIN_1")
	)
	(segment
		(start 34.8742 -165.5318)
		(end 34.8742 -167.5638)
		(width 0.1397)
		(layer "B.Cu")
		(net "FANIN_1")
	)
	(segment
		(start 7.00405 -366.070134)
		(end 7.00405 -378.10821)
		(width 0.1397)
		(layer "B.Cu")
		(net "FANIN_1")
	)
	(segment
		(start 33.121854 -258.736592)
		(end 33.121854 -272.595086)
		(width 0.1397)
		(layer "B.Cu")
		(net "FANIN_1")
	)
	(segment
		(start 39.2176 -215.1126)
		(end 40.7162 -216.6112)
		(width 0.1397)
		(layer "B.Cu")
		(net "FANIN_1")
	)
	(segment
		(start 40.7162 -216.6112)
		(end 40.7162 -245.1354)
		(width 0.1397)
		(layer "B.Cu")
		(net "FANIN_1")
	)
	(segment
		(start 39.1668 -215.0364)
		(end 39.2176 -215.0872)
		(width 0.1397)
		(layer "B.Cu")
		(net "FANIN_1")
	)
	(segment
		(start 9.777984 -358.621584)
		(end 9.777984 -363.2962)
		(width 0.1397)
		(layer "B.Cu")
		(net "FANIN_1")
	)
	(segment
		(start 9.3218 -358.1654)
		(end 9.777984 -358.621584)
		(width 0.1397)
		(layer "B.Cu")
		(net "FANIN_1")
	)
	(segment
		(start 39.9034 -245.9482)
		(end 39.9034 -249.7074)
		(width 0.1397)
		(layer "B.Cu")
		(net "FANIN_1")
	)
	(segment
		(start 4.977384 -380.134876)
		(end 4.977384 -415.56813)
		(width 0.1397)
		(layer "B.Cu")
		(net "FANIN_1")
	)
	(segment
		(start 7.00405 -378.10821)
		(end 4.977384 -380.134876)
		(width 0.1397)
		(layer "B.Cu")
		(net "FANIN_1")
	)
	(segment
		(start 9.777984 -363.2962)
		(end 7.00405 -366.070134)
		(width 0.1397)
		(layer "B.Cu")
		(net "FANIN_1")
	)
	(segment
		(start 35.02025 -173.45025)
		(end 35.02025 -210.91525)
		(width 0.1397)
		(layer "B.Cu")
		(net "FANIN_1")
	)
	(segment
		(start 5.8928 -447.548)
		(end 6.35 -448.0052)
		(width 0.1397)
		(layer "B.Cu")
		(net "FANIN_1")
	)
	(segment
		(start 21.971 -286.131)
		(end 21.971 -290.322)
		(width 0.1397)
		(layer "B.Cu")
		(net "FANIN_1")
	)
	(segment
		(start 33.464246 -256.146554)
		(end 33.464246 -258.3942)
		(width 0.1397)
		(layer "B.Cu")
		(net "FANIN_1")
	)
	(segment
		(start 40.7162 -245.1354)
		(end 39.9034 -245.9482)
		(width 0.1397)
		(layer "B.Cu")
		(net "FANIN_1")
	)
	(segment
		(start 34.925 -173.355)
		(end 35.02025 -173.45025)
		(width 0.1397)
		(layer "B.Cu")
		(net "FANIN_1")
	)
	(segment
		(start 33.464246 -258.3942)
		(end 33.121854 -258.736592)
		(width 0.1397)
		(layer "B.Cu")
		(net "FANIN_1")
	)
	(segment
		(start 39.2176 -215.0872)
		(end 39.2176 -215.1126)
		(width 0.1397)
		(layer "B.Cu")
		(net "FANIN_1")
	)
	(zone
		(net "GND")
		(layer "F.Cu")
		(hatch none 0.5)
		(connect_pads
			(clearance 0.5)
		)
		(min_thickness 0.25)
		(fill yes
			(thermal_gap 0.5)
			(thermal_bridge_width 0.5)
			(island_removal_mode 0)
		)
		(polygon
			(pts
				(xy 15.748 -145.796) (xy 15.748 -145.288) (xy 13.462 -143.002) (xy 7.493 -143.002) (xy 7.239 -143.256)
				(xy 7.239 -143.891) (xy 7.62 -144.272) (xy 8.636 -144.272) (xy 9.017 -144.653) (xy 9.017 -145.288)
				(xy 9.779 -146.05) (xy 15.494 -146.05)
			)
		)
	)
	(zone
		(net "P3V3_LX_COPPER")
		(layer "F.Cu")
		(hatch none 0.5)
		(connect_pads
			(clearance 0.5)
		)
		(min_thickness 0.25)
		(fill yes
			(thermal_gap 0.5)
			(thermal_bridge_width 0.5)
			(island_removal_mode 0)
		)
		(polygon
			(pts
				(xy 23.876 -238.125) (xy 23.368 -238.633) (xy 23.368 -239.268) (xy 22.86 -239.776) (xy 21.463 -239.776)
				(xy 21.209 -240.03) (xy 21.209 -242.316) (xy 22.479 -243.586) (xy 24.257 -243.586) (xy 24.511 -243.332)
				(xy 24.511 -240.665) (xy 25.146 -240.03) (xy 26.924 -240.03) (xy 27.432 -239.522) (xy 27.432 -238.379)
				(xy 27.178 -238.125)
			)
		)
	)
	(zone
		(net "P12V")
		(layer "F.Cu")
		(hatch none 0.5)
		(connect_pads
			(clearance 0.5)
		)
		(min_thickness 0.25)
		(fill yes
			(thermal_gap 0.5)
			(thermal_bridge_width 0.5)
			(island_removal_mode 0)
		)
		(polygon
			(pts
				(xy 38.6588 -290.7792) (xy 38.6588 -345.567) (xy 39.1668 -346.075) (xy 42.926 -346.075) (xy 43.688 -346.837)
				(xy 43.688 -362.204) (xy 43.688 -372.0592) (xy 43.2181 -372.5291) (xy 42.6212 -373.126) (xy 39.37 -373.126)
				(xy 37.211 -370.967) (xy 36.195 -370.967) (xy 36.195 -372.618) (xy 37.338 -373.761) (xy 37.338 -373.888)
				(xy 37.465 -374.015) (xy 38.1 -374.015) (xy 38.354 -374.269) (xy 38.354 -375.92) (xy 39.37 -376.936)
				(xy 39.37 -381.508) (xy 37.338 -383.54) (xy 13.97 -383.54) (xy 12.573 -384.937) (xy 12.573 -400.558)
				(xy 13.081 -401.066) (xy 44.45 -401.066) (xy 44.577 -400.939) (xy 44.577 -381) (xy 45.593 -379.984)
				(xy 50.292 -379.984) (xy 51.308 -381) (xy 51.562 -381) (xy 51.562 -284.353) (xy 50.4698 -283.2608)
				(xy 25.8318 -283.2608) (xy 25.4 -282.829) (xy 25.4 -256.032) (xy 24.003 -254.635) (xy 18.161 -254.635)
				(xy 17.907 -254.889) (xy 17.907 -257.683) (xy 18.796 -258.572) (xy 18.796 -282.7528) (xy 18.288 -283.2608)
				(xy 16.1544 -283.2608) (xy 15.8242 -283.591) (xy 15.8242 -284.7848) (xy 15.875 -284.8356) (xy 16.6116 -284.8356)
				(xy 16.891 -285.115) (xy 16.891 -286.6644) (xy 17.0434 -286.8168) (xy 18.6436 -286.8168) (xy 18.8468 -286.6136)
				(xy 18.8468 -285.6738) (xy 18.923 -285.5976) (xy 21.4884 -285.5976) (xy 21.6154 -285.7246) (xy 21.6154 -286.131)
				(xy 21.59 -286.1564) (xy 21.59 -286.766) (xy 22.0091 -287.1851) (xy 22.9743 -287.1851) (xy 24.9936 -289.2044)
				(xy 37.084 -289.2044)
			)
		)
	)
	(zone
		(net "P3V3")
		(layer "F.Cu")
		(hatch none 0.5)
		(connect_pads
			(clearance 0.5)
		)
		(min_thickness 0.25)
		(fill yes
			(thermal_gap 0.5)
			(thermal_bridge_width 0.5)
			(island_removal_mode 0)
		)
		(polygon
			(pts
				(xy 26.797 -234.95) (xy 26.416 -234.95) (xy 25.781 -235.585) (xy 25.781 -237.363) (xy 25.908 -237.49)
				(xy 27.178 -237.49) (xy 28.067 -238.379) (xy 31.115 -238.379) (xy 31.369 -238.125) (xy 31.369 -237.49)
				(xy 31.242 -237.363) (xy 29.21 -237.363)
			)
		)
	)
	(zone
		(net "GND")
		(layer "F.Cu")
		(hatch none 0.5)
		(connect_pads
			(clearance 0.5)
		)
		(min_thickness 0.25)
		(fill yes
			(thermal_gap 0.5)
			(thermal_bridge_width 0.5)
			(island_removal_mode 0)
		)
		(polygon
			(pts
				(xy 17.78 -293.751) (xy 17.78 -290.449) (xy 17.018 -289.687) (xy 15.621 -289.687) (xy 15.113 -290.195)
				(xy 15.113 -293.497) (xy 15.748 -294.132) (xy 17.399 -294.132)
			)
		)
	)
	(zone
		(layer "F.Cu")
		(hatch none 0.5)
		(connect_pads
			(clearance 0)
		)
		(min_thickness 0.25)
		(keepout
			(tracks allowed)
			(vias allowed)
			(pads allowed)
			(copperpour allowed)
			(footprints not_allowed)
		)
		(placement
			(enabled no)
			(sheetname "")
		)
		(fill
			(thermal_gap 0.5)
			(thermal_bridge_width 0.5)
			(island_removal_mode 0)
		)
		(polygon
			(pts
				(arc
					(start 15.999968 -31.800038)
					(mid 15.267774 -33.567712)
					(end 13.5001 -34.299906)
				)
				(xy 0 -34.299906)
				(arc
					(start 0 -0.999998)
					(mid 0.074208 -0.621966)
					(end 0.28575 -0.299974)
				)
				(arc
					(start 13.5001 -0.299974)
					(mid 15.267789 -1.032333)
					(end 15.999968 -2.800096)
				)
			)
		)
	)
	(zone
		(layer "F.Cu")
		(hatch none 0.5)
		(connect_pads
			(clearance 0)
		)
		(min_thickness 0.25)
		(keepout
			(tracks allowed)
			(vias allowed)
			(pads allowed)
			(copperpour allowed)
			(footprints not_allowed)
		)
		(placement
			(enabled no)
			(sheetname "")
		)
		(fill
			(thermal_gap 0.5)
			(thermal_bridge_width 0.5)
			(island_removal_mode 0)
		)
		(polygon
			(pts
				(arc
					(start 15.999968 -207.840072)
					(mid 15.267774 -209.607746)
					(end 13.5001 -210.33994)
				)
				(xy 0 -210.33994) (xy 0 -176.340008)
				(arc
					(start 13.5001 -176.340008)
					(mid 15.267774 -177.072202)
					(end 15.999968 -178.839876)
				)
			)
		)
	)
	(zone
		(layer "F.Cu")
		(hatch none 0.5)
		(connect_pads
			(clearance 0)
		)
		(min_thickness 0.25)
		(keepout
			(tracks allowed)
			(vias allowed)
			(pads allowed)
			(copperpour allowed)
			(footprints not_allowed)
		)
		(placement
			(enabled no)
			(sheetname "")
		)
		(fill
			(thermal_gap 0.5)
			(thermal_bridge_width 0.5)
			(island_removal_mode 0)
		)
		(polygon
			(pts
				(arc
					(start 6.999986 -464.000088)
					(mid 2.999994 -460.000096)
					(end 6.999986 -456.000104)
				)
				(arc
					(start 6.999986 -456.000104)
					(mid 10.999978 -460.000096)
					(end 6.999986 -464.000088)
				)
			)
		)
	)
	(zone
		(net "P3V3_AUX_BJT_B")
		(layer "F.Cu")
		(hatch none 0.5)
		(connect_pads
			(clearance 0.5)
		)
		(min_thickness 0.25)
		(fill yes
			(thermal_gap 0.5)
			(thermal_bridge_width 0.5)
			(island_removal_mode 0)
		)
		(polygon
			(pts
				(xy 32.385 -179.07) (xy 32.131 -179.324) (xy 32.131 -181.483) (xy 30.734 -182.88) (xy 30.099 -182.88)
				(xy 29.21 -183.769) (xy 29.21 -184.404) (xy 29.464 -184.658) (xy 30.48 -184.658) (xy 31.115 -184.023)
				(xy 33.655 -184.023) (xy 34.036 -183.642) (xy 34.036 -182.245) (xy 34.798 -181.483) (xy 35.179 -181.483)
				(xy 35.306 -181.356) (xy 35.306 -179.324) (xy 35.052 -179.07)
			)
		)
	)
	(zone
		(layer "F.Cu")
		(hatch none 0.5)
		(connect_pads
			(clearance 0)
		)
		(min_thickness 0.25)
		(keepout
			(tracks allowed)
			(vias allowed)
			(pads allowed)
			(copperpour allowed)
			(footprints not_allowed)
		)
		(placement
			(enabled no)
			(sheetname "")
		)
		(fill
			(thermal_gap 0.5)
			(thermal_bridge_width 0.5)
			(island_removal_mode 0)
		)
		(polygon
			(pts
				(arc
					(start 4.500118 -344.000074)
					(mid 0.500126 -340.000082)
					(end 4.500118 -336.00009)
				)
				(arc
					(start 4.500118 -336.00009)
					(mid 8.50011 -340.000082)
					(end 4.500118 -344.000074)
				)
			)
		)
	)
	(zone
		(net "P3V3_AUX")
		(layer "F.Cu")
		(hatch none 0.5)
		(connect_pads
			(clearance 0.5)
		)
		(min_thickness 0.25)
		(fill yes
			(thermal_gap 0.5)
			(thermal_bridge_width 0.5)
			(island_removal_mode 0)
		)
		(polygon
			(pts
				(xy 40.5892 -174.498) (xy 40.2336 -174.8536) (xy 40.2336 -174.879) (xy 39.9796 -175.133) (xy 38.735 -175.133)
				(xy 37.973 -175.895) (xy 37.973 -176.403) (xy 37.084 -177.292) (xy 35.814 -177.292) (xy 35.56 -177.546)
				(xy 35.56 -181.991) (xy 35.433 -182.118) (xy 34.671 -182.118) (xy 34.417 -182.372) (xy 34.417 -183.515)
				(xy 34.798 -183.896) (xy 38.354 -183.896) (xy 39.243 -184.785) (xy 39.243 -186.69) (xy 39.37 -186.817)
				(xy 40.513 -186.817) (xy 40.513 -184.9628) (xy 40.6146 -184.8612) (xy 40.64 -184.8358) (xy 41.7576 -184.8358)
				(xy 41.91 -184.9882) (xy 41.91 -186.817) (xy 42.291 -186.817) (xy 42.418 -186.69) (xy 42.418 -184.023)
				(xy 42.1513 -183.7563) (xy 41.4655 -183.7563) (xy 39.3192 -181.61) (xy 38.227 -181.61) (xy 37.592 -180.975)
				(xy 37.592 -180.467) (xy 37.846 -180.213) (xy 38.227 -180.213) (xy 38.354 -180.086) (xy 38.354 -179.324)
				(xy 38.1 -179.07) (xy 37.719 -179.07) (xy 37.465 -178.816) (xy 37.465 -178.308) (xy 37.719 -178.054)
				(xy 40.513 -178.054) (xy 40.767 -177.8) (xy 40.767 -176.276) (xy 41.148 -175.895) (xy 42.291 -175.895)
				(xy 42.291 -177.8) (xy 42.418 -177.927) (xy 42.926 -177.927) (xy 43.1038 -177.7492) (xy 43.1038 -177.1396)
				(xy 44.577 -175.6664) (xy 44.577 -174.9552) (xy 44.1198 -174.498)
			)
		)
	)
	(zone
		(net "P12VU_NET")
		(layer "F.Cu")
		(hatch none 0.5)
		(connect_pads
			(clearance 0.5)
		)
		(min_thickness 0.25)
		(fill yes
			(thermal_gap 0.5)
			(thermal_bridge_width 0.5)
			(island_removal_mode 0)
		)
		(polygon
			(pts
				(xy 16.3195 -112.8395) (xy 10.6045 -112.8395) (xy 10.287 -113.157) (xy 10.287 -121.031) (xy 10.922 -121.666)
				(xy 24.638 -121.666) (xy 24.7015 -121.6025) (xy 29.9085 -121.6025) (xy 30.6705 -121.6025) (xy 31.623 -120.65)
				(xy 31.623 -114.3) (xy 30.1625 -112.8395) (xy 29.6545 -112.8395) (xy 25.8445 -112.8395) (xy 23.6855 -112.8395)
			)
		)
	)
	(zone
		(layer "F.Cu")
		(hatch none 0.5)
		(connect_pads
			(clearance 0)
		)
		(min_thickness 0.25)
		(keepout
			(tracks allowed)
			(vias allowed)
			(pads allowed)
			(copperpour allowed)
			(footprints not_allowed)
		)
		(placement
			(enabled no)
			(sheetname "")
		)
		(fill
			(thermal_gap 0.5)
			(thermal_bridge_width 0.5)
			(island_removal_mode 0)
		)
		(polygon
			(pts
				(arc
					(start 45.500036 -15.999968)
					(mid 49.500028 -19.99996)
					(end 45.500036 -23.999952)
				)
				(arc
					(start 45.500036 -23.999952)
					(mid 41.500044 -19.99996)
					(end 45.500036 -15.999968)
				)
			)
		)
	)
	(zone
		(net "GND")
		(layer "F.Cu")
		(hatch none 0.5)
		(connect_pads
			(clearance 0.5)
		)
		(min_thickness 0.25)
		(fill yes
			(thermal_gap 0.5)
			(thermal_bridge_width 0.5)
			(island_removal_mode 0)
		)
		(polygon
			(pts
				(xy 18.669 -281.94) (xy 18.669 -275.082) (xy 18.288 -274.701) (xy 16.129 -274.701) (xy 15.113 -275.717)
				(xy 15.113 -282.448) (xy 15.494 -282.829) (xy 17.78 -282.829)
			)
		)
	)
	(zone
		(layer "F.Cu")
		(hatch none 0.5)
		(connect_pads
			(clearance 0)
		)
		(min_thickness 0.25)
		(keepout
			(tracks allowed)
			(vias allowed)
			(pads allowed)
			(copperpour allowed)
			(footprints not_allowed)
		)
		(placement
			(enabled no)
			(sheetname "")
		)
		(fill
			(thermal_gap 0.5)
			(thermal_bridge_width 0.5)
			(island_removal_mode 0)
		)
		(polygon
			(pts
				(arc
					(start 6.999986 -155.999942)
					(mid 10.999978 -159.999934)
					(end 6.999986 -163.999926)
				)
				(arc
					(start 6.999986 -163.999926)
					(mid 2.999994 -159.999934)
					(end 6.999986 -155.999942)
				)
			)
		)
	)
	(zone
		(layer "F.Cu")
		(hatch none 0.5)
		(connect_pads
			(clearance 0)
		)
		(min_thickness 0.25)
		(keepout
			(tracks allowed)
			(vias allowed)
			(pads allowed)
			(copperpour allowed)
			(footprints not_allowed)
		)
		(placement
			(enabled no)
			(sheetname "")
		)
		(fill
			(thermal_gap 0.5)
			(thermal_bridge_width 0.5)
			(island_removal_mode 0)
		)
		(polygon
			(pts
				(arc
					(start 13.5001 -110.339886)
					(mid 15.267789 -111.072245)
					(end 15.999968 -112.840008)
				)
				(arc
					(start 15.999968 -141.83995)
					(mid 15.267789 -143.607713)
					(end 13.5001 -144.340072)
				)
				(xy 0 -144.340072) (xy 0 -110.339886)
			)
		)
	)
	(zone
		(layer "F.Cu")
		(hatch none 0.5)
		(connect_pads
			(clearance 0)
		)
		(min_thickness 0.25)
		(keepout
			(tracks allowed)
			(vias allowed)
			(pads allowed)
			(copperpour allowed)
			(footprints not_allowed)
		)
		(placement
			(enabled no)
			(sheetname "")
		)
		(fill
			(thermal_gap 0.5)
			(thermal_bridge_width 0.5)
			(island_removal_mode 0)
		)
		(polygon
			(pts
				(arc
					(start 6.999986 -43.999912)
					(mid 2.999994 -39.99992)
					(end 6.999986 -35.999928)
				)
				(arc
					(start 6.999986 -35.999928)
					(mid 10.999978 -39.99992)
					(end 6.999986 -43.999912)
				)
			)
		)
	)
	(zone
		(net "P3V3_IN")
		(layer "F.Cu")
		(hatch none 0.5)
		(connect_pads
			(clearance 0.5)
		)
		(min_thickness 0.25)
		(fill yes
			(thermal_gap 0.5)
			(thermal_bridge_width 0.5)
			(island_removal_mode 0)
		)
		(polygon
			(pts
				(xy 17.78 -246.634) (xy 14.097 -246.634) (xy 13.97 -246.761) (xy 13.97 -247.777) (xy 14.224 -248.031)
				(xy 14.986 -248.031) (xy 15.113 -248.158) (xy 15.113 -248.285) (xy 17.399 -248.285) (xy 17.526 -248.412)
				(xy 20.066 -248.412) (xy 20.193 -248.285) (xy 20.193 -247.65) (xy 18.796 -247.65)
			)
		)
	)
	(zone
		(layer "F.Cu")
		(hatch none 0.5)
		(connect_pads
			(clearance 0)
		)
		(min_thickness 0.25)
		(keepout
			(tracks allowed)
			(vias allowed)
			(pads allowed)
			(copperpour allowed)
			(footprints not_allowed)
		)
		(placement
			(enabled no)
			(sheetname "")
		)
		(fill
			(thermal_gap 0.5)
			(thermal_bridge_width 0.5)
			(island_removal_mode 0)
		)
		(polygon
			(pts
				(arc
					(start 45.500036 -484.000048)
					(mid 41.500044 -480.000056)
					(end 45.500036 -476.000064)
				)
				(arc
					(start 45.500036 -476.000064)
					(mid 49.500028 -480.000056)
					(end 45.500036 -484.000048)
				)
			)
		)
	)
	(zone
		(layer "F.Cu")
		(hatch none 0.5)
		(connect_pads
			(clearance 0)
		)
		(min_thickness 0.25)
		(keepout
			(tracks allowed)
			(vias allowed)
			(pads allowed)
			(copperpour allowed)
			(footprints not_allowed)
		)
		(placement
			(enabled no)
			(sheetname "")
		)
		(fill
			(thermal_gap 0.5)
			(thermal_bridge_width 0.5)
			(island_removal_mode 0)
		)
		(polygon
			(pts
				(xy 8.999982 -351.199958) (xy 8.999982 -323.799962) (xy 38.699948 -323.799962) (xy 38.699948 -329.149964)
				(arc
					(start 44.04995 -329.149964)
					(mid 49.954289 -331.595621)
					(end 52.399946 -337.49996)
				)
				(arc
					(start 52.399946 -337.49996)
					(mid 49.954289 -343.404299)
					(end 44.04995 -345.849956)
				)
				(xy 38.699948 -345.849956) (xy 38.699948 -351.199958)
			)
		)
	)
	(zone
		(layer "F.Cu")
		(hatch none 0.5)
		(connect_pads
			(clearance 0)
		)
		(min_thickness 0.25)
		(keepout
			(tracks allowed)
			(vias allowed)
			(pads allowed)
			(copperpour allowed)
			(footprints not_allowed)
		)
		(placement
			(enabled no)
			(sheetname "")
		)
		(fill
			(thermal_gap 0.5)
			(thermal_bridge_width 0.5)
			(island_removal_mode 0)
		)
		(polygon
			(pts
				(arc
					(start 6.999986 -163.999926)
					(mid 2.999994 -159.999934)
					(end 6.999986 -155.999942)
				)
				(arc
					(start 6.999986 -155.999942)
					(mid 10.999978 -159.999934)
					(end 6.999986 -163.999926)
				)
			)
		)
	)
	(zone
		(net "P12VL_NET")
		(layer "F.Cu")
		(hatch none 0.5)
		(connect_pads
			(clearance 0.5)
		)
		(min_thickness 0.25)
		(fill yes
			(thermal_gap 0.5)
			(thermal_bridge_width 0.5)
			(island_removal_mode 0)
		)
		(polygon
			(pts
				(xy 37.719 -121.539) (xy 51.308 -121.539) (xy 51.689 -121.158) (xy 51.689 -113.03) (xy 51.308 -112.649)
				(xy 37.719 -112.649) (xy 33.528 -112.649) (xy 32.639 -113.538) (xy 32.639 -120.904) (xy 33.274 -121.539)
			)
		)
	)
	(zone
		(layer "F.Cu")
		(hatch none 0.5)
		(connect_pads
			(clearance 0)
		)
		(min_thickness 0.25)
		(keepout
			(tracks allowed)
			(vias allowed)
			(pads allowed)
			(copperpour allowed)
			(footprints allowed)
		)
		(placement
			(enabled no)
			(sheetname "")
		)
		(fill
			(thermal_gap 0.5)
			(thermal_bridge_width 0.5)
			(island_removal_mode 0)
		)
		(polygon
			(pts
				(xy 40.6908 -136.906) (xy 40.6908 -136.0678) (xy 42.037 -136.0678) (xy 42.037 -136.906)
			)
		)
	)
	(zone
		(net "GND")
		(layer "F.Cu")
		(hatch none 0.5)
		(connect_pads
			(clearance 0.5)
		)
		(min_thickness 0.25)
		(fill yes
			(thermal_gap 0.5)
			(thermal_bridge_width 0.5)
			(island_removal_mode 0)
		)
		(polygon
			(pts
				(arc
					(start 0.999998 -0.762254)
					(mid 0.831888 -0.831888)
					(end 0.762254 -0.999998)
				)
				(arc
					(start 0.762254 -499.000018)
					(mid 0.831888 -499.168128)
					(end 0.999998 -499.237762)
				)
				(arc
					(start 16.500094 -499.237762)
					(mid 16.668204 -499.168128)
					(end 16.737838 -499.000018)
				)
				(arc
					(start 16.737838 -491.000034)
					(mid 17.25399 -489.753934)
					(end 18.50009 -489.237782)
				)
				(arc
					(start 51.500024 -489.237782)
					(mid 51.668134 -489.168148)
					(end 51.737768 -489.000038)
				)
				(xy 51.737768 -381.937768) (xy 50.292 -380.492) (xy 45.847 -380.492) (xy 44.958 -381.381) (xy 44.958 -397.637)
				(xy 45.974 -398.653) (xy 45.974 -400.05) (xy 47.879 -401.955) (xy 47.879 -409.956) (xy 47.117 -410.718)
				(xy 47.117 -423.291) (xy 46.355 -424.053) (xy 35.56 -424.053) (xy 33.655 -425.958) (xy 33.655 -474.472)
				(xy 34.671 -475.488) (xy 35.814 -475.488) (xy 36.83 -476.504) (xy 36.83 -480.822) (xy 35.941 -481.711)
				(xy 28.702 -481.711) (xy 28.194 -482.219) (xy 28.194 -486.918) (xy 27.559 -487.553) (xy 2.921 -487.553)
				(xy 2.032 -486.664) (xy 2.032 -485.394) (xy 2.286 -485.14) (xy 2.286 -477.266) (xy 2.794 -476.758)
				(xy 4.064 -476.758) (xy 5.842 -478.536) (xy 5.842 -479.425) (xy 6.985 -479.425) (xy 13.335 -473.075)
				(xy 13.335 -458.4192) (xy 14.4272 -457.327) (xy 14.4272 -454.9394) (xy 13.6398 -454.152) (xy 13.4366 -454.152)
				(xy 13.4239 -454.1647) (xy 11.6459 -454.1647) (xy 11.4554 -453.9742) (xy 11.4554 -453.062848) (xy 11.398504 -453.005952)
				(xy 11.398504 -451.183248) (xy 12.169648 -450.412104) (xy 12.452096 -450.412104) (xy 12.5222 -450.342)
				(xy 13.843 -450.342) (xy 13.9065 -450.4055) (xy 15.0495 -449.2625) (xy 15.0495 -444.8175) (xy 12.573 -442.341)
				(xy 12.573 -416.179) (xy 12.2682 -415.8742) (xy 12.2682 -384.048) (xy 13.6652 -382.651) (xy 25.146 -382.651)
				(xy 25.654 -382.143) (xy 25.654 -380.365) (xy 24.765 -379.476) (xy 21.844 -379.476) (xy 20.701 -378.333)
				(xy 20.701 -376.428) (xy 21.082 -376.047) (xy 21.082 -373.507) (xy 20.447 -372.872) (xy 20.447 -370.586)
				(xy 20.828 -370.586) (xy 21.082 -370.332) (xy 22.987 -370.332) (xy 23.241 -370.078) (xy 23.241 -369.189)
				(xy 23.114 -369.062) (xy 21.463 -369.062) (xy 21.336 -368.935) (xy 21.336 -368.427) (xy 21.717 -368.046)
				(xy 23.241 -368.046) (xy 23.495 -367.792) (xy 23.495 -366.2172) (xy 23.4188 -366.141) (xy 22.8346 -366.141)
				(xy 22.5552 -366.4204) (xy 21.844 -366.4204) (xy 21.463 -366.0394) (xy 21.463 -365.76) (xy 21.4757 -365.7473)
				(xy 21.4757 -365.4425) (xy 21.844 -365.0742) (xy 23.3172 -365.0742) (xy 23.495 -364.8964) (xy 23.495 -363.728)
				(xy 23.368 -363.601) (xy 22.5806 -363.601) (xy 22.098 -363.1184) (xy 22.098 -360.4006) (xy 22.479 -360.0196)
				(xy 24.0284 -360.0196) (xy 26.035 -358.013) (xy 26.035 -355.473) (xy 27.178 -354.33) (xy 28.575 -354.33)
				(xy 28.702 -354.203) (xy 28.702 -353.822) (xy 28.321 -353.441) (xy 28.321 -351.155) (xy 29.21 -350.266)
				(xy 37.592 -350.266) (xy 38.354 -349.504) (xy 38.354 -291.211) (xy 36.703 -289.56) (xy 34.798 -289.56)
				(xy 34.036 -290.322) (xy 34.036 -294.386) (xy 32.766 -295.656) (xy 29.718 -295.656) (xy 18.923 -306.451)
				(xy 18.923 -340.995) (xy 5.969 -353.949) (xy 5.969 -359.156) (xy 6.223 -359.41) (xy 7.874 -359.41)
				(xy 9.525 -361.061) (xy 9.525 -363.093) (xy 8.128 -364.49) (xy 8.128 -375.539) (xy 6.858 -376.809)
				(xy 2.159 -376.809) (xy 1.905 -376.555) (xy 1.905 -374.396) (xy 2.667 -373.634) (xy 3.683 -373.634)
				(xy 4.318 -372.999) (xy 4.318 -366.649) (xy 2.413 -364.744) (xy 2.413 -351.536) (xy 15.24 -338.709)
				(xy 15.24 -304.292) (xy 16.383 -303.149) (xy 16.383 -298.069) (xy 15.748 -297.434) (xy 15.367 -297.434)
				(xy 15.113 -297.688) (xy 15.113 -298.577) (xy 10.033 -303.657) (xy 10.033 -307.594) (xy 6.604 -311.023)
				(xy 1.905 -311.023) (xy 1.651 -310.769) (xy 1.651 -301.625) (xy 2.921 -300.355) (xy 7.239 -300.355)
				(xy 10.922 -296.672) (xy 10.922 -257.937) (xy 12.192 -256.667) (xy 14.224 -256.667) (xy 15.113 -255.778)
				(xy 15.113 -255.016) (xy 15.748 -254.381) (xy 15.748 -253.492) (xy 15.875 -253.365) (xy 17.272 -253.365)
				(xy 18.288 -254.381) (xy 24.638 -254.381) (xy 25.908 -255.651) (xy 25.908 -282.448) (xy 26.416 -282.956)
				(xy 51.102768 -282.956) (xy 51.737768 -282.321) (xy 51.737768 -134.211568) (xy 51.4604 -133.9342)
				(xy 44.1198 -133.9342) (xy 43.942 -134.112) (xy 43.942 -136.652) (xy 43.688 -136.906) (xy 42.799 -136.906)
				(xy 42.545 -137.16) (xy 42.545 -138.43) (xy 43.18 -139.065) (xy 43.18 -140.0302) (xy 42.9641 -140.2461)
				(xy 42.926 -140.208) (xy 42.164 -140.208) (xy 39.624 -142.748) (xy 38.227 -142.748) (xy 36.322 -140.843)
				(xy 36.322 -136.906) (xy 37.846 -135.382) (xy 38.7096 -135.382) (xy 38.862 -135.2296) (xy 38.862 -134.239)
				(xy 38.5064 -133.8834) (xy 25.273 -133.8834) (xy 24.9555 -134.2009) (xy 24.9555 -135.0137) (xy 23.9268 -136.0424)
				(xy 23.9268 -137.9982) (xy 23.876 -138.049) (xy 23.876 -138.938) (xy 25.4 -138.938) (xy 26.289 -138.049)
				(xy 27.559 -138.049) (xy 28.448 -138.938) (xy 28.448 -139.827) (xy 27.813 -140.462) (xy 26.797 -140.462)
				(xy 26.67 -140.589) (xy 26.67 -142.494) (xy 26.797 -142.621) (xy 32.258 -142.621) (xy 35.1917 -145.5547)
				(xy 35.1917 -145.8341) (xy 35.2679 -145.9103) (xy 35.2679 -146.6977) (xy 35.433 -146.8628) (xy 36.3474 -146.8628)
				(xy 36.6014 -146.6088) (xy 36.8808 -146.6088) (xy 37.6936 -147.4216) (xy 37.6936 -147.5994) (xy 37.6428 -147.6502)
				(xy 37.6428 -148.1836) (xy 41.8592 -152.4) (xy 45.339 -152.4) (xy 47.371 -154.432) (xy 47.371 -164.719)
				(xy 46.609 -165.481) (xy 42.545 -165.481) (xy 41.656 -164.592) (xy 41.656 -162.941) (xy 39.624 -162.941)
				(xy 39.37 -163.195) (xy 39.37 -169.037) (xy 40.132 -169.799) (xy 40.132 -170.307) (xy 39.37 -171.069)
				(xy 39.37 -171.831) (xy 40.767 -173.228) (xy 44.196 -173.228) (xy 45.72 -174.752) (xy 45.72 -178.689)
				(xy 45.466 -178.943) (xy 43.18 -178.943) (xy 43.18 -177.038) (xy 44.577 -175.641) (xy 44.577 -174.879)
				(xy 44.196 -174.498) (xy 39.37 -174.498) (xy 38.608 -173.736) (xy 38.608 -172.085) (xy 38.227 -171.704)
				(xy 37.973 -171.704) (xy 36.703 -172.974) (xy 35.433 -172.974) (xy 35.052 -172.593) (xy 34.29 -172.593)
				(xy 34.163 -172.466) (xy 34.163 -171.069) (xy 32.893 -169.799) (xy 22.86 -169.799) (xy 22.225 -169.164)
				(xy 22.225 -165.481) (xy 23.495 -164.211) (xy 23.495 -162.179) (xy 21.844 -162.179) (xy 21.844 -162.687)
				(xy 19.431 -165.1) (xy 17.018 -165.1) (xy 15.621 -166.497) (xy 15.621 -169.037) (xy 16.383 -169.799)
				(xy 16.891 -169.799) (xy 18.161 -171.069) (xy 18.161 -171.958) (xy 20.828 -171.958) (xy 21.336 -172.466)
				(xy 22.352 -172.466) (xy 22.352 -171.704) (xy 22.733 -171.323) (xy 24.765 -171.323) (xy 24.892 -171.45)
				(xy 24.892 -176.403) (xy 24.384 -176.911) (xy 20.574 -176.911) (xy 20.574 -176.022) (xy 20.447 -175.895)
				(xy 17.145 -175.895) (xy 13.843 -172.593) (xy 10.16 -172.593) (xy 9.017 -171.45) (xy 9.017 -156.972)
				(xy 1.8542 -149.8092) (xy 1.8542 -130.5306) (xy 1.651 -130.3274) (xy 1.651 -128.651) (xy 2.032 -128.27)
				(xy 6.35 -128.27) (xy 7.62 -127) (xy 7.62 -123.825) (xy 9.525 -121.92) (xy 9.525 -90.551) (xy 9.398 -90.424)
				(xy 9.398 -89.789) (xy 9.271 -89.662) (xy 9.271 -85.852) (xy 8.255 -84.836) (xy 4.191 -84.836) (xy 3.683 -84.328)
				(xy 3.683 -77.089) (xy 4.445 -76.327) (xy 9.017 -76.327) (xy 9.144 -76.2) (xy 9.144 -73.025) (xy 10.287 -71.882)
				(xy 17.3228 -71.882) (xy 17.3228 -68.5292) (xy 13.716 -64.9224) (xy 13.716 -63.881) (xy 14.097 -63.5)
				(xy 14.6304 -63.5) (xy 15.5194 -62.611) (xy 15.5194 -59.7916) (xy 15.1384 -59.4106) (xy 15.1384 -58.8264)
				(xy 14.859 -58.547) (xy 12.319 -58.547) (xy 11.811 -59.055) (xy 11.811 -59.2455) (xy 11.5443 -59.2455)
				(xy 11.5062 -59.2074) (xy 10.795 -59.2074) (xy 10.6172 -59.0296) (xy 10.6172 -43.2562) (xy 13.7414 -40.132)
				(xy 13.7414 -39.5732) (xy 14.4018 -38.9128) (xy 14.6812 -38.9128) (xy 14.9352 -39.1668) (xy 14.9352 -39.6748)
				(xy 15.3416 -40.0812) (xy 19.431 -40.0812) (xy 20.0406 -39.4716) (xy 27.813 -39.4716) (xy 27.8257 -39.4843)
				(xy 28.8163 -39.4843) (xy 35.814 -46.482) (xy 35.814 -49.149) (xy 36.8046 -50.1396) (xy 47.117 -50.1396)
				(xy 48.006 -51.0286) (xy 48.006 -79.375) (xy 45.339 -82.042) (xy 45.339 -108.331) (xy 46.482 -109.474)
				(xy 47.371 -109.474) (xy 48.387 -110.49) (xy 49.784 -110.49) (xy 49.911 -110.617) (xy 49.911 -112.141)
				(xy 50.038 -112.268) (xy 51.229768 -112.268) (xy 51.737768 -111.76) (xy 51.737768 -70.914768) (xy 51.649884 -70.826884)
				(xy 51.737768 -70.739)
				(arc
					(start 51.737768 -10.999978)
					(mid 51.668134 -10.831868)
					(end 51.500024 -10.762234)
				)
				(arc
					(start 18.50009 -10.762234)
					(mid 17.25399 -10.246082)
					(end 16.737838 -8.999982)
				)
				(arc
					(start 16.737838 -0.999998)
					(mid 16.668204 -0.831888)
					(end 16.500094 -0.762254)
				)
			)
		)
		(polygon
			(pts
				(xy 13.639546 -454.152508) (xy 13.436854 -454.152508) (xy 13.424154 -454.165208) (xy 11.843004 -454.165208)
				(xy 11.843004 -455.863452) (xy 13.866622 -457.88707) (xy 14.426692 -457.326746) (xy 14.426692 -454.939654)
			)
		)
		(polygon
			(pts
				(arc
					(start 11.093196 -453.927972)
					(mid 11.046069 -453.842209)
					(end 10.948416 -453.836024)
				)
				(arc
					(start 10.948416 -453.836024)
					(mid 10.889137 -453.860429)
					(end 10.827766 -453.87895)
				)
				(xy 10.81405 -453.882252) (xy 10.338308 -454.358248)
				(arc
					(start 10.338308 -454.3806)
					(mid 10.326501 -454.477658)
					(end 10.291826 -454.569068)
				)
				(arc
					(start 10.291826 -454.569068)
					(mid 10.283186 -454.64088)
					(end 10.324592 -454.700132)
				)
				(arc
					(start 10.324592 -454.700132)
					(mid 10.540684 -454.946199)
					(end 10.61212 -455.26579)
				)
				(xy 10.611358 -455.287634)
				(arc
					(start 10.919714 -455.595736)
					(mid 11.030381 -455.617821)
					(end 11.093196 -455.524108)
				)
			)
		)
		(polygon
			(pts
				(xy 7.26313 -451.072504) (xy 5.597906 -451.072504)
				(arc
					(start 5.582666 -451.089268)
					(mid 5.426843 -451.215019)
					(end 5.240528 -451.288404)
				)
				(xy 5.200904 -451.297548) (xy 5.200904 -451.621652) (xy 5.203698 -451.624192) (xy 6.426708 -451.624192)
				(xy 6.426708 -452.449692) (xy 6.562598 -452.449692) (xy 7.210298 -453.097392) (xy 7.210552 -453.097392)
				(xy 7.604252 -453.491092)
				(arc
					(start 7.8994 -453.491092)
					(mid 8.111679 -453.550852)
					(end 8.261604 -453.71258)
				)
				(arc
					(start 8.261604 -453.71258)
					(mid 8.336298 -453.766682)
					(end 8.42391 -453.73798)
				)
				(arc
					(start 8.42391 -453.73798)
					(mid 8.556093 -453.649278)
					(end 8.7122 -453.618092)
				)
				(arc
					(start 9.0678 -453.618092)
					(mid 9.098753 -453.619329)
					(end 9.129522 -453.622918)
				)
				(xy 9.154922 -453.626728) (xy 9.209024 -453.572626) (xy 8.759952 -453.123808) (xy 7.797292 -453.123808)
				(xy 7.797292 -451.624192) (xy 9.804908 -451.624192) (xy 9.804908 -452.576692)
				(arc
					(start 10.598912 -452.576692)
					(mid 10.645845 -452.545332)
					(end 10.634726 -452.490078)
				)
				(xy 10.597896 -452.453248)
				(arc
					(start 10.597896 -451.263004)
					(mid 10.524983 -451.165284)
					(end 10.410698 -451.207886)
				)
				(arc
					(start 10.410698 -451.207886)
					(mid 9.896803 -451.509492)
					(end 9.348978 -451.274942)
				)
				(xy 9.333738 -451.256908) (xy 8.980932 -451.256908)
				(arc
					(start 8.972804 -451.259702)
					(mid 8.906951 -451.276625)
					(end 8.8392 -451.282308)
				)
				(arc
					(start 8.4836 -451.282308)
					(mid 8.349026 -451.259321)
					(end 8.2296 -451.193154)
				)
				(arc
					(start 8.2296 -451.193154)
					(mid 8.11019 -451.259366)
					(end 7.9756 -451.282308)
				)
				(arc
					(start 7.62 -451.282308)
					(mid 7.425297 -451.232667)
					(end 7.278116 -451.095872)
				)
			)
		)
		(polygon
			(pts
				(xy 11.8618 -444.1698) (xy 9.4996 -444.1698) (xy 9.4996 -449.707) (xy 10.033 -450.2404) (xy 11.5316 -450.2404)
				(xy 11.8618 -449.9102)
			)
		)
		(polygon
			(pts
				(xy 8.4074 -433.9336) (xy 4.7498 -433.9336) (xy 4.2418 -434.4416) (xy 4.2418 -436.245) (xy 4.5466 -436.5498)
				(xy 5.0292 -436.5498) (xy 4.953 -436.626) (xy 4.953 -443.0014) (xy 7.5184 -445.5668) (xy 8.2804 -445.5668)
				(xy 8.2804 -446.3034) (xy 8.636 -446.659) (xy 9.3218 -445.9732) (xy 9.3218 -436.8038) (xy 9.2456 -436.7276)
				(xy 9.2456 -434.7718)
			)
		)
		(polygon
			(pts
				(arc
					(start 5.816346 -430.555654)
					(mid 5.681909 -430.532789)
					(end 5.5626 -430.466754)
				)
				(arc
					(start 5.5626 -430.466754)
					(mid 5.44319 -430.532966)
					(end 5.3086 -430.555908)
				)
				(xy 4.953508 -430.555908) (xy 4.953508 -432.727608) (xy 4.572508 -432.727608)
				(arc
					(start 4.572508 -432.922426)
					(mid 4.613792 -433.004185)
					(end 4.70408 -433.019454)
				)
				(arc
					(start 4.70408 -433.019454)
					(mid 4.913474 -432.994419)
					(end 5.1181 -433.045362)
				)
				(arc
					(start 5.1181 -433.045362)
					(mid 5.215225 -433.038377)
					(end 5.261864 -432.952906)
				)
				(xy 5.261864 -432.794664) (xy 5.57276 -432.794664) (xy 5.57276 -432.300634) (xy 5.866892 -432.006502)
				(arc
					(start 5.866892 -430.606454)
					(mid 5.852103 -430.570623)
					(end 5.816346 -430.555654)
				)
			)
		)
		(polygon
			(pts
				(arc
					(start 5.200904 -418.178742)
					(mid 5.178032 -418.163998)
					(end 5.1562 -418.147754)
				)
				(arc
					(start 5.1562 -418.147754)
					(mid 5.03679 -418.213966)
					(end 4.9022 -418.236908)
				)
				(arc
					(start 4.5466 -418.236908)
					(mid 4.478855 -418.231186)
					(end 4.412996 -418.214302)
				)
				(xy 4.404868 -418.211508)
				(arc
					(start 4.033774 -418.211508)
					(mid 3.939942 -418.274144)
					(end 3.961892 -418.384736)
				)
				(xy 4.674108 -419.096952) (xy 4.674108 -419.772592) (xy 5.055108 -419.772592) (xy 5.055108 -421.786558)
				(arc
					(start 5.090414 -421.797734)
					(mid 5.384005 -421.988868)
					(end 5.538724 -422.303194)
				)
				(xy 5.546598 -422.344596) (xy 7.815072 -422.344596)
				(arc
					(start 7.830058 -422.319704)
					(mid 7.844802 -422.296832)
					(end 7.861046 -422.275)
				)
				(arc
					(start 7.861046 -422.275)
					(mid 7.805286 -422.182156)
					(end 7.775956 -422.077896)
				)
				(xy 7.76986 -422.034208) (xy 5.968492 -422.034208) (xy 5.968492 -420.493698) (xy 5.225796 -419.750748)
				(xy 5.225796 -418.193728)
			)
		)
		(polygon
			(pts
				(xy 8.89 -411.734) (xy 6.985 -411.734) (xy 5.842 -412.877) (xy 5.842 -418.084) (xy 5.6896 -418.2364)
				(xy 5.6896 -419.608) (xy 6.2738 -420.1922) (xy 8.3312 -420.1922) (xy 8.382 -420.243) (xy 9.779 -420.243)
				(xy 10.033 -419.989) (xy 10.033 -415.544) (xy 9.144 -414.655) (xy 9.144 -411.988)
			)
		)
		(polygon
			(pts
				(xy 30.353 -318.135) (xy 26.416 -318.135) (xy 25.527 -319.024) (xy 25.527 -320.802) (xy 26.543 -321.818)
				(xy 30.226 -321.818) (xy 30.988 -321.056) (xy 30.988 -318.77)
			)
		)
		(polygon
			(pts
				(xy 31.623 -248.158) (xy 28.067 -248.158) (xy 27.94 -248.285) (xy 27.94 -248.539) (xy 26.543 -249.936)
				(xy 26.543 -251.968) (xy 26.797 -252.222) (xy 28.321 -252.222) (xy 28.829 -252.73) (xy 28.829 -253.365)
				(xy 29.591 -254.127) (xy 29.591 -255.524) (xy 30.226 -256.159) (xy 30.861 -256.159) (xy 31.369 -255.651)
				(xy 31.369 -252.984) (xy 31.242 -252.857) (xy 31.242 -249.174) (xy 31.623 -248.793)
			)
		)
		(polygon
			(pts
				(xy 39.497 -247.269) (xy 38.1 -247.269) (xy 38.1 -247.777) (xy 37.719 -248.158) (xy 34.417 -248.158)
				(xy 34.29 -248.285) (xy 34.29 -252.8824) (xy 32.004 -252.8824) (xy 31.75 -253.1364) (xy 31.75 -256.2606)
				(xy 34.0106 -258.5212) (xy 36.7284 -258.5212) (xy 36.8808 -258.3688) (xy 36.8808 -257.1242) (xy 36.576 -256.8194)
				(xy 36.576 -255.6764) (xy 36.8554 -255.397) (xy 39.37 -255.397) (xy 41.148 -253.619) (xy 41.148 -251.841)
				(xy 39.878 -250.571) (xy 39.878 -247.65)
			)
		)
		(polygon
			(pts
				(xy 36.322 -240.792) (xy 33.274 -240.792) (xy 33.02 -241.046) (xy 33.02 -242.189) (xy 33.775904 -242.944904)
				(xy 33.775904 -243.049552) (xy 34.064448 -243.338096) (xy 34.169096 -243.338096) (xy 34.417 -243.586)
				(xy 34.417 -244.729) (xy 39.243 -244.729) (xy 39.243 -243.713)
			)
		)
		(polygon
			(pts
				(xy 30.1752 -239.2172) (xy 28.067 -239.2172) (xy 27.1526 -240.1316) (xy 27.1526 -241.554) (xy 27.94 -242.3414)
				(xy 30.1244 -242.3414) (xy 30.353 -242.1128) (xy 30.353 -239.395)
			)
		)
		(polygon
			(pts
				(xy 21.082 -239.141) (xy 15.113 -239.141) (xy 14.605 -239.649) (xy 14.605 -245.999) (xy 14.478 -246.126)
				(xy 14.097 -246.126) (xy 13.716 -246.507) (xy 13.716 -248.92) (xy 14.097 -249.301) (xy 14.097 -249.428)
				(xy 14.605 -249.936) (xy 18.669 -249.936) (xy 18.669 -251.079) (xy 18.923 -251.333) (xy 22.987 -251.333)
				(xy 24.765 -249.555) (xy 26.035 -249.555) (xy 26.67 -248.92) (xy 26.67 -245.618) (xy 24.638 -243.586)
				(xy 24.511 -243.586) (xy 24.384 -243.713) (xy 22.606 -243.713) (xy 21.082 -242.189) (xy 21.082 -240.03)
				(xy 21.463 -239.649) (xy 21.463 -239.522)
			)
		)
		(polygon
			(pts
				(xy 15.875 -225.171) (xy 13.2334 -225.171) (xy 12.5349 -225.8695) (xy 12.5095 -225.8695) (xy 11.303 -227.076)
				(xy 11.303 -229.235) (xy 14.859 -232.791) (xy 14.859 -233.172) (xy 18.542 -229.489) (xy 18.542 -227.838)
			)
		)
		(polygon
			(pts
				(xy 29.083 -214.63) (xy 22.733 -214.63) (xy 21.463 -215.9) (xy 20.828 -215.9) (xy 20.828 -221.742)
				(xy 21.59 -222.504) (xy 24.003 -222.504) (xy 24.892 -223.393) (xy 26.737564 -223.393) (xy 26.737564 -223.79686)
				(xy 26.645108 -223.88957)
				(arc
					(start 26.645108 -224.0534)
					(mid 26.622121 -224.187974)
					(end 26.555954 -224.3074)
				)
				(arc
					(start 26.555954 -224.3074)
					(mid 26.596056 -224.36795)
					(end 26.624788 -224.434654)
				)
				(arc
					(start 26.624788 -224.434654)
					(mid 26.697768 -224.501747)
					(end 26.79319 -224.474786)
				)
				(xy 26.94813 -224.319592)
				(arc
					(start 27.509724 -224.319592)
					(mid 27.592538 -224.277208)
					(end 27.60599 -224.185226)
				)
				(arc
					(start 27.60599 -224.185226)
					(mid 27.589459 -224.120232)
					(end 27.583892 -224.0534)
				)
				(arc
					(start 27.583892 -223.6978)
					(mid 27.592509 -223.614759)
					(end 27.617928 -223.53524)
				)
				(arc
					(start 27.617928 -223.53524)
					(mid 27.60985 -223.438991)
					(end 27.524964 -223.393)
				)
				(arc
					(start 28.812236 -223.393)
					(mid 28.727427 -223.439041)
					(end 28.719272 -223.53524)
				)
				(arc
					(start 28.719272 -223.53524)
					(mid 28.744653 -223.614767)
					(end 28.753308 -223.6978)
				)
				(arc
					(start 28.753308 -224.0534)
					(mid 28.730321 -224.187974)
					(end 28.664154 -224.3074)
				)
				(arc
					(start 28.664154 -224.3074)
					(mid 28.704503 -224.368541)
					(end 28.733242 -224.435924)
				)
				(arc
					(start 28.733242 -224.435924)
					(mid 28.810049 -224.504394)
					(end 28.907232 -224.470722)
				)
				(arc
					(start 28.907232 -224.470722)
					(mid 29.054768 -224.359214)
					(end 29.2354 -224.319592)
				)
				(arc
					(start 29.643324 -224.319592)
					(mid 29.726138 -224.277208)
					(end 29.73959 -224.185226)
				)
				(arc
					(start 29.73959 -224.185226)
					(mid 29.723059 -224.120232)
					(end 29.717492 -224.0534)
				)
				(xy 29.717746 -223.88957) (xy 29.221176 -223.393) (xy 30.226 -223.393) (xy 30.607 -223.012) (xy 30.607 -217.17)
				(xy 29.337 -215.9) (xy 29.337 -214.884)
			)
		)
		(polygon
			(pts
				(arc
					(start 28.84932 -211.74583)
					(mid 28.7782 -211.716739)
					(end 28.70708 -211.74583)
				)
				(arc
					(start 28.70708 -211.74583)
					(mid 28.576224 -211.831768)
					(end 28.4226 -211.861908)
				)
				(xy 28.27655 -211.861908) (xy 27.991816 -212.146642) (xy 27.991816 -213.087458) (xy 27.992324 -213.087966)
				(xy 27.992324 -213.893908) (xy 28.427172 -213.893908) (xy 28.427172 -213.22665) (xy 29.48813 -212.165692)
				(xy 29.801566 -212.165692)
				(arc
					(start 29.816806 -212.149436)
					(mid 29.86812 -212.099662)
					(end 29.924502 -212.05571)
				)
				(xy 29.946092 -212.04047) (xy 29.946092 -211.773262) (xy 29.929328 -211.758022)
				(arc
					(start 29.91612 -211.74583)
					(mid 29.845 -211.716739)
					(end 29.77388 -211.74583)
				)
				(arc
					(start 29.77388 -211.74583)
					(mid 29.643024 -211.831768)
					(end 29.4894 -211.861908)
				)
				(arc
					(start 29.1338 -211.861908)
					(mid 28.980174 -211.831773)
					(end 28.84932 -211.74583)
				)
			)
		)
		(polygon
			(pts
				(xy 27.26563 -210.033108)
				(arc
					(start 26.812748 -210.033108)
					(mid 26.734208 -210.070256)
					(end 26.71318 -210.15452)
				)
				(arc
					(start 26.71318 -210.15452)
					(mid 26.719248 -210.19445)
					(end 26.721308 -210.234784)
				)
				(arc
					(start 26.721308 -210.590384)
					(mid 26.698321 -210.724958)
					(end 26.632154 -210.844384)
				)
				(arc
					(start 26.632154 -210.844384)
					(mid 26.698366 -210.963794)
					(end 26.721308 -211.098384)
				)
				(arc
					(start 26.721308 -211.453984)
					(mid 26.715586 -211.521729)
					(end 26.698702 -211.587588)
				)
				(xy 26.695908 -211.595716) (xy 26.695908 -212.427566)
				(arc
					(start 26.712164 -212.442806)
					(mid 26.854987 -212.633109)
					(end 26.921206 -212.861652)
				)
				(arc
					(start 26.921206 -212.861652)
					(mid 26.95433 -212.927012)
					(end 27.022806 -212.953092)
				)
				(arc
					(start 27.025854 -212.953092)
					(mid 27.097532 -212.923244)
					(end 27.1272 -212.851492)
				)
				(xy 27.1272 -211.788502) (xy 27.660092 -211.25561)
				(arc
					(start 27.660092 -211.0994)
					(mid 27.683079 -210.964826)
					(end 27.749246 -210.8454)
				)
				(arc
					(start 27.749246 -210.8454)
					(mid 27.683034 -210.72599)
					(end 27.660092 -210.5914)
				)
				(xy 27.660092 -210.590384) (xy 27.660346 -210.42757)
			)
		)
		(polygon
			(pts
				(xy 28.216352 -209.416904) (xy 27.604466 -209.416904)
				(arc
					(start 27.589734 -209.431636)
					(mid 27.475609 -209.519856)
					(end 27.343354 -209.577432)
				)
				(arc
					(start 27.343354 -209.577432)
					(mid 27.273535 -209.649853)
					(end 27.300174 -209.74685)
				)
				(xy 27.382978 -209.829654)
				(arc
					(start 27.400758 -209.831432)
					(mid 27.53521 -209.870633)
					(end 27.648408 -209.953098)
				)
				(xy 27.663394 -209.968592) (xy 27.759406 -209.968592)
				(arc
					(start 27.774392 -209.953098)
					(mid 27.908054 -209.861203)
					(end 28.067 -209.828892)
				)
				(xy 28.403296 -209.828892) (xy 28.403296 -209.603848)
			)
		)
		(polygon
			(pts
				(xy 27.686 -193.5226) (xy 27.432 -193.5226) (xy 27.432 -193.7766) (xy 27.686 -193.7766)
			)
		)
		(polygon
			(pts
				(xy 23.1902 -186.436) (xy 22.9362 -186.436) (xy 22.9362 -186.69) (xy 23.1902 -186.69)
			)
		)
		(polygon
			(pts
				(xy 23.1902 -185.8772) (xy 22.9362 -185.8772) (xy 22.9362 -186.1312) (xy 23.1902 -186.1312)
			)
		)
		(polygon
			(pts
				(xy 37.8206 -179.5018) (xy 37.5666 -179.5018) (xy 37.5666 -179.7558) (xy 37.8206 -179.7558)
			)
		)
		(polygon
			(pts
				(xy 35.306 -178.816) (xy 32.131 -178.816) (xy 31.877 -179.07) (xy 31.877 -181.356) (xy 30.734 -182.499)
				(xy 30.099 -182.499) (xy 28.956 -183.642) (xy 28.956 -184.658) (xy 29.083 -184.785) (xy 30.226 -184.785)
				(xy 31.496 -186.055) (xy 32.639 -186.055) (xy 33.909 -187.325) (xy 35.433 -187.325) (xy 35.687 -187.071)
				(xy 35.687 -179.197)
			)
		)
		(polygon
			(pts
				(xy 21.59 -177.673) (xy 19.812 -177.673) (xy 19.812 -177.8) (xy 19.939 -177.927) (xy 19.939 -179.578)
				(xy 19.558 -179.959) (xy 19.558 -181.8005) (xy 19.431 -181.9275) (xy 15.6845 -181.9275) (xy 11.049 -186.563)
				(xy 2.794 -186.563) (xy 2.667 -186.69) (xy 2.667 -199.263) (xy 2.921 -199.517) (xy 4.445 -199.517)
				(xy 4.953 -199.009) (xy 4.953 -198.247) (xy 5.207 -197.993) (xy 15.24 -197.993) (xy 17.653 -200.406)
				(xy 21.971 -200.406) (xy 22.225 -200.66) (xy 22.225 -200.406) (xy 22.479 -200.152) (xy 22.479 -199.39)
				(xy 22.733 -199.136) (xy 22.733 -182.753) (xy 22.225 -182.245) (xy 23.241 -181.229) (xy 23.749 -181.229)
				(xy 24.003 -180.975) (xy 24.003 -178.943) (xy 23.622 -178.562) (xy 22.479 -178.562)
			)
		)
		(polygon
			(pts
				(xy 39.6494 -177.2158) (xy 39.3954 -177.2158) (xy 39.3954 -177.4698) (xy 39.6494 -177.4698)
			)
		)
		(polygon
			(pts
				(xy 39.0906 -177.2158) (xy 38.8366 -177.2158) (xy 38.8366 -177.4698) (xy 39.0906 -177.4698)
			)
		)
		(polygon
			(pts
				(xy 38.6588 -177.165) (xy 38.4048 -177.165) (xy 38.4048 -177.419) (xy 38.6588 -177.419)
			)
		)
		(polygon
			(pts
				(xy 38.0492 -177.165) (xy 37.7952 -177.165) (xy 37.7952 -177.419) (xy 38.0492 -177.419)
			)
		)
		(polygon
			(pts
				(xy 43.0022 -176.4284) (xy 42.7482 -176.4284) (xy 42.7482 -176.6824) (xy 43.0022 -176.6824)
			)
		)
		(polygon
			(pts
				(xy 42.291 -175.514) (xy 41.529 -175.514) (xy 40.767 -176.276) (xy 40.767 -177.419) (xy 41.021 -177.673)
				(xy 42.037 -177.673) (xy 42.037 -176.53) (xy 42.418 -176.149) (xy 42.418 -175.641)
			)
		)
		(polygon
			(pts
				(xy 27.7114 -171.1452) (xy 27.6098 -171.1452) (xy 27.559 -171.196) (xy 27.559 -176.276) (xy 27.813 -176.53)
				(xy 28.702 -176.53) (xy 28.829 -176.403) (xy 33.274 -176.403) (xy 33.528 -176.149) (xy 33.528 -171.958)
				(xy 32.893 -171.323) (xy 27.8892 -171.323)
			)
		)
		(polygon
			(pts
				(xy 36.321492 -137.058908) (xy 35.393884 -137.058908) (xy 35.32632 -137.126218)
				(arc
					(start 35.32632 -137.254234)
					(mid 35.319893 -137.326757)
					(end 35.300666 -137.396982)
				)
				(arc
					(start 35.300666 -137.396982)
					(mid 35.312167 -137.49055)
					(end 35.395662 -137.534396)
				)
				(xy 36.321492 -137.534396)
			)
		)
		(polygon
			(pts
				(arc
					(start 8.987028 -67.695572)
					(mid 8.852457 -67.672749)
					(end 8.733028 -67.606672)
				)
				(arc
					(start 8.733028 -67.606672)
					(mid 8.613594 -67.672734)
					(end 8.479028 -67.695572)
				)
				(xy 8.367014 -67.695572) (xy 7.737094 -68.325492)
				(arc
					(start 7.74065 -68.350892)
					(mid 7.747177 -68.423143)
					(end 7.74573 -68.495672)
				)
				(arc
					(start 7.74573 -68.495672)
					(mid 7.77248 -68.572317)
					(end 7.846822 -68.604892)
				)
				(xy 8.011668 -68.604892)
				(arc
					(start 8.019796 -68.602098)
					(mid 8.085649 -68.585175)
					(end 8.1534 -68.579492)
				)
				(arc
					(start 8.509 -68.579492)
					(mid 8.643574 -68.602479)
					(end 8.763 -68.668646)
				)
				(arc
					(start 8.763 -68.668646)
					(mid 8.88241 -68.602434)
					(end 9.017 -68.579492)
				)
				(arc
					(start 9.3726 -68.579492)
					(mid 9.526226 -68.609627)
					(end 9.65708 -68.69557)
				)
				(arc
					(start 9.65708 -68.69557)
					(mid 9.7282 -68.724661)
					(end 9.79932 -68.69557)
				)
				(arc
					(start 9.79932 -68.69557)
					(mid 9.930176 -68.609632)
					(end 10.0838 -68.579492)
				)
				(xy 10.303002 -68.579492)
				(arc
					(start 10.592562 -68.290186)
					(mid 10.614398 -68.179641)
					(end 10.52068 -68.116958)
				)
				(xy 9.652762 -68.116958) (xy 9.23163 -67.695572)
			)
		)
		(polygon
			(pts
				(xy 8.330692 -17.674844) (xy 4.985512 -17.674844)
				(arc
					(start 4.972304 -17.705578)
					(mid 4.766813 -18.010872)
					(end 4.466082 -18.222976)
				)
				(arc
					(start 4.466082 -18.222976)
					(mid 4.437062 -18.261688)
					(end 4.453636 -18.30705)
				)
				(arc
					(start 4.453636 -18.30705)
					(mid 4.474941 -18.326882)
					(end 4.495292 -18.34769)
				)
				(xy 4.510278 -18.363692) (xy 8.711692 -18.363692) (xy 10.273792 -19.925792) (xy 16.928592 -19.925792)
				(xy 16.928592 -18.947892)
				(arc
					(start 18.533872 -18.947892)
					(mid 18.627496 -18.885753)
					(end 18.606516 -18.775426)
				)
				(arc
					(start 18.606516 -18.775426)
					(mid 18.560598 -18.718999)
					(end 18.52549 -18.655284)
				)
				(arc
					(start 18.52549 -18.655284)
					(mid 18.498445 -18.628889)
					(end 18.46072 -18.628614)
				)
				(arc
					(start 18.46072 -18.628614)
					(mid 18.388574 -18.649022)
					(end 18.313908 -18.655792)
				)
				(arc
					(start 17.907254 -18.655792)
					(mid 17.750473 -18.624354)
					(end 17.617948 -18.534888)
				)
				(arc
					(start 17.617948 -18.534888)
					(mid 17.584841 -18.519885)
					(end 17.55013 -18.530824)
				)
				(arc
					(start 17.55013 -18.530824)
					(mid 17.431004 -18.59649)
					(end 17.296892 -18.619216)
				)
				(xy 17.07769 -18.619216) (xy 15.891002 -19.805904) (xy 10.461752 -19.805904)
			)
		)
	)
	(zone
		(layer "F.Cu")
		(hatch none 0.5)
		(connect_pads
			(clearance 0)
		)
		(min_thickness 0.25)
		(keepout
			(tracks allowed)
			(vias allowed)
			(pads allowed)
			(copperpour allowed)
			(footprints not_allowed)
		)
		(placement
			(enabled no)
			(sheetname "")
		)
		(fill
			(thermal_gap 0.5)
			(thermal_bridge_width 0.5)
			(island_removal_mode 0)
		)
		(polygon
			(pts
				(arc
					(start 45.500036 -298.99991)
					(mid 41.500044 -294.999918)
					(end 45.500036 -290.999926)
				)
				(arc
					(start 45.500036 -290.999926)
					(mid 49.500028 -294.999918)
					(end 45.500036 -298.99991)
				)
			)
		)
	)
	(zone
		(net "P12V")
		(layer "F.Cu")
		(hatch none 0.5)
		(connect_pads
			(clearance 0.5)
		)
		(min_thickness 0.25)
		(fill yes
			(thermal_gap 0.5)
			(thermal_bridge_width 0.5)
			(island_removal_mode 0)
		)
		(polygon
			(pts
				(xy 22.4536 -181.991) (xy 22.4536 -207.2386) (xy 22.606 -207.391) (xy 27.178 -207.391) (xy 28.1686 -206.4004)
				(xy 28.1686 -182.118) (xy 28.1686 -181.3306) (xy 27.686 -180.848) (xy 23.114 -180.848) (xy 22.4536 -181.5084)
			)
		)
	)
	(zone
		(net "P12V")
		(layer "F.Cu")
		(hatch none 0.5)
		(connect_pads
			(clearance 0.5)
		)
		(min_thickness 0.25)
		(fill yes
			(thermal_gap 0.5)
			(thermal_bridge_width 0.5)
			(island_removal_mode 0)
		)
		(polygon
			(pts
				(xy 17.526 -476.885) (xy 17.526 -480.568) (xy 18.415 -481.457) (xy 34.925 -481.457) (xy 36.195 -480.187)
				(xy 36.576 -479.806) (xy 36.576 -478.155) (xy 36.576 -476.758) (xy 36.322 -476.504) (xy 17.907 -476.504)
			)
		)
	)
	(zone
		(net "GND")
		(layer "F.Cu")
		(hatch none 0.5)
		(connect_pads
			(clearance 0.5)
		)
		(min_thickness 0.25)
		(fill yes
			(thermal_gap 0.5)
			(thermal_bridge_width 0.5)
			(island_removal_mode 0)
		)
		(polygon
			(pts
				(xy 20.193 -143.891) (xy 20.828 -143.256) (xy 20.828 -141.605) (xy 20.701 -141.478) (xy 18.669 -141.478)
				(xy 18.161 -140.97) (xy 18.161 -136.271) (xy 18.669 -135.763) (xy 21.209 -135.763) (xy 21.59 -135.382)
				(xy 21.59 -134.747) (xy 21.59 -134.366) (xy 21.1582 -133.9342) (xy 20.2692 -133.9342) (xy 6.9596 -133.9342)
				(xy 6.858 -134.0358) (xy 6.858 -135.636) (xy 8.509 -137.287) (xy 8.509 -142.113) (xy 8.89 -142.494)
				(xy 14.859 -142.494) (xy 15.494 -143.129) (xy 18.415 -143.129) (xy 19.304 -144.018) (xy 20.193 -144.018)
			)
		)
	)
	(zone
		(net "P3V3_LX")
		(layer "F.Cu")
		(hatch none 0.5)
		(connect_pads
			(clearance 0.5)
		)
		(min_thickness 0.25)
		(fill yes
			(thermal_gap 0.5)
			(thermal_bridge_width 0.5)
			(island_removal_mode 0)
		)
		(polygon
			(pts
				(xy 18.0594 -239.5728) (xy 15.0876 -239.5728) (xy 14.859 -239.8014) (xy 14.859 -246.253) (xy 15.3797 -246.7737)
				(xy 17.3609 -246.7737) (xy 17.907 -247.3198) (xy 18.288 -247.3198) (xy 18.288 -247.2944) (xy 18.542 -247.2944)
				(xy 18.542 -247.3198) (xy 20.1676 -247.3198) (xy 20.2057 -247.2817) (xy 20.2057 -245.2243) (xy 18.4912 -243.5098)
				(xy 18.4912 -240.0046)
			)
		)
	)
	(zone
		(net "GND")
		(layer "F.Cu")
		(hatch none 0.5)
		(connect_pads
			(clearance 0.5)
		)
		(min_thickness 0.25)
		(fill yes
			(thermal_gap 0.5)
			(thermal_bridge_width 0.5)
			(island_removal_mode 0)
		)
		(polygon
			(pts
				(xy 5.588 -192.659) (xy 6.096 -192.659) (xy 7.62 -191.135) (xy 14.732 -191.135) (xy 17.272 -188.595)
				(xy 18.669 -188.595) (xy 19.558 -187.706) (xy 19.558 -186.69) (xy 19.812 -186.436) (xy 19.812 -185.42)
				(xy 19.685 -185.293) (xy 18.288 -185.293) (xy 17.78 -184.785) (xy 15.621 -184.785) (xy 12.446 -187.96)
				(xy 6.477 -187.96) (xy 5.207 -189.23) (xy 5.207 -192.278)
			)
		)
	)
	(zone
		(net "GND")
		(layer "F.Cu")
		(hatch none 0.5)
		(connect_pads
			(clearance 0.5)
		)
		(min_thickness 0.25)
		(fill yes
			(thermal_gap 0.5)
			(thermal_bridge_width 0.5)
			(island_removal_mode 0)
		)
		(polygon
			(pts
				(xy 21.463 -249.174) (xy 20.955 -249.174) (xy 20.828 -249.047) (xy 20.828 -246.761) (xy 20.955 -246.634)
				(xy 21.463 -246.634) (xy 21.59 -246.761) (xy 21.59 -247.65) (xy 23.368 -247.65) (xy 23.495 -247.523)
				(xy 23.495 -246.634) (xy 23.622 -246.507) (xy 24.511 -246.507) (xy 24.638 -246.634) (xy 24.638 -248.412)
				(xy 24.511 -248.539) (xy 23.368 -248.539) (xy 23.114 -248.285) (xy 21.844 -248.285) (xy 21.717 -248.412)
				(xy 21.717 -248.92)
			)
		)
	)
	(zone
		(layer "F.Cu")
		(hatch none 0.5)
		(connect_pads
			(clearance 0)
		)
		(min_thickness 0.25)
		(keepout
			(tracks allowed)
			(vias allowed)
			(pads allowed)
			(copperpour allowed)
			(footprints allowed)
		)
		(placement
			(enabled no)
			(sheetname "")
		)
		(fill
			(thermal_gap 0.5)
			(thermal_bridge_width 0.5)
			(island_removal_mode 0)
		)
		(polygon
			(pts
				(xy 32.0548 -370.1288) (xy 32.0548 -368.7572) (xy 33.7058 -368.7572) (xy 33.7058 -370.1288)
			)
		)
	)
	(zone
		(net "P12V")
		(layer "F.Cu")
		(hatch none 0.5)
		(connect_pads
			(clearance 0.5)
		)
		(min_thickness 0.25)
		(fill yes
			(thermal_gap 0.5)
			(thermal_bridge_width 0.5)
			(island_removal_mode 0)
		)
		(polygon
			(pts
				(xy 21.4122 -29.5148) (xy 27.559 -29.5148) (xy 30.3784 -26.6954) (xy 30.3784 -15.24) (xy 26.9748 -11.8364)
				(xy 21.9456 -11.8364) (xy 21.1836 -12.5984) (xy 21.1836 -13.3604) (xy 21.717 -13.8938) (xy 22.1742 -14.351)
				(xy 23.9776 -14.351) (xy 24.1046 -14.478) (xy 24.1046 -19.177) (xy 22.987 -19.177) (xy 21.844 -19.177)
				(xy 21.336 -19.177) (xy 21.209 -19.304) (xy 21.209 -19.812) (xy 21.1455 -19.8755) (xy 21.1455 -21.0185)
				(xy 21.1455 -23.0505) (xy 21.1455 -29.2481)
			)
		)
	)
	(zone
		(net "GND")
		(layer "F.Cu")
		(hatch none 0.5)
		(connect_pads
			(clearance 0.5)
		)
		(min_thickness 0.25)
		(fill yes
			(thermal_gap 0.5)
			(thermal_bridge_width 0.5)
			(island_removal_mode 0)
		)
		(polygon
			(pts
				(xy 28.067 -149.733) (xy 28.067 -148.59) (xy 27.178 -147.701) (xy 25.273 -147.701) (xy 24.003 -148.971)
				(xy 24.003 -150.114) (xy 24.13 -150.241) (xy 24.892 -150.241) (xy 25.908 -151.257) (xy 26.543 -151.257)
			)
		)
	)
	(zone
		(net "P12V_FAN1")
		(layer "F.Cu")
		(hatch none 0.5)
		(connect_pads
			(clearance 0.5)
		)
		(min_thickness 0.25)
		(fill yes
			(thermal_gap 0.5)
			(thermal_bridge_width 0.5)
			(island_removal_mode 0)
		)
		(polygon
			(pts
				(xy 14.478 -484.251) (xy 7.874 -484.251) (xy 7.112 -483.489) (xy 2.667 -483.489) (xy 2.413 -483.743)
				(xy 2.413 -485.775) (xy 3.048 -486.41) (xy 4.826 -486.41) (xy 5.715 -487.299) (xy 27.305 -487.299)
				(xy 27.559 -487.045) (xy 27.559 -482.346) (xy 26.924 -481.711) (xy 17.018 -481.711)
			)
		)
	)
	(zone
		(net "P12V")
		(layer "F.Cu")
		(hatch none 0.5)
		(connect_pads
			(clearance 0.5)
		)
		(min_thickness 0.25)
		(fill yes
			(thermal_gap 0.5)
			(thermal_bridge_width 0.5)
			(island_removal_mode 0)
		)
		(polygon
			(pts
				(xy 15.3924 -121.92) (xy 10.16 -121.92) (xy 7.874 -124.206) (xy 7.874 -131.445) (xy 7.8994 -131.4704)
				(xy 7.8994 -132.4102) (xy 9.0424 -133.5532) (xy 21.7424 -133.5532) (xy 23.2664 -133.5532) (xy 23.3045 -133.5151)
				(xy 24.4729 -133.5151) (xy 24.511 -133.5532) (xy 28.2194 -133.5532) (xy 28.2956 -133.6294) (xy 36.8808 -133.6294)
				(xy 39.3954 -133.6294) (xy 39.497 -133.5278) (xy 39.5732 -133.4516) (xy 43.942 -133.4516) (xy 44.0182 -133.5278)
				(xy 44.1198 -133.6294) (xy 51.5366 -133.6294) (xy 51.689 -133.477) (xy 51.689 -133.3754) (xy 51.689 -131.445)
				(xy 51.689 -122.174) (xy 51.435 -121.92) (xy 47.0662 -121.92) (xy 46.8122 -122.174) (xy 46.8122 -123.1646)
				(xy 46.6344 -123.3424) (xy 38.4556 -123.3424) (xy 38.3032 -123.19) (xy 38.3032 -122.2756) (xy 37.9476 -121.92)
				(xy 37.4015 -121.92) (xy 25.2476 -121.92) (xy 24.8158 -122.3518) (xy 24.8158 -123.0376) (xy 24.4348 -123.4186)
				(xy 24.3332 -123.5202) (xy 16.9926 -123.5202) (xy 16.891 -123.4186) (xy 16.6878 -123.2154)
			)
		)
	)
	(zone
		(net "P12V_FAN5")
		(layer "F.Cu")
		(hatch none 0.5)
		(connect_pads
			(clearance 0.5)
		)
		(min_thickness 0.25)
		(fill yes
			(thermal_gap 0.5)
			(thermal_bridge_width 0.5)
			(island_removal_mode 0)
		)
		(polygon
			(pts
				(xy 6.1976 -129.032) (xy 2.286 -129.032) (xy 1.9558 -129.3622) (xy 1.9558 -149.6568) (xy 9.271 -156.972)
				(xy 20.828 -156.972) (xy 21.7297 -156.0703) (xy 21.7297 -152.8953) (xy 20.8534 -152.019) (xy 9.398 -152.019)
				(xy 5.5372 -148.1582) (xy 5.5372 -136.652) (xy 5.5499 -136.6393) (xy 5.5499 -134.7597) (xy 7.5438 -132.7658)
				(xy 7.5438 -130.3782) (xy 6.5532 -129.3876)
			)
		)
	)
	(zone
		(layer "F.Cu")
		(hatch none 0.5)
		(connect_pads
			(clearance 0)
		)
		(min_thickness 0.25)
		(keepout
			(tracks allowed)
			(vias allowed)
			(pads allowed)
			(copperpour allowed)
			(footprints not_allowed)
		)
		(placement
			(enabled no)
			(sheetname "")
		)
		(fill
			(thermal_gap 0.5)
			(thermal_bridge_width 0.5)
			(island_removal_mode 0)
		)
		(polygon
			(pts
				(arc
					(start 45.500036 -148.999956)
					(mid 41.500044 -144.999964)
					(end 45.500036 -140.999972)
				)
				(arc
					(start 45.500036 -140.999972)
					(mid 49.500028 -144.999964)
					(end 45.500036 -148.999956)
				)
			)
		)
	)
	(zone
		(layer "F.Cu")
		(hatch none 0.5)
		(connect_pads
			(clearance 0)
		)
		(min_thickness 0.25)
		(keepout
			(tracks allowed)
			(vias allowed)
			(pads allowed)
			(copperpour allowed)
			(footprints not_allowed)
		)
		(placement
			(enabled no)
			(sheetname "")
		)
		(fill
			(thermal_gap 0.5)
			(thermal_bridge_width 0.5)
			(island_removal_mode 0)
		)
		(polygon
			(pts
				(arc
					(start 4.500118 -336.00009)
					(mid 8.50011 -340.000082)
					(end 4.500118 -344.000074)
				)
				(arc
					(start 4.500118 -344.000074)
					(mid 0.500126 -340.000082)
					(end 4.500118 -336.00009)
				)
			)
		)
	)
	(zone
		(layer "F.Cu")
		(hatch none 0.5)
		(connect_pads
			(clearance 0)
		)
		(min_thickness 0.25)
		(keepout
			(tracks allowed)
			(vias allowed)
			(pads allowed)
			(copperpour allowed)
			(footprints allowed)
		)
		(placement
			(enabled no)
			(sheetname "")
		)
		(fill
			(thermal_gap 0.5)
			(thermal_bridge_width 0.5)
			(island_removal_mode 0)
		)
		(polygon
			(pts
				(xy 24.5364 -144.3736) (xy 19.4564 -144.3736) (xy 19.4564 -136.7282) (xy 24.5364 -136.7282)
			)
		)
	)
	(zone
		(net "P12V_AUX")
		(layer "F.Cu")
		(hatch none 0.5)
		(connect_pads
			(clearance 0.5)
		)
		(min_thickness 0.25)
		(fill yes
			(thermal_gap 0.5)
			(thermal_bridge_width 0.5)
			(island_removal_mode 0)
		)
		(polygon
			(pts
				(xy 13.5636 -410.718) (xy 12.573 -411.7086) (xy 12.573 -415.5694) (xy 12.8905 -415.8869) (xy 12.8905 -416.6235)
				(xy 12.7 -416.814) (xy 12.7 -442.087) (xy 15.494 -444.881) (xy 15.494 -449.58) (xy 15.494 -453.32142)
				(xy 15.48638 -453.32142) (xy 15.24 -453.5678) (xy 15.24 -474.472) (xy 16.891 -476.123) (xy 30.861 -476.123)
				(xy 32.131 -474.853) (xy 32.512 -474.472) (xy 32.512 -425.831) (xy 32.639 -425.704) (xy 34.925 -423.418)
				(xy 36.068 -423.418) (xy 46.101 -423.418) (xy 46.736 -422.783) (xy 46.736 -422.148) (xy 46.736 -411.607)
				(xy 45.847 -410.718)
			)
		)
	)
	(zone
		(layer "F.Cu")
		(hatch none 0.5)
		(connect_pads
			(clearance 0)
		)
		(min_thickness 0.25)
		(keepout
			(tracks allowed)
			(vias allowed)
			(pads allowed)
			(copperpour allowed)
			(footprints not_allowed)
		)
		(placement
			(enabled no)
			(sheetname "")
		)
		(fill
			(thermal_gap 0.5)
			(thermal_bridge_width 0.5)
			(island_removal_mode 0)
		)
		(polygon
			(pts
				(arc
					(start 45.500036 -290.999926)
					(mid 49.500028 -294.999918)
					(end 45.500036 -298.99991)
				)
				(arc
					(start 45.500036 -298.99991)
					(mid 41.500044 -294.999918)
					(end 45.500036 -290.999926)
				)
			)
		)
	)
	(zone
		(net "P12VU")
		(layer "F.Cu")
		(hatch none 0.5)
		(connect_pads
			(clearance 0.5)
		)
		(min_thickness 0.25)
		(fill yes
			(thermal_gap 0.5)
			(thermal_bridge_width 0.5)
			(island_removal_mode 0)
		)
		(polygon
			(pts
				(xy 10.414 -72.263) (xy 9.652 -73.025) (xy 9.652 -80.137) (xy 11.43 -81.915) (xy 11.43 -88.519)
				(xy 9.8425 -90.1065) (xy 9.8425 -110.5535) (xy 11.938 -112.649) (xy 21.59 -112.649) (xy 21.844 -112.649)
				(xy 25.273 -112.649) (xy 26.3144 -112.649) (xy 27.432 -112.649) (xy 27.559 -112.522) (xy 27.559 -110.744)
				(xy 27.432 -110.617) (xy 27.305 -110.49) (xy 26.162 -110.49) (xy 24.13 -108.458) (xy 24.13 -97.282)
				(xy 24.13 -95.3262) (xy 24.1554 -95.3008) (xy 24.1554 -95.2246) (xy 23.495 -94.5642) (xy 23.495 -89.5858)
				(xy 23.9268 -89.154) (xy 24.5872 -89.154) (xy 26.289 -89.154) (xy 27.051 -88.392) (xy 27.051 -80.391)
				(xy 30.48 -76.962) (xy 30.48 -66.6496) (xy 30.2514 -66.421) (xy 28.3718 -64.5414) (xy 19.9136 -64.5414)
				(xy 18.3134 -66.1416) (xy 18.3134 -68.2498) (xy 18.3134 -71.4248) (xy 17.4752 -72.263)
			)
		)
	)
	(zone
		(net "GND")
		(layer "F.Cu")
		(hatch none 0.5)
		(connect_pads
			(clearance 0.5)
		)
		(min_thickness 0.25)
		(fill yes
			(thermal_gap 0.5)
			(thermal_bridge_width 0.5)
			(island_removal_mode 0)
		)
		(polygon
			(pts
				(xy 28.448 -110.236) (xy 28.702 -109.982) (xy 28.829 -109.855) (xy 28.829 -109.22) (xy 28.829 -98.298)
				(xy 28.829 -95.377) (xy 29.464 -94.742) (xy 29.464 -93.98) (xy 29.464 -89.8144) (xy 29.2608 -89.6112)
				(xy 23.876 -89.6112) (xy 23.6982 -89.789) (xy 23.6982 -94.361) (xy 24.384 -95.0468) (xy 24.384 -98.552)
				(xy 24.384 -108.331) (xy 26.289 -110.236)
			)
		)
	)
	(zone
		(net "GND")
		(layer "F.Cu")
		(hatch none 0.5)
		(connect_pads
			(clearance 0.5)
		)
		(min_thickness 0.25)
		(fill yes
			(thermal_gap 0.5)
			(thermal_bridge_width 0.5)
			(island_removal_mode 0)
		)
		(polygon
			(pts
				(xy 30.226 -145.542) (xy 30.226 -148.717) (xy 30.607 -149.098) (xy 33.528 -149.098) (xy 34.671 -150.241)
				(xy 35.687 -150.241) (xy 36.449 -151.003) (xy 36.83 -151.384) (xy 36.83 -154.686) (xy 36.957 -154.813)
				(xy 37.338 -154.813) (xy 37.592 -154.559) (xy 37.592 -153.924) (xy 37.846 -153.67) (xy 39.243 -153.67)
				(xy 39.37 -153.543) (xy 39.37 -153.416) (xy 40.005 -152.781) (xy 40.005 -151.003) (xy 37.6936 -148.6916)
				(xy 36.2712 -148.6916) (xy 35.0647 -147.4851) (xy 35.0647 -146.0627) (xy 32.766 -143.764) (xy 29.845 -143.764)
				(xy 29.718 -143.891) (xy 29.718 -145.034)
			)
		)
	)
	(zone
		(layer "F.Cu")
		(hatch none 0.5)
		(connect_pads
			(clearance 0)
		)
		(min_thickness 0.25)
		(keepout
			(tracks allowed)
			(vias allowed)
			(pads allowed)
			(copperpour allowed)
			(footprints not_allowed)
		)
		(placement
			(enabled no)
			(sheetname "")
		)
		(fill
			(thermal_gap 0.5)
			(thermal_bridge_width 0.5)
			(island_removal_mode 0)
		)
		(polygon
			(pts
				(arc
					(start 15.999968 -387.160008)
					(mid 15.267774 -388.927682)
					(end 13.5001 -389.659876)
				)
				(xy 0 -389.659876) (xy 0 -355.659944)
				(arc
					(start 13.5001 -355.659944)
					(mid 15.267789 -356.392303)
					(end 15.999968 -358.160066)
				)
			)
		)
	)
	(zone
		(layer "F.Cu")
		(hatch none 0.5)
		(connect_pads
			(clearance 0)
		)
		(min_thickness 0.25)
		(keepout
			(tracks allowed)
			(vias allowed)
			(pads allowed)
			(copperpour allowed)
			(footprints not_allowed)
		)
		(placement
			(enabled no)
			(sheetname "")
		)
		(fill
			(thermal_gap 0.5)
			(thermal_bridge_width 0.5)
			(island_removal_mode 0)
		)
		(polygon
			(pts
				(arc
					(start 45.500036 -476.000064)
					(mid 49.500028 -480.000056)
					(end 45.500036 -484.000048)
				)
				(arc
					(start 45.500036 -484.000048)
					(mid 41.500044 -480.000056)
					(end 45.500036 -476.000064)
				)
			)
		)
	)
	(zone
		(net "P12V_SENSE_TRACE")
		(layer "F.Cu")
		(hatch none 0.5)
		(connect_pads
			(clearance 0.5)
		)
		(min_thickness 0.25)
		(fill yes
			(thermal_gap 0.5)
			(thermal_bridge_width 0.5)
			(island_removal_mode 0)
		)
		(polygon
			(pts
				(xy 46.0756 -401.2946) (xy 14.8844 -401.2946) (xy 12.7 -401.2946) (xy 12.4206 -401.574) (xy 12.4206 -408.9146)
				(xy 13.97 -410.464) (xy 45.593 -410.464) (xy 46.101 -410.464) (xy 46.863 -410.464) (xy 47.625 -409.702)
				(xy 47.625 -402.209) (xy 46.736 -401.32) (xy 46.7106 -401.2946) (xy 46.3296 -401.2946)
			)
		)
	)
	(zone
		(net "P12V_FAN4")
		(layer "F.Cu")
		(hatch none 0.5)
		(connect_pads
			(clearance 0.5)
		)
		(min_thickness 0.25)
		(fill yes
			(thermal_gap 0.5)
			(thermal_bridge_width 0.5)
			(island_removal_mode 0)
		)
		(polygon
			(pts
				(xy 20.574 -189.23) (xy 17.653 -189.23) (xy 17.018 -189.865) (xy 17.018 -193.04) (xy 16.002 -194.056)
				(xy 3.429 -194.056) (xy 2.54 -194.945) (xy 2.54 -196.723) (xy 3.175 -197.358) (xy 15.24 -197.358)
				(xy 17.78 -199.898) (xy 20.574 -199.898) (xy 21.336 -199.136) (xy 21.336 -195.4276) (xy 21.1582 -195.2498)
				(xy 21.1582 -189.8142)
			)
		)
	)
	(zone
		(layer "F.Cu")
		(hatch none 0.5)
		(connect_pads
			(clearance 0)
		)
		(min_thickness 0.25)
		(keepout
			(tracks allowed)
			(vias allowed)
			(pads allowed)
			(copperpour allowed)
			(footprints not_allowed)
		)
		(placement
			(enabled no)
			(sheetname "")
		)
		(fill
			(thermal_gap 0.5)
			(thermal_bridge_width 0.5)
			(island_removal_mode 0)
		)
		(polygon
			(pts
				(arc
					(start 13.5001 -465.70011)
					(mid 15.267774 -466.432304)
					(end 15.999968 -468.199978)
				)
				(arc
					(start 15.999968 -497.19992)
					(mid 15.267789 -498.967683)
					(end 13.5001 -499.700042)
				)
				(arc
					(start 0.28575 -499.700042)
					(mid 0.074121 -499.378086)
					(end 0 -499.000018)
				)
				(xy 0 -465.70011)
			)
		)
	)
	(zone
		(net "P3V3")
		(layer "F.Cu")
		(hatch none 0.5)
		(connect_pads
			(clearance 0.5)
		)
		(min_thickness 0.25)
		(fill yes
			(thermal_gap 0.5)
			(thermal_bridge_width 0.5)
			(island_removal_mode 0)
		)
		(polygon
			(pts
				(xy 26.67 -358.4194) (xy 26.3906 -358.4194) (xy 26.2382 -358.5718) (xy 26.2382 -360.934) (xy 26.416 -361.1118)
				(xy 26.924 -361.1118) (xy 27.1018 -360.934) (xy 27.1018 -359.6894) (xy 27.3304 -359.4608) (xy 28.575 -359.4608)
				(xy 29.6164 -360.5022) (xy 29.6164 -361.0864) (xy 29.718 -361.188) (xy 30.353 -361.188) (xy 30.48 -361.061)
				(xy 30.48 -359.791) (xy 29.1084 -358.4194) (xy 28.829 -358.14) (xy 28.829 -357.378) (xy 28.702 -357.251)
				(xy 27.051 -357.251) (xy 26.924 -357.378) (xy 26.924 -358.1654)
			)
		)
	)
	(zone
		(layer "F.Cu")
		(hatch none 0.5)
		(connect_pads
			(clearance 0)
		)
		(min_thickness 0.25)
		(keepout
			(tracks allowed)
			(vias allowed)
			(pads allowed)
			(copperpour allowed)
			(footprints not_allowed)
		)
		(placement
			(enabled no)
			(sheetname "")
		)
		(fill
			(thermal_gap 0.5)
			(thermal_bridge_width 0.5)
			(island_removal_mode 0)
		)
		(polygon
			(pts
				(arc
					(start 6.999986 -35.999928)
					(mid 10.999978 -39.99992)
					(end 6.999986 -43.999912)
				)
				(arc
					(start 6.999986 -43.999912)
					(mid 2.999994 -39.99992)
					(end 6.999986 -35.999928)
				)
			)
		)
	)
	(zone
		(layer "F.Cu")
		(hatch none 0.5)
		(connect_pads
			(clearance 0)
		)
		(min_thickness 0.25)
		(keepout
			(tracks allowed)
			(vias allowed)
			(pads allowed)
			(copperpour allowed)
			(footprints allowed)
		)
		(placement
			(enabled no)
			(sheetname "")
		)
		(fill
			(thermal_gap 0.5)
			(thermal_bridge_width 0.5)
			(island_removal_mode 0)
		)
		(polygon
			(pts
				(xy 25.1968 -370.1288) (xy 25.1968 -368.7572) (xy 27.686 -368.7572) (xy 27.686 -370.1288)
			)
		)
	)
	(zone
		(layer "F.Cu")
		(hatch none 0.5)
		(connect_pads
			(clearance 0)
		)
		(min_thickness 0.25)
		(keepout
			(tracks allowed)
			(vias allowed)
			(pads allowed)
			(copperpour allowed)
			(footprints not_allowed)
		)
		(placement
			(enabled no)
			(sheetname "")
		)
		(fill
			(thermal_gap 0.5)
			(thermal_bridge_width 0.5)
			(island_removal_mode 0)
		)
		(polygon
			(pts
				(arc
					(start 6.999986 -456.000104)
					(mid 10.999978 -460.000096)
					(end 6.999986 -464.000088)
				)
				(arc
					(start 6.999986 -464.000088)
					(mid 2.999994 -460.000096)
					(end 6.999986 -456.000104)
				)
			)
		)
	)
	(zone
		(layer "F.Cu")
		(hatch none 0.5)
		(connect_pads
			(clearance 0)
		)
		(min_thickness 0.25)
		(keepout
			(tracks allowed)
			(vias allowed)
			(pads allowed)
			(copperpour allowed)
			(footprints not_allowed)
		)
		(placement
			(enabled no)
			(sheetname "")
		)
		(fill
			(thermal_gap 0.5)
			(thermal_bridge_width 0.5)
			(island_removal_mode 0)
		)
		(polygon
			(pts
				(xy 8.999982 -351.199958) (xy 38.699948 -351.199958) (xy 38.699948 -345.849956)
				(arc
					(start 44.04995 -345.849956)
					(mid 49.954289 -343.404299)
					(end 52.399946 -337.49996)
				)
				(arc
					(start 52.399946 -337.49996)
					(mid 49.954289 -331.595621)
					(end 44.04995 -329.149964)
				)
				(xy 38.699948 -329.149964) (xy 38.699948 -323.799962) (xy 8.999982 -323.799962)
			)
		)
	)
	(zone
		(layer "F.Cu")
		(hatch none 0.5)
		(connect_pads
			(clearance 0)
		)
		(min_thickness 0.25)
		(keepout
			(tracks allowed)
			(vias allowed)
			(pads allowed)
			(copperpour allowed)
			(footprints not_allowed)
		)
		(placement
			(enabled no)
			(sheetname "")
		)
		(fill
			(thermal_gap 0.5)
			(thermal_bridge_width 0.5)
			(island_removal_mode 0)
		)
		(polygon
			(pts
				(xy 17.649952 -471.65006) (xy 31.34995 -471.65006) (xy 31.34995 -453.520048)
				(arc
					(start 30.249876 -453.520048)
					(mid 28.549854 -451.820026)
					(end 30.249876 -450.120004)
				)
				(xy 31.34995 -450.120004) (xy 31.34995 -429.250094) (xy 17.649952 -429.250094)
			)
		)
	)
	(zone
		(net "P12V_FAN2")
		(layer "F.Cu")
		(hatch none 0.5)
		(connect_pads
			(clearance 0.5)
		)
		(min_thickness 0.25)
		(fill yes
			(thermal_gap 0.5)
			(thermal_bridge_width 0.5)
			(island_removal_mode 0)
		)
		(polygon
			(pts
				(xy 32.9946 -289.7378) (xy 25.4 -289.7378) (xy 24.7396 -290.3982) (xy 24.7396 -292.2524) (xy 24.384 -292.608)
				(xy 24.384 -295.8592) (xy 15.5448 -304.6984) (xy 15.5448 -338.963) (xy 2.667 -351.8408) (xy 2.667 -364.7948)
				(xy 4.699 -366.8268) (xy 4.699 -373.507) (xy 4.191 -374.015) (xy 2.667 -374.015) (xy 2.159 -374.523)
				(xy 2.159 -376.047) (xy 2.54 -376.428) (xy 6.35 -376.428) (xy 7.747 -375.031) (xy 7.747 -364.744)
				(xy 5.588 -362.585) (xy 5.588 -353.822) (xy 18.6182 -340.7918) (xy 18.6182 -306.07) (xy 29.4386 -295.2496)
				(xy 32.6644 -295.2496) (xy 33.655 -294.259) (xy 33.655 -290.3982)
			)
		)
	)
	(zone
		(layer "F.Cu")
		(hatch none 0.5)
		(connect_pads
			(clearance 0)
		)
		(min_thickness 0.25)
		(keepout
			(tracks allowed)
			(vias allowed)
			(pads allowed)
			(copperpour allowed)
			(footprints allowed)
		)
		(placement
			(enabled no)
			(sheetname "")
		)
		(fill
			(thermal_gap 0.5)
			(thermal_bridge_width 0.5)
			(island_removal_mode 0)
		)
		(polygon
			(pts
				(xy 34.544 -162.814) (xy 34.544 -161.29) (xy 36.83 -161.29) (xy 36.83 -162.814)
			)
		)
	)
	(zone
		(net "GND")
		(layer "F.Cu")
		(hatch none 0.5)
		(connect_pads
			(clearance 0.5)
		)
		(min_thickness 0.25)
		(fill yes
			(thermal_gap 0.5)
			(thermal_bridge_width 0.5)
			(island_removal_mode 0)
		)
		(polygon
			(pts
				(xy 20.828 -150.114) (xy 20.828 -151.13) (xy 21.59 -151.892) (xy 22.86 -151.892) (xy 23.114 -151.638)
				(xy 23.114 -148.844) (xy 24.1935 -147.7645) (xy 24.1935 -147.1295) (xy 23.368 -146.304) (xy 23.114 -146.304)
				(xy 21.971 -146.304) (xy 21.209 -145.542) (xy 18.542 -145.542) (xy 18.161 -145.161) (xy 17.399 -145.161)
				(xy 17.272 -145.288) (xy 17.272 -146.685) (xy 18.034 -147.447) (xy 18.669 -147.447) (xy 19.177 -147.955)
				(xy 19.177 -149.225) (xy 19.431 -149.479) (xy 20.193 -149.479)
			)
		)
	)
	(zone
		(net "P12V_FAN6")
		(layer "F.Cu")
		(hatch none 0.5)
		(connect_pads
			(clearance 0.5)
		)
		(min_thickness 0.25)
		(fill yes
			(thermal_gap 0.5)
			(thermal_bridge_width 0.5)
			(island_removal_mode 0)
		)
		(polygon
			(pts
				(xy 8.5852 -18.669) (xy 2.667 -18.669) (xy 2.286 -19.05) (xy 2.286 -20.701) (xy 2.794 -21.209) (xy 3.302 -21.209)
				(xy 3.429 -21.082) (xy 7.112 -21.082) (xy 8.1915 -22.1615) (xy 13.2207 -27.1907) (xy 13.2334 -27.1907)
				(xy 15.4305 -29.3878) (xy 18.4658 -29.3878) (xy 20.0279 -27.8257) (xy 20.7137 -27.8257) (xy 20.8788 -27.6606)
				(xy 20.8788 -20.6248) (xy 20.0406 -19.7866) (xy 19.5961 -19.3421) (xy 19.304 -19.05) (xy 17.3101 -19.05)
				(xy 16.129 -20.2311) (xy 15.4813 -20.2311) (xy 10.1473 -20.2311) (xy 9.7536 -19.8374)
			)
		)
	)
	(zone
		(layer "F.Cu")
		(hatch none 0.5)
		(connect_pads
			(clearance 0)
		)
		(min_thickness 0.25)
		(keepout
			(tracks allowed)
			(vias allowed)
			(pads allowed)
			(copperpour allowed)
			(footprints not_allowed)
		)
		(placement
			(enabled no)
			(sheetname "")
		)
		(fill
			(thermal_gap 0.5)
			(thermal_bridge_width 0.5)
			(island_removal_mode 0)
		)
		(polygon
			(pts
				(arc
					(start 16.500094 0)
					(mid 17.207199 -0.292893)
					(end 17.500092 -0.999998)
				)
				(arc
					(start 17.500092 -8.999982)
					(mid 17.792985 -9.707087)
					(end 18.50009 -9.99998)
				)
				(arc
					(start 51.500024 -9.99998)
					(mid 52.207129 -10.292873)
					(end 52.500022 -10.999978)
				)
				(arc
					(start 52.500022 -489.000038)
					(mid 52.207129 -489.707143)
					(end 51.500024 -490.000036)
				)
				(arc
					(start 18.50009 -490.000036)
					(mid 17.792985 -490.292929)
					(end 17.500092 -491.000034)
				)
				(arc
					(start 17.500092 -499.000018)
					(mid 17.207199 -499.707123)
					(end 16.500094 -500.000016)
				)
				(arc
					(start 0.999998 -500.000016)
					(mid 0.612674 -499.92196)
					(end 0.28575 -499.700042)
				)
				(arc
					(start 13.5001 -499.700042)
					(mid 15.267789 -498.967683)
					(end 15.999968 -497.19992)
				)
				(arc
					(start 15.999968 -468.199978)
					(mid 15.267774 -466.432304)
					(end 13.5001 -465.70011)
				)
				(xy 0 -465.70011) (xy 0 -389.659876)
				(arc
					(start 13.5001 -389.659876)
					(mid 15.267774 -388.927682)
					(end 15.999968 -387.160008)
				)
				(arc
					(start 15.999968 -358.160066)
					(mid 15.267789 -356.392303)
					(end 13.5001 -355.659944)
				)
				(xy 0 -355.659944) (xy 0 -323.660008)
				(arc
					(start 13.5001 -323.660008)
					(mid 15.267863 -322.927724)
					(end 15.999968 -321.159886)
				)
				(arc
					(start 15.999968 -292.159944)
					(mid 15.267774 -290.39227)
					(end 13.5001 -289.660076)
				)
				(xy 0 -289.660076) (xy 0 -210.33994)
				(arc
					(start 13.5001 -210.33994)
					(mid 15.267774 -209.607746)
					(end 15.999968 -207.840072)
				)
				(arc
					(start 15.999968 -178.839876)
					(mid 15.267774 -177.072202)
					(end 13.5001 -176.340008)
				)
				(xy 0 -176.340008) (xy 0 -144.340072)
				(arc
					(start 13.5001 -144.340072)
					(mid 15.267789 -143.607713)
					(end 15.999968 -141.83995)
				)
				(arc
					(start 15.999968 -112.840008)
					(mid 15.267789 -111.072245)
					(end 13.5001 -110.339886)
				)
				(xy 0 -110.339886) (xy 0 -34.299906)
				(arc
					(start 13.5001 -34.299906)
					(mid 15.267774 -33.567712)
					(end 15.999968 -31.800038)
				)
				(arc
					(start 15.999968 -2.800096)
					(mid 15.267789 -1.032333)
					(end 13.5001 -0.299974)
				)
				(arc
					(start 0.28575 -0.299974)
					(mid 0.612638 -0.07797)
					(end 0.999998 0)
				)
			)
		)
	)
	(zone
		(layer "F.Cu")
		(hatch none 0.5)
		(connect_pads
			(clearance 0)
		)
		(min_thickness 0.25)
		(keepout
			(tracks allowed)
			(vias allowed)
			(pads allowed)
			(copperpour allowed)
			(footprints not_allowed)
		)
		(placement
			(enabled no)
			(sheetname "")
		)
		(fill
			(thermal_gap 0.5)
			(thermal_bridge_width 0.5)
			(island_removal_mode 0)
		)
		(polygon
			(pts
				(arc
					(start 45.500036 -23.999952)
					(mid 41.500044 -19.99996)
					(end 45.500036 -15.999968)
				)
				(arc
					(start 45.500036 -15.999968)
					(mid 49.500028 -19.99996)
					(end 45.500036 -23.999952)
				)
			)
		)
	)
	(zone
		(layer "F.Cu")
		(hatch none 0.5)
		(connect_pads
			(clearance 0)
		)
		(min_thickness 0.25)
		(keepout
			(tracks allowed)
			(vias allowed)
			(pads allowed)
			(copperpour allowed)
			(footprints allowed)
		)
		(placement
			(enabled no)
			(sheetname "")
		)
		(fill
			(thermal_gap 0.5)
			(thermal_bridge_width 0.5)
			(island_removal_mode 0)
		)
		(polygon
			(pts
				(xy 40.2082 -144.0942) (xy 35.8902 -144.0942) (xy 35.8902 -136.7536) (xy 40.2082 -136.7536)
			)
		)
	)
	(zone
		(net "P12VL")
		(layer "F.Cu")
		(hatch none 0.5)
		(connect_pads
			(clearance 0.5)
		)
		(min_thickness 0.25)
		(fill yes
			(thermal_gap 0.5)
			(thermal_bridge_width 0.5)
			(island_removal_mode 0)
		)
		(polygon
			(pts
				(xy 28.956 -98.298) (xy 28.956 -108.7882) (xy 32.639 -112.4712) (xy 44.7294 -112.4712) (xy 44.831 -112.4712)
				(xy 44.831 -112.395) (xy 45.593 -112.395) (xy 45.72 -112.268) (xy 45.72 -109.601) (xy 45.085 -108.966)
				(xy 45.085 -81.661) (xy 45.0342 -81.6102) (xy 47.5107 -79.1337) (xy 47.498 -79.121) (xy 47.498 -64.135)
				(xy 47.117 -63.754) (xy 36.957 -63.754) (xy 35.687 -65.024) (xy 35.687 -65.151) (xy 35.687 -72.517)
				(xy 35.306 -72.898) (xy 27.813 -80.391) (xy 27.813 -87.757) (xy 27.813 -88.646) (xy 28.194 -89.027)
				(xy 29.083 -89.027) (xy 29.8196 -89.7636) (xy 29.8196 -94.8182) (xy 28.956 -95.6818)
			)
		)
	)
	(zone
		(net "P12V")
		(layer "F.Cu")
		(hatch none 0.5)
		(connect_pads
			(clearance 0.5)
		)
		(min_thickness 0.25)
		(fill yes
			(thermal_gap 0.5)
			(thermal_bridge_width 0.5)
			(island_removal_mode 0)
		)
		(polygon
			(pts
				(xy 12.5984 -158.115) (xy 11.9888 -158.7246) (xy 11.9888 -161.29) (xy 9.271 -164.0078) (xy 9.271 -171.323)
				(xy 10.287 -172.339) (xy 14.224 -172.339) (xy 15.367 -171.196) (xy 15.367 -166.497) (xy 17.526 -164.338)
				(xy 19.6088 -164.338) (xy 21.5519 -162.3949) (xy 21.5519 -159.0929) (xy 20.574 -158.115)
			)
		)
	)
	(zone
		(layer "F.Cu")
		(hatch none 0.5)
		(connect_pads
			(clearance 0)
		)
		(min_thickness 0.25)
		(keepout
			(tracks allowed)
			(vias allowed)
			(pads allowed)
			(copperpour allowed)
			(footprints not_allowed)
		)
		(placement
			(enabled no)
			(sheetname "")
		)
		(fill
			(thermal_gap 0.5)
			(thermal_bridge_width 0.5)
			(island_removal_mode 0)
		)
		(polygon
			(pts
				(arc
					(start 45.500036 -140.999972)
					(mid 49.500028 -144.999964)
					(end 45.500036 -148.999956)
				)
				(arc
					(start 45.500036 -148.999956)
					(mid 41.500044 -144.999964)
					(end 45.500036 -140.999972)
				)
			)
		)
	)
	(zone
		(net "P12V_FAN3")
		(layer "F.Cu")
		(hatch none 0.5)
		(connect_pads
			(clearance 0.5)
		)
		(min_thickness 0.25)
		(fill yes
			(thermal_gap 0.5)
			(thermal_bridge_width 0.5)
			(island_removal_mode 0)
		)
		(polygon
			(pts
				(xy 18.034 -263.652) (xy 15.24 -263.652) (xy 14.097 -263.652) (xy 13.081 -263.652) (xy 12.573 -264.16)
				(xy 12.573 -265.176) (xy 12.573 -266.319) (xy 12.573 -297.434) (xy 7.493 -302.514) (xy 7.493 -305.943)
				(xy 5.461 -307.975) (xy 2.667 -307.975) (xy 2.032 -308.61) (xy 2.032 -310.134) (xy 2.54 -310.642)
				(xy 5.842 -310.642) (xy 9.398 -307.086) (xy 9.398 -303.53) (xy 14.732 -298.196) (xy 14.732 -275.30425)
				(xy 15.875 -274.16125) (xy 17.93875 -274.16125) (xy 18.161 -273.939) (xy 18.161 -263.779)
			)
		)
	)
	(zone
		(layer "F.Cu")
		(hatch none 0.5)
		(connect_pads
			(clearance 0)
		)
		(min_thickness 0.25)
		(keepout
			(tracks allowed)
			(vias allowed)
			(pads allowed)
			(copperpour allowed)
			(footprints not_allowed)
		)
		(placement
			(enabled no)
			(sheetname "")
		)
		(fill
			(thermal_gap 0.5)
			(thermal_bridge_width 0.5)
			(island_removal_mode 0)
		)
		(polygon
			(pts
				(arc
					(start 13.5001 -289.660076)
					(mid 15.267774 -290.39227)
					(end 15.999968 -292.159944)
				)
				(arc
					(start 15.999968 -321.159886)
					(mid 15.267863 -322.927724)
					(end 13.5001 -323.660008)
				)
				(xy 0 -323.660008) (xy 0 -289.660076)
			)
		)
	)
	(zone
		(layer "F.Cu")
		(hatch none 0.5)
		(connect_pads
			(clearance 0)
		)
		(min_thickness 0.25)
		(keepout
			(tracks allowed)
			(vias allowed)
			(pads allowed)
			(copperpour allowed)
			(footprints not_allowed)
		)
		(placement
			(enabled no)
			(sheetname "")
		)
		(fill
			(thermal_gap 0.5)
			(thermal_bridge_width 0.5)
			(island_removal_mode 0)
		)
		(polygon
			(pts
				(xy 34.150046 -471.65006) (xy 47.850044 -471.65006) (xy 47.850044 -429.250094) (xy 34.150046 -429.250094)
				(xy 34.150046 -450.120004)
				(arc
					(start 35.25012 -450.120004)
					(mid 36.950142 -451.820026)
					(end 35.25012 -453.520048)
				)
				(xy 34.150046 -453.520048)
			)
		)
	)
	(zone
		(net "GND")
		(layer "F.Cu")
		(hatch none 0.5)
		(connect_pads
			(clearance 0.5)
		)
		(min_thickness 0.25)
		(fill yes
			(thermal_gap 0.5)
			(thermal_bridge_width 0.5)
			(island_removal_mode 0)
		)
		(polygon
			(pts
				(xy 17.272 -480.822) (xy 17.272 -477.139) (xy 16.129 -475.996) (xy 13.335 -475.996) (xy 8.636 -480.695)
				(xy 8.001 -481.33) (xy 6.604 -481.33) (xy 6.35 -481.584) (xy 6.35 -482.473) (xy 6.858 -482.981)
				(xy 7.493 -482.981) (xy 8.255 -483.743) (xy 9.525 -483.743) (xy 14.351 -483.743)
			)
		)
	)
	(zone
		(layers "F.Cu" "B.Cu" "In1.Cu" "In2.Cu")
		(name "Package Keepin")
		(hatch none 0.5)
		(connect_pads
			(clearance 0)
		)
		(min_thickness 0.25)
		(keepout
			(tracks allowed)
			(vias allowed)
			(pads allowed)
			(copperpour allowed)
			(footprints allowed)
		)
		(placement
			(enabled no)
			(sheetname "")
		)
		(fill
			(thermal_gap 0.5)
			(thermal_bridge_width 0.5)
			(island_removal_mode 0)
		)
		(polygon
			(pts
				(xy 13.436092 -4.064) (xy 4.064 -4.064) (xy 4.064 -495.936016) (xy 13.436092 -495.936016)
				(arc
					(start 13.436092 -491.000034)
					(mid 14.919303 -487.419247)
					(end 18.50009 -485.936036)
				)
				(xy 48.436022 -485.936036) (xy 48.436022 -14.06398)
				(arc
					(start 18.50009 -14.06398)
					(mid 14.919303 -12.580769)
					(end 13.436092 -8.999982)
				)
			)
		)
	)
	(zone
		(layers "F.Cu" "B.Cu" "In1.Cu" "In2.Cu")
		(name "Route Keepin")
		(hatch none 0.5)
		(connect_pads
			(clearance 0)
		)
		(min_thickness 0.25)
		(keepout
			(tracks allowed)
			(vias allowed)
			(pads allowed)
			(copperpour allowed)
			(footprints allowed)
		)
		(placement
			(enabled no)
			(sheetname "")
		)
		(fill
			(thermal_gap 0.5)
			(thermal_bridge_width 0.5)
			(island_removal_mode 0)
		)
		(polygon
			(pts
				(arc
					(start 0.999998 -0.762)
					(mid 0.831708 -0.831708)
					(end 0.762 -0.999998)
				)
				(arc
					(start 0.762 -499.000018)
					(mid 0.831708 -499.168308)
					(end 0.999998 -499.238016)
				)
				(arc
					(start 16.500094 -499.238016)
					(mid 16.668384 -499.168308)
					(end 16.738092 -499.000018)
				)
				(arc
					(start 16.738092 -491.000034)
					(mid 17.254169 -489.754113)
					(end 18.50009 -489.238036)
				)
				(arc
					(start 51.500024 -489.238036)
					(mid 51.668314 -489.168328)
					(end 51.738022 -489.000038)
				)
				(arc
					(start 51.738022 -10.999978)
					(mid 51.668314 -10.831688)
					(end 51.500024 -10.76198)
				)
				(arc
					(start 18.50009 -10.76198)
					(mid 17.254169 -10.245903)
					(end 16.738092 -8.999982)
				)
				(arc
					(start 16.738092 -0.999998)
					(mid 16.668384 -0.831708)
					(end 16.500094 -0.762)
				)
			)
		)
	)
	(zone
		(layer "B.Cu")
		(hatch none 0.5)
		(connect_pads
			(clearance 0)
		)
		(min_thickness 0.25)
		(keepout
			(tracks allowed)
			(vias allowed)
			(pads allowed)
			(copperpour allowed)
			(footprints not_allowed)
		)
		(placement
			(enabled no)
			(sheetname "")
		)
		(fill
			(thermal_gap 0.5)
			(thermal_bridge_width 0.5)
			(island_removal_mode 0)
		)
		(polygon
			(pts
				(arc
					(start 7.599934 -291.660072)
					(mid 3.599942 -295.660064)
					(end 7.599934 -299.660056)
				)
				(arc
					(start 7.599934 -299.660056)
					(mid 11.599926 -295.660064)
					(end 7.599934 -291.660072)
				)
			)
		)
	)
	(zone
		(layer "B.Cu")
		(hatch none 0.5)
		(connect_pads
			(clearance 0)
		)
		(min_thickness 0.25)
		(keepout
			(tracks allowed)
			(vias allowed)
			(pads allowed)
			(copperpour allowed)
			(footprints not_allowed)
		)
		(placement
			(enabled no)
			(sheetname "")
		)
		(fill
			(thermal_gap 0.5)
			(thermal_bridge_width 0.5)
			(island_removal_mode 0)
		)
		(polygon
			(pts
				(arc
					(start 6.999986 -35.999928)
					(mid 2.999994 -39.99992)
					(end 6.999986 -43.999912)
				)
				(arc
					(start 6.999986 -43.999912)
					(mid 10.999978 -39.99992)
					(end 6.999986 -35.999928)
				)
			)
		)
	)
	(zone
		(net "P12V_AUX")
		(layer "B.Cu")
		(hatch none 0.5)
		(connect_pads
			(clearance 0.5)
		)
		(min_thickness 0.25)
		(fill yes
			(thermal_gap 0.5)
			(thermal_bridge_width 0.5)
			(island_removal_mode 0)
		)
		(polygon
			(pts
				(xy 46.609 -422.275) (xy 46.609 -419.608) (xy 46.609 -415.036) (xy 45.593 -414.02) (xy 14.097 -414.02)
				(xy 13.208 -414.909) (xy 13.208 -416.56) (xy 13.208 -469.011) (xy 13.208 -472.313) (xy 16.002 -475.107)
				(xy 16.256 -475.361) (xy 30.353 -475.361) (xy 32.131 -473.583) (xy 32.512 -473.202) (xy 32.512 -425.831)
				(xy 32.639 -425.704) (xy 34.798 -423.545) (xy 35.941 -423.545) (xy 46.101 -423.545) (xy 46.609 -423.037)
			)
		)
	)
	(zone
		(layer "B.Cu")
		(hatch none 0.5)
		(connect_pads
			(clearance 0)
		)
		(min_thickness 0.25)
		(keepout
			(tracks allowed)
			(vias allowed)
			(pads allowed)
			(copperpour allowed)
			(footprints not_allowed)
		)
		(placement
			(enabled no)
			(sheetname "")
		)
		(fill
			(thermal_gap 0.5)
			(thermal_bridge_width 0.5)
			(island_removal_mode 0)
		)
		(polygon
			(pts
				(arc
					(start 7.599934 -200.33996)
					(mid 3.599942 -204.339952)
					(end 7.599934 -208.339944)
				)
				(arc
					(start 7.599934 -208.339944)
					(mid 11.599926 -204.339952)
					(end 7.599934 -200.33996)
				)
			)
		)
	)
	(zone
		(layer "B.Cu")
		(hatch none 0.5)
		(connect_pads
			(clearance 0)
		)
		(min_thickness 0.25)
		(keepout
			(tracks allowed)
			(vias allowed)
			(pads allowed)
			(copperpour allowed)
			(footprints not_allowed)
		)
		(placement
			(enabled no)
			(sheetname "")
		)
		(fill
			(thermal_gap 0.5)
			(thermal_bridge_width 0.5)
			(island_removal_mode 0)
		)
		(polygon
			(pts
				(arc
					(start 7.599934 -142.340076)
					(mid 11.599926 -138.340084)
					(end 7.599934 -134.340092)
				)
				(arc
					(start 7.599934 -134.340092)
					(mid 3.599942 -138.340084)
					(end 7.599934 -142.340076)
				)
			)
		)
	)
	(zone
		(layer "B.Cu")
		(hatch none 0.5)
		(connect_pads
			(clearance 0)
		)
		(min_thickness 0.25)
		(keepout
			(tracks allowed)
			(vias allowed)
			(pads allowed)
			(copperpour allowed)
			(footprints not_allowed)
		)
		(placement
			(enabled no)
			(sheetname "")
		)
		(fill
			(thermal_gap 0.5)
			(thermal_bridge_width 0.5)
			(island_removal_mode 0)
		)
		(polygon
			(pts
				(arc
					(start 45.500036 -298.99991)
					(mid 49.500028 -294.999918)
					(end 45.500036 -290.999926)
				)
				(arc
					(start 45.500036 -290.999926)
					(mid 41.500044 -294.999918)
					(end 45.500036 -298.99991)
				)
			)
		)
	)
	(zone
		(layer "B.Cu")
		(hatch none 0.5)
		(connect_pads
			(clearance 0)
		)
		(min_thickness 0.25)
		(keepout
			(tracks allowed)
			(vias allowed)
			(pads allowed)
			(copperpour allowed)
			(footprints not_allowed)
		)
		(placement
			(enabled no)
			(sheetname "")
		)
		(fill
			(thermal_gap 0.5)
			(thermal_bridge_width 0.5)
			(island_removal_mode 0)
		)
		(polygon
			(pts
				(arc
					(start 45.500036 -15.999968)
					(mid 41.500044 -19.99996)
					(end 45.500036 -23.999952)
				)
				(arc
					(start 45.500036 -23.999952)
					(mid 49.500028 -19.99996)
					(end 45.500036 -15.999968)
				)
			)
		)
	)
	(zone
		(layer "B.Cu")
		(hatch none 0.5)
		(connect_pads
			(clearance 0)
		)
		(min_thickness 0.25)
		(keepout
			(tracks allowed)
			(vias allowed)
			(pads allowed)
			(copperpour allowed)
			(footprints not_allowed)
		)
		(placement
			(enabled no)
			(sheetname "")
		)
		(fill
			(thermal_gap 0.5)
			(thermal_bridge_width 0.5)
			(island_removal_mode 0)
		)
		(polygon
			(pts
				(arc
					(start 7.599934 -112.339882)
					(mid 3.599688 -116.340128)
					(end 7.599934 -120.34012)
				)
				(arc
					(start 7.599934 -120.34012)
					(mid 11.599926 -116.340128)
					(end 7.599934 -112.339882)
				)
			)
		)
	)
	(zone
		(layer "B.Cu")
		(hatch none 0.5)
		(connect_pads
			(clearance 0)
		)
		(min_thickness 0.25)
		(keepout
			(tracks allowed)
			(vias allowed)
			(pads allowed)
			(copperpour allowed)
			(footprints not_allowed)
		)
		(placement
			(enabled no)
			(sheetname "")
		)
		(fill
			(thermal_gap 0.5)
			(thermal_bridge_width 0.5)
			(island_removal_mode 0)
		)
		(polygon
			(pts
				(arc
					(start 7.599934 -299.660056)
					(mid 11.599926 -295.660064)
					(end 7.599934 -291.660072)
				)
				(arc
					(start 7.599934 -291.660072)
					(mid 3.599942 -295.660064)
					(end 7.599934 -299.660056)
				)
			)
		)
	)
	(zone
		(layer "B.Cu")
		(hatch none 0.5)
		(connect_pads
			(clearance 0)
		)
		(min_thickness 0.25)
		(keepout
			(tracks allowed)
			(vias allowed)
			(pads allowed)
			(copperpour allowed)
			(footprints not_allowed)
		)
		(placement
			(enabled no)
			(sheetname "")
		)
		(fill
			(thermal_gap 0.5)
			(thermal_bridge_width 0.5)
			(island_removal_mode 0)
		)
		(polygon
			(pts
				(arc
					(start 4.500118 -336.00009)
					(mid 0.500126 -340.000082)
					(end 4.500118 -344.000074)
				)
				(arc
					(start 4.500118 -344.000074)
					(mid 8.50011 -340.000082)
					(end 4.500118 -336.00009)
				)
			)
		)
	)
	(zone
		(layer "B.Cu")
		(hatch none 0.5)
		(connect_pads
			(clearance 0)
		)
		(min_thickness 0.25)
		(keepout
			(tracks allowed)
			(vias allowed)
			(pads allowed)
			(copperpour allowed)
			(footprints not_allowed)
		)
		(placement
			(enabled no)
			(sheetname "")
		)
		(fill
			(thermal_gap 0.5)
			(thermal_bridge_width 0.5)
			(island_removal_mode 0)
		)
		(polygon
			(pts
				(arc
					(start 6.999986 -456.000104)
					(mid 2.999994 -460.000096)
					(end 6.999986 -464.000088)
				)
				(arc
					(start 6.999986 -464.000088)
					(mid 10.999978 -460.000096)
					(end 6.999986 -456.000104)
				)
			)
		)
	)
	(zone
		(layer "B.Cu")
		(hatch none 0.5)
		(connect_pads
			(clearance 0)
		)
		(min_thickness 0.25)
		(keepout
			(tracks allowed)
			(vias allowed)
			(pads allowed)
			(copperpour allowed)
			(footprints not_allowed)
		)
		(placement
			(enabled no)
			(sheetname "")
		)
		(fill
			(thermal_gap 0.5)
			(thermal_bridge_width 0.5)
			(island_removal_mode 0)
		)
		(polygon
			(pts
				(arc
					(start 40.999918 -448.69989)
					(mid 45.749718 -443.95009)
					(end 40.999918 -439.200036)
				)
				(arc
					(start 40.999918 -439.200036)
					(mid 36.249864 -443.95009)
					(end 40.999918 -448.69989)
				)
			)
		)
	)
	(zone
		(layer "B.Cu")
		(hatch none 0.5)
		(connect_pads
			(clearance 0)
		)
		(min_thickness 0.25)
		(keepout
			(tracks allowed)
			(vias allowed)
			(pads allowed)
			(copperpour allowed)
			(footprints not_allowed)
		)
		(placement
			(enabled no)
			(sheetname "")
		)
		(fill
			(thermal_gap 0.5)
			(thermal_bridge_width 0.5)
			(island_removal_mode 0)
		)
		(polygon
			(pts
				(arc
					(start 7.599934 -489.700062)
					(mid 3.599942 -493.700054)
					(end 7.599934 -497.700046)
				)
				(arc
					(start 7.599934 -497.700046)
					(mid 11.599926 -493.700054)
					(end 7.599934 -489.700062)
				)
			)
		)
	)
	(zone
		(layer "B.Cu")
		(hatch none 0.5)
		(connect_pads
			(clearance 0)
		)
		(min_thickness 0.25)
		(keepout
			(tracks allowed)
			(vias allowed)
			(pads allowed)
			(copperpour allowed)
			(footprints not_allowed)
		)
		(placement
			(enabled no)
			(sheetname "")
		)
		(fill
			(thermal_gap 0.5)
			(thermal_bridge_width 0.5)
			(island_removal_mode 0)
		)
		(polygon
			(pts
				(arc
					(start 45.449998 -332.749906)
					(mid 40.699944 -337.49996)
					(end 45.449998 -342.250014)
				)
				(arc
					(start 45.449998 -342.250014)
					(mid 50.200052 -337.49996)
					(end 45.449998 -332.749906)
				)
			)
		)
	)
	(zone
		(layer "B.Cu")
		(hatch none 0.5)
		(connect_pads
			(clearance 0)
		)
		(min_thickness 0.25)
		(keepout
			(tracks allowed)
			(vias allowed)
			(pads allowed)
			(copperpour allowed)
			(footprints not_allowed)
		)
		(placement
			(enabled no)
			(sheetname "")
		)
		(fill
			(thermal_gap 0.5)
			(thermal_bridge_width 0.5)
			(island_removal_mode 0)
		)
		(polygon
			(pts
				(arc
					(start 24.500078 -458.300074)
					(mid 19.750024 -463.050128)
					(end 24.500078 -467.799928)
				)
				(arc
					(start 24.500078 -467.799928)
					(mid 29.249878 -463.050128)
					(end 24.500078 -458.300074)
				)
			)
		)
	)
	(zone
		(layer "B.Cu")
		(hatch none 0.5)
		(connect_pads
			(clearance 0)
		)
		(min_thickness 0.25)
		(keepout
			(tracks allowed)
			(vias allowed)
			(pads allowed)
			(copperpour allowed)
			(footprints not_allowed)
		)
		(placement
			(enabled no)
			(sheetname "")
		)
		(fill
			(thermal_gap 0.5)
			(thermal_bridge_width 0.5)
			(island_removal_mode 0)
		)
		(polygon
			(pts
				(arc
					(start 7.599934 -475.70009)
					(mid 11.599926 -471.700098)
					(end 7.599934 -467.700106)
				)
				(arc
					(start 7.599934 -467.700106)
					(mid 3.599942 -471.700098)
					(end 7.599934 -475.70009)
				)
			)
		)
	)
	(zone
		(layer "B.Cu")
		(hatch none 0.5)
		(connect_pads
			(clearance 0)
		)
		(min_thickness 0.25)
		(keepout
			(tracks allowed)
			(vias allowed)
			(pads allowed)
			(copperpour allowed)
			(footprints not_allowed)
		)
		(placement
			(enabled no)
			(sheetname "")
		)
		(fill
			(thermal_gap 0.5)
			(thermal_bridge_width 0.5)
			(island_removal_mode 0)
		)
		(polygon
			(pts
				(arc
					(start 7.599934 -387.65988)
					(mid 11.599926 -383.659888)
					(end 7.599934 -379.659896)
				)
				(arc
					(start 7.599934 -379.659896)
					(mid 3.599942 -383.659888)
					(end 7.599934 -387.65988)
				)
			)
		)
	)
	(zone
		(layer "B.Cu")
		(hatch none 0.5)
		(connect_pads
			(clearance 0)
		)
		(min_thickness 0.25)
		(keepout
			(tracks allowed)
			(vias allowed)
			(pads allowed)
			(copperpour allowed)
			(footprints not_allowed)
		)
		(placement
			(enabled no)
			(sheetname "")
		)
		(fill
			(thermal_gap 0.5)
			(thermal_bridge_width 0.5)
			(island_removal_mode 0)
		)
		(polygon
			(pts
				(arc
					(start 7.599934 -24.299926)
					(mid 3.599942 -28.299918)
					(end 7.599934 -32.29991)
				)
				(arc
					(start 7.599934 -32.29991)
					(mid 11.599926 -28.299918)
					(end 7.599934 -24.299926)
				)
			)
		)
	)
	(zone
		(layer "B.Cu")
		(hatch none 0.5)
		(connect_pads
			(clearance 0)
		)
		(min_thickness 0.25)
		(keepout
			(tracks allowed)
			(vias allowed)
			(pads allowed)
			(copperpour allowed)
			(footprints not_allowed)
		)
		(placement
			(enabled no)
			(sheetname "")
		)
		(fill
			(thermal_gap 0.5)
			(thermal_bridge_width 0.5)
			(island_removal_mode 0)
		)
		(polygon
			(pts
				(arc
					(start 45.500036 -140.999972)
					(mid 41.500044 -144.999964)
					(end 45.500036 -148.999956)
				)
				(arc
					(start 45.500036 -148.999956)
					(mid 49.500028 -144.999964)
					(end 45.500036 -140.999972)
				)
			)
		)
	)
	(zone
		(layer "B.Cu")
		(hatch none 0.5)
		(connect_pads
			(clearance 0)
		)
		(min_thickness 0.25)
		(keepout
			(tracks allowed)
			(vias allowed)
			(pads allowed)
			(copperpour allowed)
			(footprints not_allowed)
		)
		(placement
			(enabled no)
			(sheetname "")
		)
		(fill
			(thermal_gap 0.5)
			(thermal_bridge_width 0.5)
			(island_removal_mode 0)
		)
		(polygon
			(pts
				(arc
					(start 40.999918 -458.300074)
					(mid 36.249864 -463.050128)
					(end 40.999918 -467.799928)
				)
				(arc
					(start 40.999918 -467.799928)
					(mid 45.749718 -463.050128)
					(end 40.999918 -458.300074)
				)
			)
		)
	)
	(zone
		(layer "B.Cu")
		(hatch none 0.5)
		(connect_pads
			(clearance 0)
		)
		(min_thickness 0.25)
		(keepout
			(tracks allowed)
			(vias allowed)
			(pads allowed)
			(copperpour allowed)
			(footprints not_allowed)
		)
		(placement
			(enabled no)
			(sheetname "")
		)
		(fill
			(thermal_gap 0.5)
			(thermal_bridge_width 0.5)
			(island_removal_mode 0)
		)
		(polygon
			(pts
				(arc
					(start 7.599934 -357.65994)
					(mid 3.599942 -361.659932)
					(end 7.599934 -365.659924)
				)
				(arc
					(start 7.599934 -365.659924)
					(mid 11.599926 -361.659932)
					(end 7.599934 -357.65994)
				)
			)
		)
	)
	(zone
		(layer "B.Cu")
		(hatch none 0.5)
		(connect_pads
			(clearance 0)
		)
		(min_thickness 0.25)
		(keepout
			(tracks allowed)
			(vias allowed)
			(pads allowed)
			(copperpour allowed)
			(footprints not_allowed)
		)
		(placement
			(enabled no)
			(sheetname "")
		)
		(fill
			(thermal_gap 0.5)
			(thermal_bridge_width 0.5)
			(island_removal_mode 0)
		)
		(polygon
			(pts
				(arc
					(start 7.599934 -178.340004)
					(mid 3.599942 -182.339996)
					(end 7.599934 -186.339988)
				)
				(arc
					(start 7.599934 -186.339988)
					(mid 11.599926 -182.339996)
					(end 7.599934 -178.340004)
				)
			)
		)
	)
	(zone
		(layer "B.Cu")
		(hatch none 0.5)
		(connect_pads
			(clearance 0)
		)
		(min_thickness 0.25)
		(keepout
			(tracks allowed)
			(vias allowed)
			(pads allowed)
			(copperpour allowed)
			(footprints not_allowed)
		)
		(placement
			(enabled no)
			(sheetname "")
		)
		(fill
			(thermal_gap 0.5)
			(thermal_bridge_width 0.5)
			(island_removal_mode 0)
		)
		(polygon
			(pts
				(arc
					(start 6.999986 -155.999942)
					(mid 2.999994 -159.999934)
					(end 6.999986 -163.999926)
				)
				(arc
					(start 6.999986 -163.999926)
					(mid 10.999978 -159.999934)
					(end 6.999986 -155.999942)
				)
			)
		)
	)
	(zone
		(layer "B.Cu")
		(hatch none 0.5)
		(connect_pads
			(clearance 0)
		)
		(min_thickness 0.25)
		(keepout
			(tracks allowed)
			(vias allowed)
			(pads allowed)
			(copperpour allowed)
			(footprints not_allowed)
		)
		(placement
			(enabled no)
			(sheetname "")
		)
		(fill
			(thermal_gap 0.5)
			(thermal_bridge_width 0.5)
			(island_removal_mode 0)
		)
		(polygon
			(pts
				(arc
					(start 17.500092 -491.000034)
					(mid 17.792985 -490.292929)
					(end 18.50009 -490.000036)
				)
				(arc
					(start 51.500024 -490.000036)
					(mid 52.207129 -489.707143)
					(end 52.500022 -489.000038)
				)
				(arc
					(start 52.500022 -10.999978)
					(mid 52.207129 -10.292873)
					(end 51.500024 -9.99998)
				)
				(arc
					(start 18.50009 -9.99998)
					(mid 17.792985 -9.707087)
					(end 17.500092 -8.999982)
				)
				(arc
					(start 17.500092 -0.999998)
					(mid 17.207199 -0.292893)
					(end 16.500094 0)
				)
				(arc
					(start 0.999998 0)
					(mid 0.292893 -0.292893)
					(end 0 -0.999998)
				)
				(arc
					(start 0 -499.000018)
					(mid 0.292893 -499.707123)
					(end 0.999998 -500.000016)
				)
				(arc
					(start 16.500094 -500.000016)
					(mid 17.207199 -499.707123)
					(end 17.500092 -499.000018)
				)
			)
		)
	)
	(zone
		(layer "B.Cu")
		(hatch none 0.5)
		(connect_pads
			(clearance 0)
		)
		(min_thickness 0.25)
		(keepout
			(tracks allowed)
			(vias allowed)
			(pads allowed)
			(copperpour allowed)
			(footprints not_allowed)
		)
		(placement
			(enabled no)
			(sheetname "")
		)
		(fill
			(thermal_gap 0.5)
			(thermal_bridge_width 0.5)
			(island_removal_mode 0)
		)
		(polygon
			(pts
				(arc
					(start 7.599934 -2.29997)
					(mid 3.599942 -6.299962)
					(end 7.599934 -10.299954)
				)
				(arc
					(start 7.599934 -10.299954)
					(mid 11.599926 -6.299962)
					(end 7.599934 -2.29997)
				)
			)
		)
	)
	(zone
		(net "GND")
		(layer "B.Cu")
		(hatch none 0.5)
		(connect_pads
			(clearance 0.5)
		)
		(min_thickness 0.25)
		(fill yes
			(thermal_gap 0.5)
			(thermal_bridge_width 0.5)
			(island_removal_mode 0)
		)
		(polygon
			(pts
				(arc
					(start 0.999998 -0.762254)
					(mid 0.831888 -0.831888)
					(end 0.762254 -0.999998)
				)
				(arc
					(start 0.762254 -499.000018)
					(mid 0.831888 -499.168128)
					(end 0.999998 -499.237762)
				)
				(arc
					(start 16.500094 -499.237762)
					(mid 16.668204 -499.168128)
					(end 16.737838 -499.000018)
				)
				(arc
					(start 16.737838 -491.000034)
					(mid 17.25399 -489.753934)
					(end 18.50009 -489.237782)
				)
				(arc
					(start 51.500024 -489.237782)
					(mid 51.668134 -489.168148)
					(end 51.737768 -489.000038)
				)
				(arc
					(start 51.737768 -10.999978)
					(mid 51.668134 -10.831868)
					(end 51.500024 -10.762234)
				)
				(arc
					(start 18.50009 -10.762234)
					(mid 17.25399 -10.246082)
					(end 16.737838 -8.999982)
				)
				(arc
					(start 16.737838 -0.999998)
					(mid 16.668204 -0.831888)
					(end 16.500094 -0.762254)
				)
			)
		)
		(polygon
			(pts
				(arc
					(start 46.644306 -61.983366)
					(mid 46.534606 -62.551147)
					(end 46.136052 -62.970156)
				)
				(arc
					(start 46.136052 -62.970156)
					(mid 46.086321 -63.044909)
					(end 46.115224 -63.129922)
				)
				(arc
					(start 49.813718 -66.828416)
					(mid 49.924502 -66.850452)
					(end 49.9872 -66.756534)
				)
				(xy 49.9872 -65.071752)
				(arc
					(start 46.81728 -61.901832)
					(mid 46.702071 -61.881753)
					(end 46.644306 -61.983366)
				)
			)
		)
		(polygon
			(pts
				(arc
					(start 46.60011 -64.946784)
					(mid 46.63341 -65.437946)
					(end 46.434756 -65.888362)
				)
				(xy 46.407578 -65.923668)
				(arc
					(start 49.368964 -68.885054)
					(mid 49.479509 -68.90689)
					(end 49.542192 -68.813172)
				)
				(xy 49.542192 -67.617848)
				(arc
					(start 46.768766 -64.844168)
					(mid 46.644057 -64.829198)
					(end 46.60011 -64.946784)
				)
			)
		)
		(polygon
			(pts
				(arc
					(start 42.6339 -63.007494)
					(mid 42.535563 -63.012991)
					(end 42.488104 -63.099188)
				)
				(xy 42.488104 -63.643256)
				(arc
					(start 42.153586 -63.308738)
					(mid 42.042802 -63.286702)
					(end 41.980104 -63.38062)
				)
				(arc
					(start 41.980104 -64.72809)
					(mid 42.057091 -64.826664)
					(end 42.171366 -64.775842)
				)
				(arc
					(start 42.171366 -64.775842)
					(mid 42.303301 -64.584212)
					(end 42.474896 -64.4271)
				)
				(arc
					(start 42.474896 -64.4271)
					(mid 42.514549 -64.366403)
					(end 42.503598 -64.294766)
				)
				(arc
					(start 42.503598 -64.294766)
					(mid 42.561568 -64.338386)
					(end 42.6339 -64.332358)
				)
				(arc
					(start 42.6339 -64.332358)
					(mid 43.791058 -64.516262)
					(end 44.026074 -65.66408)
				)
				(arc
					(start 44.026074 -65.66408)
					(mid 44.034605 -65.760182)
					(end 44.119546 -65.805812)
				)
				(arc
					(start 44.579794 -65.805812)
					(mid 44.664632 -65.760114)
					(end 44.673266 -65.66408)
				)
				(arc
					(start 44.673266 -65.66408)
					(mid 44.858492 -64.567437)
					(end 45.932852 -64.279526)
				)
				(arc
					(start 45.932852 -64.279526)
					(mid 46.050336 -64.235517)
					(end 46.035468 -64.11087)
				)
				(xy 45.520102 -63.595504) (xy 44.064936 -63.595504) (xy 43.492674 -63.023242)
				(arc
					(start 43.461432 -63.035688)
					(mid 43.044698 -63.108515)
					(end 42.6339 -63.007494)
				)
			)
		)
		(polygon
			(pts
				(arc
					(start 42.488104 -61.060584)
					(mid 42.535664 -61.14662)
					(end 42.6339 -61.152278)
				)
				(arc
					(start 42.6339 -61.152278)
					(mid 43.782247 -61.327854)
					(end 44.035472 -62.461648)
				)
				(xy 44.023026 -62.49289) (xy 44.375832 -62.845696)
				(arc
					(start 44.704508 -62.845696)
					(mid 44.79482 -62.790145)
					(end 44.78655 -62.684406)
				)
				(arc
					(start 44.78655 -62.684406)
					(mid 44.592234 -62.017361)
					(end 44.866052 -61.378846)
				)
				(arc
					(start 44.866052 -61.378846)
					(mid 44.884956 -61.269041)
					(end 44.791884 -61.207904)
				)
				(xy 44.217336 -61.207904) (xy 43.492674 -60.483242)
				(arc
					(start 43.461432 -60.495688)
					(mid 43.044698 -60.568515)
					(end 42.6339 -60.467494)
				)
				(arc
					(start 42.6339 -60.467494)
					(mid 42.535563 -60.472991)
					(end 42.488104 -60.559188)
				)
			)
		)
		(polygon
			(pts
				(xy 14.097 -413.512) (xy 12.573 -415.036) (xy 12.573 -472.694) (xy 15.748 -475.869) (xy 30.607 -475.869)
				(xy 33.147 -473.329) (xy 33.655 -472.821) (xy 33.655 -425.958) (xy 35.56 -424.053) (xy 46.863 -424.053)
				(xy 47.371 -423.545) (xy 47.371 -415.29) (xy 45.72 -413.639) (xy 45.6946 -413.639) (xy 44.2214 -412.1658)
				(xy 37.6936 -412.1658) (xy 36.7284 -411.2006) (xy 30.5816 -411.2006) (xy 29.5402 -410.1592) (xy 20.193 -410.1592)
				(xy 17.653 -407.6192) (xy 16.3068 -407.6192) (xy 15.494 -408.432) (xy 15.494 -412.115)
			)
		)
		(polygon
			(pts
				(arc
					(start 4.76885 -423.077132)
					(mid 4.685224 -423.098958)
					(end 4.648708 -423.177208)
				)
				(arc
					(start 4.648708 -432.903376)
					(mid 4.685453 -432.981583)
					(end 4.769104 -433.003198)
				)
				(arc
					(start 4.769104 -433.003198)
					(mid 4.837667 -432.994537)
					(end 4.906772 -432.994054)
				)
				(xy 4.929124 -432.995324) (xy 5.066792 -432.857402)
				(arc
					(start 5.066792 -423.186098)
					(mid 5.033441 -423.110834)
					(end 4.955286 -423.085006)
				)
				(arc
					(start 4.955286 -423.085006)
					(mid 4.86179 -423.087671)
					(end 4.76885 -423.077132)
				)
			)
		)
		(polygon
			(pts
				(arc
					(start 3.605276 -368.498628)
					(mid 3.507202 -368.504522)
					(end 3.459988 -368.590576)
				)
				(xy 3.459988 -368.92865) (xy 3.694684 -369.163346)
				(arc
					(start 3.724402 -369.153694)
					(mid 4.080912 -369.104238)
					(end 4.4323 -369.182142)
				)
				(arc
					(start 4.4323 -369.182142)
					(mid 4.527727 -369.172936)
					(end 4.573016 -369.088416)
				)
				(arc
					(start 4.573016 -368.611404)
					(mid 4.527749 -368.526851)
					(end 4.4323 -368.517678)
				)
				(arc
					(start 4.4323 -368.517678)
					(mid 4.016758 -368.596111)
					(end 3.605276 -368.498628)
				)
			)
		)
		(polygon
			(pts
				(arc
					(start 38.178486 -365.87938)
					(mid 38.07605 -365.877791)
					(end 38.024308 -365.966248)
				)
				(xy 38.024308 -368.849402)
				(arc
					(start 38.049454 -368.864134)
					(mid 38.280666 -369.088236)
					(end 38.378638 -369.394994)
				)
				(xy 38.379908 -369.414044) (xy 38.429692 -369.464082) (xy 38.474904 -369.41887)
				(arc
					(start 38.47846 -369.406424)
					(mid 38.670998 -369.116299)
					(end 38.994334 -368.98707)
				)
				(xy 39.012876 -368.985546) (xy 38.979856 -369.018566) (xy 39.294308 -369.332764) (xy 39.294308 -369.471448)
				(arc
					(start 39.30142 -369.483386)
					(mid 39.314859 -369.506871)
					(end 39.327328 -369.530884)
				)
				(arc
					(start 39.327328 -369.530884)
					(mid 39.386865 -369.557065)
					(end 39.42334 -369.503198)
				)
				(arc
					(start 39.42334 -369.503198)
					(mid 39.446829 -369.268992)
					(end 39.560754 -369.063016)
				)
				(xy 39.572692 -369.048792) (xy 39.572692 -368.3254)
				(arc
					(start 39.529258 -368.31905)
					(mid 39.43102 -368.297161)
					(end 39.337234 -368.26063)
				)
				(arc
					(start 39.337234 -368.26063)
					(mid 39.239282 -368.266192)
					(end 39.191692 -368.35207)
				)
				(xy 39.191692 -368.165634)
				(arc
					(start 39.175436 -368.150394)
					(mid 38.963079 -367.665)
					(end 39.175436 -367.179606)
				)
				(xy 39.191692 -367.164366) (xy 39.191692 -366.70107) (xy 38.454076 -365.963454)
				(arc
					(start 38.435534 -365.96193)
					(mid 38.302184 -365.935686)
					(end 38.178486 -365.87938)
				)
			)
		)
		(polygon
			(pts
				(arc
					(start 4.07797 -364.958122)
					(mid 3.967425 -364.936286)
					(end 3.904742 -365.030004)
				)
				(arc
					(start 3.904488 -366.46231)
					(mid 3.935422 -366.53531)
					(end 4.00939 -366.56391)
				)
				(arc
					(start 4.00939 -366.56391)
					(mid 4.225029 -366.580405)
					(end 4.4323 -366.642142)
				)
				(arc
					(start 4.4323 -366.642142)
					(mid 4.527727 -366.632936)
					(end 4.573016 -366.548416)
				)
				(xy 4.573016 -365.453422)
			)
		)
		(polygon
			(pts
				(arc
					(start 5.97662 -363.006132)
					(mid 5.863966 -362.975348)
					(end 5.796788 -363.070902)
				)
				(xy 5.796788 -363.177836) (xy 6.771132 -364.151926)
				(arc
					(start 6.771132 -377.565666)
					(mid 6.833768 -377.659498)
					(end 6.94436 -377.637548)
				)
				(xy 7.213092 -377.368562) (xy 7.213092 -366.141508) (xy 9.40308 -363.95152)
				(arc
					(start 9.40308 -363.070902)
					(mid 9.335914 -362.975315)
					(end 9.223248 -363.006132)
				)
				(arc
					(start 9.223248 -363.006132)
					(mid 8.964374 -363.267863)
					(end 8.66394 -363.480604)
				)
				(arc
					(start 8.66394 -363.480604)
					(mid 8.617761 -363.538892)
					(end 8.623808 -363.612938)
				)
				(arc
					(start 8.623808 -363.612938)
					(mid 8.566289 -363.565935)
					(end 8.492236 -363.570774)
				)
				(arc
					(start 8.492236 -363.570774)
					(mid 7.138087 -363.717653)
					(end 5.97662 -363.006132)
				)
			)
		)
		(polygon
			(pts
				(arc
					(start 16.876522 -299.427646)
					(mid 16.821174 -299.416789)
					(end 16.789908 -299.463714)
				)
				(arc
					(start 16.789908 -336.583528)
					(mid 16.852662 -336.677155)
					(end 16.963136 -336.655156)
				)
				(xy 17.042892 -336.5754) (xy 17.042892 -299.809408)
				(arc
					(start 17.030954 -299.795184)
					(mid 16.935048 -299.638935)
					(end 16.89227 -299.460666)
				)
				(xy 16.890746 -299.442124)
			)
		)
		(polygon
			(pts
				(arc
					(start 17.892522 -291.071046)
					(mid 17.837174 -291.060189)
					(end 17.805908 -291.107114)
				)
				(arc
					(start 17.805908 -294.334692)
					(mid 17.835576 -294.406444)
					(end 17.907254 -294.436292)
				)
				(arc
					(start 17.946878 -294.437562)
					(mid 17.98662 -294.422486)
					(end 18.00098 -294.382444)
				)
				(arc
					(start 18.00098 -294.382444)
					(mid 18.034872 -294.127469)
					(end 18.17497 -293.911782)
				)
				(arc
					(start 18.17497 -293.911782)
					(mid 18.205511 -293.839677)
					(end 18.175732 -293.767256)
				)
				(xy 17.931892 -293.52367) (xy 17.931892 -291.11067)
			)
		)
		(polygon
			(pts
				(arc
					(start 32.619696 -259.372354)
					(mid 32.582567 -259.29383)
					(end 32.498284 -259.272532)
				)
				(arc
					(start 32.498284 -259.272532)
					(mid 32.406861 -259.283204)
					(end 32.314896 -259.27939)
				)
				(arc
					(start 32.314896 -259.27939)
					(mid 32.235235 -259.304301)
					(end 32.201104 -259.380482)
				)
				(arc
					(start 32.201104 -274.49018)
					(mid 32.263823 -274.584046)
					(end 32.374586 -274.562062)
				)
				(xy 32.619696 -274.316952)
			)
		)
		(polygon
			(pts
				(arc
					(start 44.329096 -252.20422)
					(mid 44.266377 -252.110354)
					(end 44.155614 -252.132338)
				)
				(xy 37.844476 -258.443476)
				(arc
					(start 37.863526 -258.477004)
					(mid 37.930633 -258.951794)
					(end 37.659056 -259.346954)
				)
				(xy 37.636704 -259.362194)
				(arc
					(start 37.636704 -259.421884)
					(mid 37.699423 -259.51575)
					(end 37.810186 -259.493766)
				)
				(xy 44.329096 -252.97511)
			)
		)
		(polygon
			(pts
				(arc
					(start 37.875718 -248.49836)
					(mid 37.76909 -248.488584)
					(end 37.712904 -248.57964)
				)
				(arc
					(start 37.712904 -251.78258)
					(mid 37.775623 -251.876446)
					(end 37.886386 -251.854462)
				)
				(xy 38.518592 -251.222002)
				(arc
					(start 38.518592 -248.690384)
					(mid 38.478147 -248.609251)
					(end 38.389052 -248.592848)
				)
				(arc
					(start 38.389052 -248.592848)
					(mid 38.121237 -248.606107)
					(end 37.875718 -248.49836)
				)
			)
		)
		(polygon
			(pts
				(arc
					(start 39.706296 -248.167906)
					(mid 39.662957 -248.08467)
					(end 39.569898 -248.072402)
				)
				(arc
					(start 39.569898 -248.072402)
					(mid 39.471619 -248.098782)
					(end 39.370254 -248.107708)
				)
				(arc
					(start 39.370254 -248.107708)
					(mid 39.298576 -248.137556)
					(end 39.268908 -248.209308)
				)
				(arc
					(start 39.268908 -250.86183)
					(mid 39.331544 -250.955662)
					(end 39.442136 -250.933712)
				)
				(xy 39.706296 -250.669552)
			)
		)
		(polygon
			(pts
				(arc
					(start 38.657784 -242.496086)
					(mid 38.621146 -242.501084)
					(end 38.597586 -242.529614)
				)
				(arc
					(start 38.597586 -242.529614)
					(mid 38.397259 -242.81136)
					(end 38.072822 -242.93068)
				)
				(xy 38.053264 -242.931696) (xy 37.712904 -243.272056) (xy 37.712904 -247.646698) (xy 37.785802 -247.646698)
				(xy 37.800788 -247.630696) (xy 37.835332 -247.596914) (xy 37.852096 -247.581928) (xy 37.852096 -243.856002)
				(xy 38.931596 -242.776502)
				(arc
					(start 38.931596 -242.613942)
					(mid 38.900113 -242.540415)
					(end 38.82517 -242.512342)
				)
				(arc
					(start 38.82517 -242.512342)
					(mid 38.740891 -242.510252)
					(end 38.657784 -242.496086)
				)
			)
		)
		(polygon
			(pts
				(arc
					(start 36.802314 -242.487704)
					(mid 36.766754 -242.473195)
					(end 36.731194 -242.487704)
				)
				(xy 36.713668 -242.504214) (xy 36.696904 -242.5192) (xy 36.696904 -251.361448) (xy 32.201104 -255.857248)
				(arc
					(start 32.201104 -256.55778)
					(mid 32.263823 -256.651646)
					(end 32.374586 -256.629662)
				)
				(xy 36.963096 -252.041152) (xy 36.963096 -242.96116)
				(arc
					(start 37.116766 -242.80749)
					(mid 37.142852 -242.708472)
					(end 37.069522 -242.637056)
				)
				(arc
					(start 37.069522 -242.637056)
					(mid 36.925977 -242.580169)
					(end 36.802314 -242.487704)
				)
			)
		)
		(polygon
			(pts
				(arc
					(start 15.830296 -230.263192)
					(mid 15.767459 -230.169531)
					(end 15.656814 -230.191564)
				)
				(xy 15.291308 -230.55707) (xy 15.291308 -231.274366)
				(arc
					(start 15.307564 -231.289606)
					(mid 15.519921 -231.775)
					(end 15.307564 -232.260394)
				)
				(xy 15.291308 -232.275634) (xy 15.291308 -232.97007)
				(arc
					(start 13.71346 -234.547664)
					(mid 13.690945 -234.657272)
					(end 13.782802 -234.721146)
				)
				(arc
					(start 13.782802 -234.721146)
					(mid 13.822271 -234.723269)
					(end 13.861542 -234.72775)
				)
				(xy 13.886942 -234.731306) (xy 15.830296 -232.787952)
			)
		)
		(polygon
			(pts
				(arc
					(start 14.197584 -216.982802)
					(mid 14.085959 -216.957035)
					(end 14.021308 -217.051636)
				)
				(arc
					(start 14.021308 -222.8342)
					(mid 14.052334 -222.907288)
					(end 14.126464 -222.9358)
				)
				(arc
					(start 14.126464 -222.9358)
					(mid 14.162305 -222.935591)
					(end 14.198092 -222.937578)
				)
				(arc
					(start 14.198092 -222.937578)
					(mid 14.275529 -222.911145)
					(end 14.308328 -222.836232)
				)
				(xy 14.308328 -217.07983)
				(arc
					(start 14.288008 -217.06459)
					(mid 14.240911 -217.02578)
					(end 14.197584 -216.982802)
				)
			)
		)
		(polygon
			(pts
				(arc
					(start 29.755846 -212.028786)
					(mid 29.693127 -211.93492)
					(end 29.582364 -211.956904)
				)
				(xy 27.626564 -213.912704) (xy 27.475688 -213.912704)
				(arc
					(start 27.460702 -213.929468)
					(mid 27.078284 -214.120179)
					(end 26.668222 -213.999826)
				)
				(xy 26.654252 -213.988904) (xy 25.925272 -213.988904)
				(arc
					(start 25.910286 -214.005668)
					(mid 25.713844 -214.148191)
					(end 25.476454 -214.198708)
				)
				(arc
					(start 25.476454 -214.198708)
					(mid 25.404776 -214.228556)
					(end 25.375108 -214.300308)
				)
				(arc
					(start 25.375108 -218.85148)
					(mid 25.44003 -218.945975)
					(end 25.551638 -218.919806)
				)
				(arc
					(start 25.551638 -218.919806)
					(mid 25.761504 -218.772589)
					(end 26.014172 -218.729306)
				)
				(xy 26.036524 -218.730576) (xy 26.121614 -218.645232) (xy 26.770584 -218.645232)
				(arc
					(start 26.78557 -218.628722)
					(mid 27.420665 -218.471364)
					(end 27.80411 -219.001594)
				)
				(arc
					(start 27.80411 -219.001594)
					(mid 27.835007 -219.07133)
					(end 27.90571 -219.099892)
				)
				(arc
					(start 28.117292 -219.099892)
					(mid 28.189044 -219.070224)
					(end 28.218892 -218.998546)
				)
				(xy 28.219654 -218.968828) (xy 28.220924 -218.946476) (xy 27.946096 -218.671648) (xy 27.946096 -216.755472)
				(arc
					(start 27.929332 -216.740486)
					(mid 27.736334 -216.3064)
					(end 27.929332 -215.872314)
				)
				(xy 27.946096 -215.857328) (xy 27.946096 -214.017352) (xy 29.755592 -212.207602)
			)
		)
		(polygon
			(pts
				(arc
					(start 16.064992 -210.945984)
					(mid 16.00851 -210.854952)
					(end 15.901924 -210.865212)
				)
				(arc
					(start 15.901924 -210.865212)
					(mid 15.648544 -210.976625)
					(end 15.372334 -210.958938)
				)
				(arc
					(start 15.372334 -210.958938)
					(mid 15.281874 -210.974113)
					(end 15.240508 -211.055966)
				)
				(xy 15.240508 -213.995254)
				(arc
					(start 15.250922 -214.00897)
					(mid 15.365864 -214.216003)
					(end 15.416276 -214.447374)
				)
				(arc
					(start 15.416276 -214.447374)
					(mid 15.482054 -214.535428)
					(end 15.589504 -214.512144)
				)
				(xy 16.064992 -214.036402)
			)
		)
		(polygon
			(pts
				(arc
					(start 13.613892 -194.435476)
					(mid 13.54372 -194.338859)
					(end 13.43025 -194.375786)
				)
				(arc
					(start 13.43025 -194.375786)
					(mid 12.114171 -195.102231)
					(end 10.715244 -194.551808)
				)
				(arc
					(start 10.715244 -194.551808)
					(mid 10.604103 -194.527318)
					(end 10.539984 -194.621404)
				)
				(xy 10.539984 -195.221606) (xy 13.437108 -198.11873) (xy 13.437108 -209.663792)
				(arc
					(start 13.449046 -209.678016)
					(mid 13.486497 -209.726605)
					(end 13.518642 -209.778854)
				)
				(xy 13.53312 -209.805524) (xy 13.613892 -209.805524)
			)
		)
		(polygon
			(pts
				(arc
					(start 15.506192 -177.719736)
					(mid 15.434809 -177.622733)
					(end 15.321026 -177.662078)
				)
				(arc
					(start 15.321026 -177.662078)
					(mid 15.288668 -177.705754)
					(end 15.253462 -177.747168)
				)
				(xy 15.240508 -177.761646)
				(arc
					(start 15.240508 -209.745834)
					(mid 15.28189 -209.827665)
					(end 15.372334 -209.842862)
				)
				(arc
					(start 15.372334 -209.842862)
					(mid 15.417138 -209.830781)
					(end 15.462758 -209.822288)
				)
				(xy 15.506192 -209.815938)
			)
		)
		(polygon
			(pts
				(arc
					(start 37.943536 -176.522888)
					(mid 37.832991 -176.501052)
					(end 37.770308 -176.59477)
				)
				(xy 37.770308 -176.946052) (xy 38.189408 -177.365152)
				(arc
					(start 38.189408 -185.896758)
					(mid 38.252162 -185.990385)
					(end 38.362636 -185.968386)
				)
				(xy 39.01186 -185.319162)
				(arc
					(start 39.01186 -179.982368)
					(mid 38.982192 -179.910616)
					(end 38.910514 -179.880768)
				)
				(arc
					(start 38.910514 -179.880768)
					(mid 38.364959 -179.505765)
					(end 38.5191 -178.861974)
				)
				(xy 38.535864 -178.846988) (xy 38.535864 -177.36312)
				(arc
					(start 38.4937 -177.355754)
					(mid 38.061555 -177.076593)
					(end 37.960554 -176.572164)
				)
				(xy 37.965888 -176.545494)
			)
		)
		(polygon
			(pts
				(arc
					(start 38.969696 -175.14316)
					(mid 38.903462 -175.047914)
					(end 38.791134 -175.076866)
				)
				(arc
					(start 38.791134 -175.076866)
					(mid 38.66588 -175.185923)
					(end 38.515036 -175.255428)
				)
				(arc
					(start 38.515036 -175.255428)
					(mid 38.456939 -175.300517)
					(end 38.444424 -175.37303)
				)
				(arc
					(start 38.444424 -175.37303)
					(mid 38.444833 -175.603662)
					(end 38.356032 -175.816514)
				)
				(xy 38.332664 -175.851312) (xy 38.529514 -176.048162)
				(arc
					(start 38.552882 -176.04613)
					(mid 38.695117 -176.049594)
					(end 38.833298 -176.083468)
				)
				(arc
					(start 38.833298 -176.083468)
					(mid 38.926383 -176.071238)
					(end 38.969696 -175.987964)
				)
			)
		)
		(polygon
			(pts
				(arc
					(start 21.518118 -173.337728)
					(mid 21.443876 -173.295279)
					(end 21.363432 -173.32452)
				)
				(xy 21.09216 -173.595792)
				(arc
					(start 21.095716 -173.621192)
					(mid 20.908976 -174.183244)
					(end 20.346924 -174.369984)
				)
				(xy 20.321524 -174.366428) (xy 19.840448 -174.847504) (xy 19.778472 -174.847504)
				(arc
					(start 19.763486 -174.864268)
					(mid 19.567044 -175.006791)
					(end 19.329654 -175.057308)
				)
				(arc
					(start 19.329654 -175.057308)
					(mid 19.257976 -175.087156)
					(end 19.228308 -175.158908)
				)
				(xy 19.228308 -175.308514)
				(arc
					(start 19.27225 -175.314356)
					(mid 19.732451 -175.663519)
					(end 19.668236 -176.237646)
				)
				(arc
					(start 19.668236 -176.237646)
					(mid 19.65991 -176.343414)
					(end 19.750278 -176.398936)
				)
				(xy 20.290282 -176.398936)
				(arc
					(start 20.514564 -176.623218)
					(mid 20.625109 -176.645054)
					(end 20.687792 -176.551336)
				)
				(xy 20.687792 -175.60417) (xy 21.62048 -174.671482) (xy 21.62048 -173.449234)
				(arc
					(start 21.60397 -173.434248)
					(mid 21.558371 -173.388365)
					(end 21.518118 -173.337728)
				)
			)
		)
		(polygon
			(pts
				(arc
					(start 38.902386 -171.191936)
					(mid 38.791602 -171.1699)
					(end 38.728904 -171.263818)
				)
				(xy 38.728904 -174.25035)
				(arc
					(start 38.745414 -174.26559)
					(mid 38.768933 -174.288574)
					(end 38.791134 -174.312834)
				)
				(arc
					(start 38.791134 -174.312834)
					(mid 38.903454 -174.341765)
					(end 38.969696 -174.24654)
				)
				(xy 38.969696 -172.965364)
				(arc
					(start 38.958774 -172.951394)
					(mid 38.930535 -172.274324)
					(end 39.560754 -172.02531)
				)
				(xy 39.566596 -172.026834) (xy 39.623492 -172.026834) (xy 39.623492 -171.913296)
			)
		)
		(polygon
			(pts
				(arc
					(start 35.339528 -170.077384)
					(mid 35.228983 -170.055548)
					(end 35.1663 -170.149266)
				)
				(xy 35.1663 -170.398694) (xy 35.897058 -171.129706)
				(arc
					(start 35.922458 -171.12615)
					(mid 36.002613 -171.119485)
					(end 36.082986 -171.122594)
				)
				(arc
					(start 36.082986 -171.122594)
					(mid 36.161125 -171.096748)
					(end 36.194492 -171.021502)
				)
				(xy 36.194492 -170.932602)
			)
		)
		(polygon
			(pts
				(arc
					(start 37.469572 -168.557448)
					(mid 37.406936 -168.463616)
					(end 37.296344 -168.485566)
				)
				(xy 36.815268 -168.966642)
				(arc
					(start 36.816538 -168.988994)
					(mid 36.817307 -169.018966)
					(end 36.816538 -169.048938)
				)
				(xy 36.815268 -169.07129)
				(arc
					(start 37.296344 -169.552366)
					(mid 37.406889 -169.574202)
					(end 37.469572 -169.480484)
				)
			)
		)
		(polygon
			(pts
				(xy 43.660822 -159.56026) (xy 43.61053 -159.510222) (xy 43.504104 -159.616648) (xy 43.504104 -159.82315)
				(xy 43.504358 -166.535354) (xy 43.504358 -166.625778) (xy 43.504358 -166.662862) (xy 43.504358 -166.670228)
				(arc
					(start 43.504358 -168.28135)
					(mid 43.535635 -168.328249)
					(end 43.590972 -168.317418)
				)
				(xy 43.686476 -168.22166) (xy 43.686476 -159.732726)
				(arc
					(start 43.684444 -159.725868)
					(mid 43.668274 -159.653829)
					(end 43.66133 -159.580326)
				)
			)
		)
		(polygon
			(pts
				(arc
					(start 39.420292 -157.721554)
					(mid 39.358187 -157.62769)
					(end 39.247572 -157.648656)
				)
				(arc
					(start 39.247572 -157.648656)
					(mid 39.215364 -157.678198)
					(end 39.181278 -157.705552)
				)
				(xy 39.160704 -157.720792) (xy 39.160704 -158.016448) (xy 37.458904 -159.718248) (xy 37.458904 -162.37077)
				(arc
					(start 37.479478 -162.38601)
					(mid 37.74496 -162.9156)
					(end 37.479478 -163.44519)
				)
				(xy 37.458904 -163.46043)
				(arc
					(start 37.458904 -166.568628)
					(mid 37.5037 -166.652865)
					(end 37.598604 -166.662862)
				)
				(arc
					(start 37.598604 -166.662862)
					(mid 37.766353 -166.620054)
					(end 37.939472 -166.622222)
				)
				(xy 37.964872 -166.625778) (xy 38.055296 -166.535354) (xy 38.055296 -159.82315) (xy 39.420292 -158.458154)
			)
		)
		(polygon
			(pts
				(xy 38.24097 -157.55112)
				(arc
					(start 36.177982 -157.55112)
					(mid 36.08415 -157.613756)
					(end 36.1061 -157.724348)
				)
				(xy 36.652708 -158.270702)
				(arc
					(start 36.652708 -159.21863)
					(mid 36.715344 -159.312462)
					(end 36.825936 -159.290512)
				)
				(arc
					(start 38.324028 -157.79242)
					(mid 38.353802 -157.720088)
					(end 38.323266 -157.648148)
				)
				(arc
					(start 38.323266 -157.648148)
					(mid 38.288249 -157.611095)
					(end 38.25621 -157.57144)
				)
			)
		)
		(polygon
			(pts
				(xy 36.66109 -154.343608)
				(arc
					(start 33.69437 -154.343608)
					(mid 33.600538 -154.406244)
					(end 33.622488 -154.516836)
				)
				(xy 35.90671 -156.800804) (xy 38.24097 -156.800804)
				(arc
					(start 38.25621 -156.780484)
					(mid 38.422472 -156.62382)
					(end 38.63213 -156.533088)
				)
				(arc
					(start 38.63213 -156.533088)
					(mid 38.706083 -156.461888)
					(end 38.680136 -156.362654)
				)
			)
		)
		(polygon
			(pts
				(arc
					(start 29.528008 -152.20696)
					(mid 29.501885 -152.209307)
					(end 29.475684 -152.210516)
				)
				(xy 29.453332 -152.232868) (xy 29.452824 -152.253188) (xy 29.452316 -152.268174) (xy 29.451046 -152.290526)
				(arc
					(start 35.815778 -158.655258)
					(mid 35.870974 -158.666237)
					(end 35.902392 -158.619444)
				)
				(xy 35.902392 -158.581598)
			)
		)
		(polygon
			(pts
				(xy 28.881324 -151.511508) (xy 24.952198 -151.511508) (xy 23.670514 -152.792938)
				(arc
					(start 23.67407 -152.818338)
					(mid 23.574021 -153.273414)
					(end 23.198582 -153.54935)
				)
				(arc
					(start 23.198582 -153.54935)
					(mid 23.127758 -153.621427)
					(end 23.154132 -153.719022)
				)
				(arc
					(start 33.709864 -164.274754)
					(mid 33.820409 -164.29659)
					(end 33.883092 -164.202872)
				)
				(xy 33.883092 -163.552124) (xy 33.360614 -163.029392)
				(arc
					(start 33.338262 -163.030662)
					(mid 32.894834 -162.03326)
					(end 33.892236 -162.476688)
				)
				(xy 33.890966 -162.49904) (xy 34.633408 -163.241228)
				(arc
					(start 34.633408 -164.709348)
					(mid 34.702542 -164.805621)
					(end 34.81578 -164.770816)
				)
				(arc
					(start 34.81578 -164.770816)
					(mid 35.050632 -164.587904)
					(end 35.345116 -164.544248)
				)
				(arc
					(start 35.345116 -164.544248)
					(mid 35.423965 -164.518998)
					(end 35.457892 -164.44341)
				)
				(xy 35.457892 -159.35833) (xy 28.920694 -152.820878)
				(arc
					(start 28.898342 -152.822148)
					(mid 28.284603 -152.271481)
					(end 28.831794 -151.654764)
				)
				(arc
					(start 28.831794 -151.654764)
					(mid 28.865376 -151.639051)
					(end 28.879292 -151.604726)
				)
				(xy 28.88107 -151.566118) (xy 28.881324 -151.564086)
			)
		)
		(polygon
			(pts
				(xy 16.297656 -148.990304)
				(arc
					(start 16.21282 -148.990304)
					(mid 16.118954 -149.053023)
					(end 16.140938 -149.163786)
				)
				(xy 17.908016 -150.930864) (xy 17.944084 -150.894796)
				(arc
					(start 17.944338 -150.894796)
					(mid 17.969733 -150.870221)
					(end 17.996408 -150.847044)
				)
				(arc
					(start 17.996408 -150.847044)
					(mid 18.033647 -150.773519)
					(end 18.004028 -150.696676)
				)
			)
		)
		(polygon
			(pts
				(arc
					(start 3.68046 -142.80642)
					(mid 3.569915 -142.784584)
					(end 3.507232 -142.878302)
				)
				(xy 3.507232 -143.70304) (xy 4.460748 -144.65681)
				(arc
					(start 4.486148 -144.653254)
					(mid 5.0482 -144.839994)
					(end 5.23494 -145.402046)
				)
				(xy 5.231384 -145.427446) (xy 5.903976 -146.100038)
				(arc
					(start 5.926328 -146.098768)
					(mid 6.148043 -146.13023)
					(end 6.341618 -146.242786)
				)
				(xy 6.355842 -146.255486) (xy 6.425692 -146.255486) (xy 6.425692 -146.139408)
				(arc
					(start 6.413754 -146.125184)
					(mid 6.290087 -145.883828)
					(end 6.288532 -145.612612)
				)
				(arc
					(start 6.288532 -145.612612)
					(mid 6.282238 -145.574451)
					(end 6.25094 -145.551652)
				)
				(arc
					(start 6.25094 -145.551652)
					(mid 5.919278 -145.333191)
					(end 5.803646 -144.953228)
				)
				(xy 5.804916 -144.930876)
			)
		)
		(polygon
			(pts
				(arc
					(start 47.840392 -129.191766)
					(mid 47.79055 -129.104338)
					(end 47.690024 -129.102866)
				)
				(arc
					(start 47.690024 -129.102866)
					(mid 47.503605 -129.171517)
					(end 47.305214 -129.181606)
				)
				(arc
					(start 47.305214 -129.181606)
					(mid 47.227075 -129.207452)
					(end 47.193708 -129.282698)
				)
				(arc
					(start 47.193708 -129.670302)
					(mid 47.227059 -129.745566)
					(end 47.305214 -129.771394)
				)
				(arc
					(start 47.305214 -129.771394)
					(mid 47.503592 -129.781549)
					(end 47.690024 -129.850134)
				)
				(arc
					(start 47.690024 -129.850134)
					(mid 47.790447 -129.848488)
					(end 47.840392 -129.761234)
				)
			)
		)
		(polygon
			(pts
				(arc
					(start 49.491392 -128.965198)
					(mid 49.420714 -128.868418)
					(end 49.306988 -128.90627)
				)
				(arc
					(start 49.306988 -128.90627)
					(mid 49.041717 -129.12543)
					(end 48.702214 -129.181606)
				)
				(arc
					(start 48.702214 -129.181606)
					(mid 48.624075 -129.207452)
					(end 48.590708 -129.282698)
				)
				(arc
					(start 48.590708 -129.670302)
					(mid 48.624059 -129.745566)
					(end 48.702214 -129.771394)
				)
				(arc
					(start 48.702214 -129.771394)
					(mid 49.041759 -129.827477)
					(end 49.306988 -130.04673)
				)
				(arc
					(start 49.306988 -130.04673)
					(mid 49.420723 -130.084612)
					(end 49.491392 -129.987802)
				)
			)
		)
		(polygon
			(pts
				(arc
					(start 47.840392 -127.159766)
					(mid 47.79055 -127.072338)
					(end 47.690024 -127.070866)
				)
				(arc
					(start 47.690024 -127.070866)
					(mid 47.503605 -127.139517)
					(end 47.305214 -127.149606)
				)
				(arc
					(start 47.305214 -127.149606)
					(mid 47.227075 -127.175452)
					(end 47.193708 -127.250698)
				)
				(arc
					(start 47.193708 -127.765302)
					(mid 47.227059 -127.840566)
					(end 47.305214 -127.866394)
				)
				(arc
					(start 47.305214 -127.866394)
					(mid 47.503592 -127.876549)
					(end 47.690024 -127.945134)
				)
				(arc
					(start 47.690024 -127.945134)
					(mid 47.790447 -127.943488)
					(end 47.840392 -127.856234)
				)
			)
		)
		(polygon
			(pts
				(arc
					(start 49.491392 -126.933198)
					(mid 49.420714 -126.836418)
					(end 49.306988 -126.87427)
				)
				(arc
					(start 49.306988 -126.87427)
					(mid 49.041717 -127.09343)
					(end 48.702214 -127.149606)
				)
				(arc
					(start 48.702214 -127.149606)
					(mid 48.624075 -127.175452)
					(end 48.590708 -127.250698)
				)
				(arc
					(start 48.590708 -127.765302)
					(mid 48.624059 -127.840566)
					(end 48.702214 -127.866394)
				)
				(arc
					(start 48.702214 -127.866394)
					(mid 49.041759 -127.922477)
					(end 49.306988 -128.14173)
				)
				(arc
					(start 49.306988 -128.14173)
					(mid 49.420723 -128.179612)
					(end 49.491392 -128.082802)
				)
			)
		)
		(polygon
			(pts
				(arc
					(start 13.549884 -125.027436)
					(mid 13.431741 -125.008745)
					(end 13.377672 -125.115574)
				)
				(arc
					(start 13.377672 -125.115574)
					(mid 13.329827 -125.489308)
					(end 13.085572 -125.776228)
				)
				(arc
					(start 13.085572 -125.776228)
					(mid 13.0393 -125.857302)
					(end 13.078714 -125.941836)
				)
				(arc
					(start 13.078714 -125.941836)
					(mid 13.347265 -126.198273)
					(end 13.556234 -126.505208)
				)
				(arc
					(start 13.556234 -126.505208)
					(mid 13.670643 -126.55585)
					(end 13.747496 -126.457202)
				)
				(xy 13.747496 -125.225048)
			)
		)
		(polygon
			(pts
				(arc
					(start 49.491392 -124.901198)
					(mid 49.420714 -124.804418)
					(end 49.306988 -124.84227)
				)
				(arc
					(start 49.306988 -124.84227)
					(mid 49.041717 -125.06143)
					(end 48.702214 -125.117606)
				)
				(arc
					(start 48.702214 -125.117606)
					(mid 48.624075 -125.143452)
					(end 48.590708 -125.218698)
				)
				(arc
					(start 48.590708 -125.733302)
					(mid 48.624059 -125.808566)
					(end 48.702214 -125.834394)
				)
				(arc
					(start 48.702214 -125.834394)
					(mid 49.041759 -125.890477)
					(end 49.306988 -126.10973)
				)
				(arc
					(start 49.306988 -126.10973)
					(mid 49.420723 -126.147612)
					(end 49.491392 -126.050802)
				)
			)
		)
		(polygon
			(pts
				(arc
					(start 47.840646 -124.28347)
					(mid 47.777927 -124.189604)
					(end 47.667164 -124.211588)
				)
				(xy 47.193708 -124.685298)
				(arc
					(start 47.193708 -125.733302)
					(mid 47.227059 -125.808566)
					(end 47.305214 -125.834394)
				)
				(arc
					(start 47.305214 -125.834394)
					(mid 47.503592 -125.844549)
					(end 47.690024 -125.913134)
				)
				(arc
					(start 47.690024 -125.913134)
					(mid 47.790447 -125.911488)
					(end 47.840392 -125.824234)
				)
				(xy 47.840392 -125.733302) (xy 47.840646 -124.685298)
			)
		)
		(polygon
			(pts
				(arc
					(start 11.690096 -123.12142)
					(mid 11.627377 -123.027554)
					(end 11.516614 -123.049538)
				)
				(xy 10.534904 -124.031248)
				(arc
					(start 10.534904 -124.476002)
					(mid 10.572552 -124.555204)
					(end 10.65784 -124.57557)
				)
				(arc
					(start 10.65784 -124.57557)
					(mid 10.784897 -124.561158)
					(end 10.912348 -124.571506)
				)
				(arc
					(start 10.912348 -124.571506)
					(mid 10.989437 -124.554213)
					(end 11.030712 -124.486924)
				)
				(arc
					(start 11.030712 -124.486924)
					(mid 11.70243 -123.926348)
					(end 12.34186 -124.5235)
				)
				(arc
					(start 12.34186 -124.5235)
					(mid 12.390099 -124.600337)
					(end 12.480544 -124.608082)
				)
				(arc
					(start 12.480544 -124.608082)
					(mid 12.653575 -124.564968)
					(end 12.831826 -124.569728)
				)
				(arc
					(start 12.831826 -124.569728)
					(mid 12.938835 -124.515752)
					(end 12.919964 -124.397516)
				)
				(xy 11.690096 -123.167648)
			)
		)
		(polygon
			(pts
				(arc
					(start 51.231292 -121.85777)
					(mid 51.168656 -121.763938)
					(end 51.058064 -121.785888)
				)
				(arc
					(start 49.101502 -123.74245)
					(mid 49.072567 -123.825637)
					(end 49.119536 -123.900184)
				)
				(arc
					(start 49.119536 -123.900184)
					(mid 49.222006 -123.979724)
					(end 49.306988 -124.07773)
				)
				(arc
					(start 49.306988 -124.07773)
					(mid 49.420723 -124.115612)
					(end 49.491392 -124.018802)
				)
				(xy 49.491392 -123.987306) (xy 51.231292 -122.247406)
			)
		)
		(polygon
			(pts
				(arc
					(start 49.09566 -113.759742)
					(mid 49.0093 -113.711698)
					(end 48.92294 -113.759742)
				)
				(arc
					(start 48.92294 -113.759742)
					(mid 48.386854 -114.071368)
					(end 47.828454 -113.801652)
				)
				(arc
					(start 47.828454 -113.801652)
					(mid 47.754321 -113.760586)
					(end 47.674784 -113.789968)
				)
				(xy 46.749208 -114.715798)
				(arc
					(start 46.749208 -123.82373)
					(mid 46.811844 -123.917562)
					(end 46.922436 -123.895612)
				)
				(arc
					(start 49.460912 -121.357136)
					(mid 49.483085 -121.247413)
					(end 49.390808 -121.183908)
				)
				(arc
					(start 49.390808 -121.183908)
					(mid 48.759837 -120.370392)
					(end 49.689004 -119.927116)
				)
				(arc
					(start 49.689004 -119.927116)
					(mid 49.786909 -119.921311)
					(end 49.834292 -119.835422)
				)
				(arc
					(start 49.834292 -119.480076)
					(mid 49.794292 -119.39928)
					(end 49.705768 -119.382032)
				)
				(arc
					(start 49.705768 -119.382032)
					(mid 49.289287 -119.360436)
					(end 48.96866 -119.093742)
				)
				(arc
					(start 48.96866 -119.093742)
					(mid 48.8823 -119.045698)
					(end 48.79594 -119.093742)
				)
				(arc
					(start 48.79594 -119.093742)
					(mid 47.573749 -118.745)
					(end 48.79594 -118.396258)
				)
				(arc
					(start 48.79594 -118.396258)
					(mid 48.8823 -118.444302)
					(end 48.96866 -118.396258)
				)
				(arc
					(start 48.96866 -118.396258)
					(mid 49.289281 -118.129551)
					(end 49.705768 -118.107968)
				)
				(arc
					(start 49.705768 -118.107968)
					(mid 49.794336 -118.090779)
					(end 49.834292 -118.009924)
				)
				(arc
					(start 49.834292 -117.702076)
					(mid 49.794292 -117.62128)
					(end 49.705768 -117.604032)
				)
				(arc
					(start 49.705768 -117.604032)
					(mid 49.289287 -117.582436)
					(end 48.96866 -117.315742)
				)
				(arc
					(start 48.96866 -117.315742)
					(mid 48.8823 -117.267698)
					(end 48.79594 -117.315742)
				)
				(arc
					(start 48.79594 -117.315742)
					(mid 47.573749 -116.967)
					(end 48.79594 -116.618258)
				)
				(arc
					(start 48.79594 -116.618258)
					(mid 48.8823 -116.666302)
					(end 48.96866 -116.618258)
				)
				(arc
					(start 48.96866 -116.618258)
					(mid 49.289281 -116.351551)
					(end 49.705768 -116.329968)
				)
				(arc
					(start 49.705768 -116.329968)
					(mid 49.794336 -116.312779)
					(end 49.834292 -116.231924)
				)
				(arc
					(start 49.834292 -115.947698)
					(mid 49.800941 -115.872434)
					(end 49.722786 -115.846606)
				)
				(arc
					(start 49.722786 -115.846606)
					(mid 49.365028 -115.781896)
					(end 49.09566 -115.537742)
				)
				(arc
					(start 49.09566 -115.537742)
					(mid 49.0093 -115.489698)
					(end 48.92294 -115.537742)
				)
				(arc
					(start 48.92294 -115.537742)
					(mid 47.700749 -115.189)
					(end 48.92294 -114.840258)
				)
				(arc
					(start 48.92294 -114.840258)
					(mid 49.0093 -114.888302)
					(end 49.09566 -114.840258)
				)
				(arc
					(start 49.09566 -114.840258)
					(mid 49.365045 -114.596138)
					(end 49.722786 -114.531394)
				)
				(arc
					(start 49.722786 -114.531394)
					(mid 49.800925 -114.505548)
					(end 49.834292 -114.430302)
				)
				(arc
					(start 49.834292 -114.169698)
					(mid 49.800941 -114.094434)
					(end 49.722786 -114.068606)
				)
				(arc
					(start 49.722786 -114.068606)
					(mid 49.365028 -114.003896)
					(end 49.09566 -113.759742)
				)
			)
		)
		(polygon
			(pts
				(xy 49.834292 -111.978948) (xy 49.660048 -111.804704)
				(arc
					(start 48.740568 -112.724184)
					(mid 48.711083 -112.803729)
					(end 48.752252 -112.877854)
				)
				(arc
					(start 48.752252 -112.877854)
					(mid 48.846425 -112.961881)
					(end 48.92294 -113.062258)
				)
				(arc
					(start 48.92294 -113.062258)
					(mid 49.0093 -113.110302)
					(end 49.09566 -113.062258)
				)
				(arc
					(start 49.09566 -113.062258)
					(mid 49.365045 -112.818138)
					(end 49.722786 -112.753394)
				)
				(arc
					(start 49.722786 -112.753394)
					(mid 49.800925 -112.727548)
					(end 49.834292 -112.652302)
				)
			)
		)
		(polygon
			(pts
				(arc
					(start 35.243262 -61.457586)
					(mid 35.265098 -61.347041)
					(end 35.17138 -61.284358)
				)
				(arc
					(start 34.01822 -61.284358)
					(mid 33.924388 -61.346994)
					(end 33.946338 -61.457586)
				)
				(xy 34.5948 -62.106048)
			)
		)
		(polygon
			(pts
				(arc
					(start 29.012896 -61.284104)
					(mid 28.921617 -61.341086)
					(end 28.932632 -61.448188)
				)
				(arc
					(start 28.932632 -61.448188)
					(mid 29.077392 -61.701946)
					(end 29.144976 -61.98616)
				)
				(arc
					(start 29.144976 -61.98616)
					(mid 29.211492 -62.07245)
					(end 29.31795 -62.048898)
				)
				(arc
					(start 29.909262 -61.457586)
					(mid 29.931298 -61.346802)
					(end 29.83738 -61.284104)
				)
			)
		)
		(polygon
			(pts
				(arc
					(start 26.472896 -61.284104)
					(mid 26.381617 -61.341086)
					(end 26.392632 -61.448188)
				)
				(arc
					(start 26.392632 -61.448188)
					(mid 26.599167 -61.935847)
					(end 26.535888 -62.461648)
				)
				(xy 26.523442 -62.49289) (xy 26.927048 -62.896496)
				(arc
					(start 27.24404 -62.896496)
					(mid 27.335627 -62.838346)
					(end 27.322526 -62.730634)
				)
				(arc
					(start 27.322526 -62.730634)
					(mid 27.090801 -62.092006)
					(end 27.30754 -61.448188)
				)
				(arc
					(start 27.30754 -61.448188)
					(mid 27.318661 -61.341034)
					(end 27.227276 -61.284104)
				)
			)
		)
		(polygon
			(pts
				(xy 14.3764 -38.5318) (xy 12.065 -38.5318) (xy 11.8872 -38.7096) (xy 11.8872 -42.799) (xy 9.8552 -44.831)
				(xy 8.509 -44.831) (xy 7.9502 -45.3898) (xy 7.9502 -51.816) (xy 8.001 -51.8668) (xy 8.001 -56.8706)
				(xy 4.0894 -60.7822) (xy 4.0894 -79.2988) (xy 2.5908 -80.7974) (xy 2.5908 -133.8834) (xy 3.6068 -134.8994)
				(xy 4.4196 -134.8994) (xy 5.9436 -133.3754) (xy 5.9436 -119.9896) (xy 4.318 -118.364) (xy 4.318 -93.5482)
				(xy 5.588 -93.5482) (xy 6.6548 -92.4814) (xy 6.6548 -91.5924) (xy 7.112 -91.1352) (xy 13.589 -91.1352)
				(xy 14.0716 -90.6526) (xy 14.0716 -74.7268) (xy 15.494 -73.3044) (xy 15.494 -70.358) (xy 18.288 -67.564)
				(xy 18.288 -63.7032) (xy 18.8214 -63.1698) (xy 20.9042 -63.1698) (xy 22.86 -61.214) (xy 40.8686 -61.214)
				(xy 42.7228 -59.3598) (xy 42.7228 -54.0766) (xy 40.7924 -52.1462) (xy 36.8046 -52.1462) (xy 28.6258 -43.9674)
				(xy 20.9804 -43.9674) (xy 17.8562 -47.0916) (xy 15.2146 -47.0916) (xy 14.732 -46.609) (xy 14.732 -38.8874)
			)
		)
	)
	(zone
		(layer "B.Cu")
		(hatch none 0.5)
		(connect_pads
			(clearance 0)
		)
		(min_thickness 0.25)
		(keepout
			(tracks allowed)
			(vias allowed)
			(pads allowed)
			(copperpour allowed)
			(footprints not_allowed)
		)
		(placement
			(enabled no)
			(sheetname "")
		)
		(fill
			(thermal_gap 0.5)
			(thermal_bridge_width 0.5)
			(island_removal_mode 0)
		)
		(polygon
			(pts
				(arc
					(start 7.599934 -379.659896)
					(mid 3.599942 -383.659888)
					(end 7.599934 -387.65988)
				)
				(arc
					(start 7.599934 -387.65988)
					(mid 11.599926 -383.659888)
					(end 7.599934 -379.659896)
				)
			)
		)
	)
	(zone
		(layer "B.Cu")
		(hatch none 0.5)
		(connect_pads
			(clearance 0)
		)
		(min_thickness 0.25)
		(keepout
			(tracks allowed)
			(vias allowed)
			(pads allowed)
			(copperpour allowed)
			(footprints not_allowed)
		)
		(placement
			(enabled no)
			(sheetname "")
		)
		(fill
			(thermal_gap 0.5)
			(thermal_bridge_width 0.5)
			(island_removal_mode 0)
		)
		(polygon
			(pts
				(arc
					(start 7.599934 -186.339988)
					(mid 11.599926 -182.339996)
					(end 7.599934 -178.340004)
				)
				(arc
					(start 7.599934 -178.340004)
					(mid 3.599942 -182.339996)
					(end 7.599934 -186.339988)
				)
			)
		)
	)
	(zone
		(layer "B.Cu")
		(hatch none 0.5)
		(connect_pads
			(clearance 0)
		)
		(min_thickness 0.25)
		(keepout
			(tracks allowed)
			(vias allowed)
			(pads allowed)
			(copperpour allowed)
			(footprints not_allowed)
		)
		(placement
			(enabled no)
			(sheetname "")
		)
		(fill
			(thermal_gap 0.5)
			(thermal_bridge_width 0.5)
			(island_removal_mode 0)
		)
		(polygon
			(pts
				(arc
					(start 7.599934 -497.700046)
					(mid 11.599926 -493.700054)
					(end 7.599934 -489.700062)
				)
				(arc
					(start 7.599934 -489.700062)
					(mid 3.599942 -493.700054)
					(end 7.599934 -497.700046)
				)
			)
		)
	)
	(zone
		(layer "B.Cu")
		(hatch none 0.5)
		(connect_pads
			(clearance 0)
		)
		(min_thickness 0.25)
		(keepout
			(tracks allowed)
			(vias allowed)
			(pads allowed)
			(copperpour allowed)
			(footprints not_allowed)
		)
		(placement
			(enabled no)
			(sheetname "")
		)
		(fill
			(thermal_gap 0.5)
			(thermal_bridge_width 0.5)
			(island_removal_mode 0)
		)
		(polygon
			(pts
				(arc
					(start 45.500036 -290.999926)
					(mid 41.500044 -294.999918)
					(end 45.500036 -298.99991)
				)
				(arc
					(start 45.500036 -298.99991)
					(mid 49.500028 -294.999918)
					(end 45.500036 -290.999926)
				)
			)
		)
	)
	(zone
		(layer "B.Cu")
		(hatch none 0.5)
		(connect_pads
			(clearance 0)
		)
		(min_thickness 0.25)
		(keepout
			(tracks allowed)
			(vias allowed)
			(pads allowed)
			(copperpour allowed)
			(footprints not_allowed)
		)
		(placement
			(enabled no)
			(sheetname "")
		)
		(fill
			(thermal_gap 0.5)
			(thermal_bridge_width 0.5)
			(island_removal_mode 0)
		)
		(polygon
			(pts
				(arc
					(start 7.599934 -32.29991)
					(mid 11.599926 -28.299918)
					(end 7.599934 -24.299926)
				)
				(arc
					(start 7.599934 -24.299926)
					(mid 3.599942 -28.299918)
					(end 7.599934 -32.29991)
				)
			)
		)
	)
	(zone
		(layer "B.Cu")
		(hatch none 0.5)
		(connect_pads
			(clearance 0)
		)
		(min_thickness 0.25)
		(keepout
			(tracks allowed)
			(vias allowed)
			(pads allowed)
			(copperpour allowed)
			(footprints not_allowed)
		)
		(placement
			(enabled no)
			(sheetname "")
		)
		(fill
			(thermal_gap 0.5)
			(thermal_bridge_width 0.5)
			(island_removal_mode 0)
		)
		(polygon
			(pts
				(arc
					(start 7.599934 -10.299954)
					(mid 11.599926 -6.299962)
					(end 7.599934 -2.29997)
				)
				(arc
					(start 7.599934 -2.29997)
					(mid 3.599942 -6.299962)
					(end 7.599934 -10.299954)
				)
			)
		)
	)
	(zone
		(layer "B.Cu")
		(hatch none 0.5)
		(connect_pads
			(clearance 0)
		)
		(min_thickness 0.25)
		(keepout
			(tracks allowed)
			(vias allowed)
			(pads allowed)
			(copperpour allowed)
			(footprints not_allowed)
		)
		(placement
			(enabled no)
			(sheetname "")
		)
		(fill
			(thermal_gap 0.5)
			(thermal_bridge_width 0.5)
			(island_removal_mode 0)
		)
		(polygon
			(pts
				(arc
					(start 45.449998 -342.250014)
					(mid 50.200052 -337.49996)
					(end 45.449998 -332.749906)
				)
				(arc
					(start 45.449998 -332.749906)
					(mid 40.699944 -337.49996)
					(end 45.449998 -342.250014)
				)
			)
		)
	)
	(zone
		(layer "B.Cu")
		(hatch none 0.5)
		(connect_pads
			(clearance 0)
		)
		(min_thickness 0.25)
		(keepout
			(tracks allowed)
			(vias allowed)
			(pads allowed)
			(copperpour allowed)
			(footprints not_allowed)
		)
		(placement
			(enabled no)
			(sheetname "")
		)
		(fill
			(thermal_gap 0.5)
			(thermal_bridge_width 0.5)
			(island_removal_mode 0)
		)
		(polygon
			(pts
				(arc
					(start 7.599934 -120.34012)
					(mid 11.599926 -116.340128)
					(end 7.599934 -112.339882)
				)
				(arc
					(start 7.599934 -112.339882)
					(mid 3.599688 -116.340128)
					(end 7.599934 -120.34012)
				)
			)
		)
	)
	(zone
		(layer "B.Cu")
		(hatch none 0.5)
		(connect_pads
			(clearance 0)
		)
		(min_thickness 0.25)
		(keepout
			(tracks allowed)
			(vias allowed)
			(pads allowed)
			(copperpour allowed)
			(footprints not_allowed)
		)
		(placement
			(enabled no)
			(sheetname "")
		)
		(fill
			(thermal_gap 0.5)
			(thermal_bridge_width 0.5)
			(island_removal_mode 0)
		)
		(polygon
			(pts
				(arc
					(start 7.599934 -208.339944)
					(mid 11.599926 -204.339952)
					(end 7.599934 -200.33996)
				)
				(arc
					(start 7.599934 -200.33996)
					(mid 3.599942 -204.339952)
					(end 7.599934 -208.339944)
				)
			)
		)
	)
	(zone
		(layer "B.Cu")
		(hatch none 0.5)
		(connect_pads
			(clearance 0)
		)
		(min_thickness 0.25)
		(keepout
			(tracks allowed)
			(vias allowed)
			(pads allowed)
			(copperpour allowed)
			(footprints not_allowed)
		)
		(placement
			(enabled no)
			(sheetname "")
		)
		(fill
			(thermal_gap 0.5)
			(thermal_bridge_width 0.5)
			(island_removal_mode 0)
		)
		(polygon
			(pts
				(arc
					(start 40.999918 -467.799928)
					(mid 45.749718 -463.050128)
					(end 40.999918 -458.300074)
				)
				(arc
					(start 40.999918 -458.300074)
					(mid 36.249864 -463.050128)
					(end 40.999918 -467.799928)
				)
			)
		)
	)
	(zone
		(layer "B.Cu")
		(hatch none 0.5)
		(connect_pads
			(clearance 0)
		)
		(min_thickness 0.25)
		(keepout
			(tracks allowed)
			(vias allowed)
			(pads allowed)
			(copperpour allowed)
			(footprints not_allowed)
		)
		(placement
			(enabled no)
			(sheetname "")
		)
		(fill
			(thermal_gap 0.5)
			(thermal_bridge_width 0.5)
			(island_removal_mode 0)
		)
		(polygon
			(pts
				(arc
					(start 45.500036 -476.000064)
					(mid 41.500044 -480.000056)
					(end 45.500036 -484.000048)
				)
				(arc
					(start 45.500036 -484.000048)
					(mid 49.500028 -480.000056)
					(end 45.500036 -476.000064)
				)
			)
		)
	)
	(zone
		(layer "B.Cu")
		(hatch none 0.5)
		(connect_pads
			(clearance 0)
		)
		(min_thickness 0.25)
		(keepout
			(tracks allowed)
			(vias allowed)
			(pads allowed)
			(copperpour allowed)
			(footprints not_allowed)
		)
		(placement
			(enabled no)
			(sheetname "")
		)
		(fill
			(thermal_gap 0.5)
			(thermal_bridge_width 0.5)
			(island_removal_mode 0)
		)
		(polygon
			(pts
				(arc
					(start 7.599934 -365.659924)
					(mid 11.599926 -361.659932)
					(end 7.599934 -357.65994)
				)
				(arc
					(start 7.599934 -357.65994)
					(mid 3.599942 -361.659932)
					(end 7.599934 -365.659924)
				)
			)
		)
	)
	(zone
		(layer "B.Cu")
		(hatch none 0.5)
		(connect_pads
			(clearance 0)
		)
		(min_thickness 0.25)
		(keepout
			(tracks allowed)
			(vias allowed)
			(pads allowed)
			(copperpour allowed)
			(footprints not_allowed)
		)
		(placement
			(enabled no)
			(sheetname "")
		)
		(fill
			(thermal_gap 0.5)
			(thermal_bridge_width 0.5)
			(island_removal_mode 0)
		)
		(polygon
			(pts
				(arc
					(start 24.500078 -467.799928)
					(mid 29.249878 -463.050128)
					(end 24.500078 -458.300074)
				)
				(arc
					(start 24.500078 -458.300074)
					(mid 19.750024 -463.050128)
					(end 24.500078 -467.799928)
				)
			)
		)
	)
	(zone
		(layer "B.Cu")
		(hatch none 0.5)
		(connect_pads
			(clearance 0)
		)
		(min_thickness 0.25)
		(keepout
			(tracks allowed)
			(vias allowed)
			(pads allowed)
			(copperpour allowed)
			(footprints not_allowed)
		)
		(placement
			(enabled no)
			(sheetname "")
		)
		(fill
			(thermal_gap 0.5)
			(thermal_bridge_width 0.5)
			(island_removal_mode 0)
		)
		(polygon
			(pts
				(arc
					(start 7.599934 -321.660012)
					(mid 11.599926 -317.66002)
					(end 7.599934 -313.660028)
				)
				(arc
					(start 7.599934 -313.660028)
					(mid 3.599942 -317.66002)
					(end 7.599934 -321.660012)
				)
			)
		)
	)
	(zone
		(layer "B.Cu")
		(hatch none 0.5)
		(connect_pads
			(clearance 0)
		)
		(min_thickness 0.25)
		(keepout
			(tracks allowed)
			(vias allowed)
			(pads allowed)
			(copperpour allowed)
			(footprints not_allowed)
		)
		(placement
			(enabled no)
			(sheetname "")
		)
		(fill
			(thermal_gap 0.5)
			(thermal_bridge_width 0.5)
			(island_removal_mode 0)
		)
		(polygon
			(pts
				(arc
					(start 24.500078 -439.200036)
					(mid 19.750024 -443.95009)
					(end 24.500078 -448.69989)
				)
				(arc
					(start 24.500078 -448.69989)
					(mid 29.249878 -443.95009)
					(end 24.500078 -439.200036)
				)
			)
		)
	)
	(zone
		(layer "B.Cu")
		(hatch none 0.5)
		(connect_pads
			(clearance 0)
		)
		(min_thickness 0.25)
		(keepout
			(tracks allowed)
			(vias allowed)
			(pads allowed)
			(copperpour allowed)
			(footprints not_allowed)
		)
		(placement
			(enabled no)
			(sheetname "")
		)
		(fill
			(thermal_gap 0.5)
			(thermal_bridge_width 0.5)
			(island_removal_mode 0)
		)
		(polygon
			(pts
				(arc
					(start 7.599934 -467.700106)
					(mid 3.599942 -471.700098)
					(end 7.599934 -475.70009)
				)
				(arc
					(start 7.599934 -475.70009)
					(mid 11.599926 -471.700098)
					(end 7.599934 -467.700106)
				)
			)
		)
	)
	(zone
		(layer "B.Cu")
		(hatch none 0.5)
		(connect_pads
			(clearance 0)
		)
		(min_thickness 0.25)
		(keepout
			(tracks allowed)
			(vias allowed)
			(pads allowed)
			(copperpour allowed)
			(footprints not_allowed)
		)
		(placement
			(enabled no)
			(sheetname "")
		)
		(fill
			(thermal_gap 0.5)
			(thermal_bridge_width 0.5)
			(island_removal_mode 0)
		)
		(polygon
			(pts
				(arc
					(start 6.999986 -163.999926)
					(mid 10.999978 -159.999934)
					(end 6.999986 -155.999942)
				)
				(arc
					(start 6.999986 -155.999942)
					(mid 2.999994 -159.999934)
					(end 6.999986 -163.999926)
				)
			)
		)
	)
	(zone
		(layer "B.Cu")
		(hatch none 0.5)
		(connect_pads
			(clearance 0)
		)
		(min_thickness 0.25)
		(keepout
			(tracks allowed)
			(vias allowed)
			(pads allowed)
			(copperpour allowed)
			(footprints not_allowed)
		)
		(placement
			(enabled no)
			(sheetname "")
		)
		(fill
			(thermal_gap 0.5)
			(thermal_bridge_width 0.5)
			(island_removal_mode 0)
		)
		(polygon
			(pts
				(arc
					(start 7.599934 -134.340092)
					(mid 3.599942 -138.340084)
					(end 7.599934 -142.340076)
				)
				(arc
					(start 7.599934 -142.340076)
					(mid 11.599926 -138.340084)
					(end 7.599934 -134.340092)
				)
			)
		)
	)
	(zone
		(layer "B.Cu")
		(hatch none 0.5)
		(connect_pads
			(clearance 0)
		)
		(min_thickness 0.25)
		(keepout
			(tracks allowed)
			(vias allowed)
			(pads allowed)
			(copperpour allowed)
			(footprints not_allowed)
		)
		(placement
			(enabled no)
			(sheetname "")
		)
		(fill
			(thermal_gap 0.5)
			(thermal_bridge_width 0.5)
			(island_removal_mode 0)
		)
		(polygon
			(pts
				(arc
					(start 40.999918 -439.200036)
					(mid 36.249864 -443.95009)
					(end 40.999918 -448.69989)
				)
				(arc
					(start 40.999918 -448.69989)
					(mid 45.749718 -443.95009)
					(end 40.999918 -439.200036)
				)
			)
		)
	)
	(zone
		(layer "B.Cu")
		(hatch none 0.5)
		(connect_pads
			(clearance 0)
		)
		(min_thickness 0.25)
		(keepout
			(tracks allowed)
			(vias allowed)
			(pads allowed)
			(copperpour allowed)
			(footprints not_allowed)
		)
		(placement
			(enabled no)
			(sheetname "")
		)
		(fill
			(thermal_gap 0.5)
			(thermal_bridge_width 0.5)
			(island_removal_mode 0)
		)
		(polygon
			(pts
				(arc
					(start 24.500078 -448.69989)
					(mid 29.249878 -443.95009)
					(end 24.500078 -439.200036)
				)
				(arc
					(start 24.500078 -439.200036)
					(mid 19.750024 -443.95009)
					(end 24.500078 -448.69989)
				)
			)
		)
	)
	(zone
		(layer "B.Cu")
		(hatch none 0.5)
		(connect_pads
			(clearance 0)
		)
		(min_thickness 0.25)
		(keepout
			(tracks allowed)
			(vias allowed)
			(pads allowed)
			(copperpour allowed)
			(footprints not_allowed)
		)
		(placement
			(enabled no)
			(sheetname "")
		)
		(fill
			(thermal_gap 0.5)
			(thermal_bridge_width 0.5)
			(island_removal_mode 0)
		)
		(polygon
			(pts
				(arc
					(start 6.999986 -43.999912)
					(mid 10.999978 -39.99992)
					(end 6.999986 -35.999928)
				)
				(arc
					(start 6.999986 -35.999928)
					(mid 2.999994 -39.99992)
					(end 6.999986 -43.999912)
				)
			)
		)
	)
	(zone
		(layer "B.Cu")
		(hatch none 0.5)
		(connect_pads
			(clearance 0)
		)
		(min_thickness 0.25)
		(keepout
			(tracks allowed)
			(vias allowed)
			(pads allowed)
			(copperpour allowed)
			(footprints not_allowed)
		)
		(placement
			(enabled no)
			(sheetname "")
		)
		(fill
			(thermal_gap 0.5)
			(thermal_bridge_width 0.5)
			(island_removal_mode 0)
		)
		(polygon
			(pts
				(arc
					(start 7.599934 -313.660028)
					(mid 3.599942 -317.66002)
					(end 7.599934 -321.660012)
				)
				(arc
					(start 7.599934 -321.660012)
					(mid 11.599926 -317.66002)
					(end 7.599934 -313.660028)
				)
			)
		)
	)
	(zone
		(net "GND")
		(layer "In1.Cu")
		(hatch none 0.5)
		(connect_pads
			(clearance 0.5)
		)
		(min_thickness 0.25)
		(fill yes
			(thermal_gap 0.5)
			(thermal_bridge_width 0.5)
			(island_removal_mode 0)
		)
		(polygon
			(pts
				(arc
					(start 0.999998 -0.763016)
					(mid 0.832426 -0.832426)
					(end 0.763016 -0.999998)
				)
				(arc
					(start 0.763016 -499.000018)
					(mid 0.832426 -499.16759)
					(end 0.999998 -499.237)
				)
				(arc
					(start 16.500094 -499.237)
					(mid 16.667666 -499.16759)
					(end 16.737076 -499.000018)
				)
				(arc
					(start 16.737076 -491.000034)
					(mid 17.253451 -489.753395)
					(end 18.50009 -489.23702)
				)
				(xy 20.8915 -489.23702) (xy 20.8915 -470.075006) (xy 21.384006 -469.5825) (xy 22.049994 -469.5825)
				(xy 22.6695 -470.202006) (xy 22.6695 -489.23702)
				(arc
					(start 51.500024 -489.23702)
					(mid 51.667596 -489.16761)
					(end 51.737006 -489.000038)
				)
				(arc
					(start 51.737006 -10.999978)
					(mid 51.667596 -10.832406)
					(end 51.500024 -10.762996)
				)
				(arc
					(start 18.50009 -10.762996)
					(mid 17.253451 -10.246621)
					(end 16.737076 -8.999982)
				)
				(arc
					(start 16.737076 -0.999998)
					(mid 16.667666 -0.832426)
					(end 16.500094 -0.763016)
				)
			)
		)
	)
	(zone
		(net "P12V_AUX")
		(layer "In1.Cu")
		(hatch none 0.5)
		(connect_pads
			(clearance 0.5)
		)
		(min_thickness 0.25)
		(fill yes
			(thermal_gap 0.5)
			(thermal_bridge_width 0.5)
			(island_removal_mode 0)
		)
		(polygon
			(pts
				(xy 21.541994 -469.9635) (xy 21.2725 -470.232994) (xy 21.2725 -489.23702) (xy 22.2885 -489.23702)
				(xy 22.2885 -470.359994) (xy 21.892006 -469.9635)
			)
		)
	)
	(zone
		(net "P12V_SENSE_TRACE")
		(layer "In2.Cu")
		(hatch none 0.5)
		(connect_pads
			(clearance 0.5)
		)
		(min_thickness 0.25)
		(fill yes
			(thermal_gap 0.5)
			(thermal_bridge_width 0.5)
			(island_removal_mode 0)
		)
		(polygon
			(pts
				(xy 13.032994 -401.3835) (xy 12.6365 -401.779994) (xy 12.6365 -409.115006) (xy 13.921994 -410.4005)
				(xy 46.911006 -410.4005) (xy 47.5615 -409.750006) (xy 47.5615 -402.160994) (xy 46.784006 -401.3835)
			)
		)
	)
	(zone
		(net "P12V")
		(layer "In2.Cu")
		(hatch none 0.5)
		(connect_pads
			(clearance 0.5)
		)
		(min_thickness 0.25)
		(fill yes
			(thermal_gap 0.5)
			(thermal_bridge_width 0.5)
			(island_removal_mode 0)
		)
		(polygon
			(pts
				(arc
					(start 0.999998 -0.763016)
					(mid 0.832426 -0.832426)
					(end 0.763016 -0.999998)
				)
				(arc
					(start 0.763016 -499.000018)
					(mid 0.832426 -499.16759)
					(end 0.999998 -499.237)
				)
				(arc
					(start 16.500094 -499.237)
					(mid 16.667666 -499.16759)
					(end 16.737076 -499.000018)
				)
				(arc
					(start 16.737076 -491.000034)
					(mid 17.253451 -489.753395)
					(end 18.50009 -489.23702)
				)
				(arc
					(start 51.500024 -489.23702)
					(mid 51.667596 -489.16761)
					(end 51.737006 -489.000038)
				)
				(xy 51.737006 -121.125488) (xy 51.386994 -121.4755) (xy 32.814006 -121.4755) (xy 32.3215 -120.982994)
				(xy 32.3215 -113.205006) (xy 32.496506 -113.03) (xy 28.7655 -109.298994) (xy 28.7655 -95.552006)
				(xy 29.5275 -94.790006) (xy 29.5275 -89.994994) (xy 28.7655 -89.232994) (xy 28.7655 -79.677006)
				(xy 35.2425 -73.200006) (xy 35.2425 -64.945006) (xy 36.878006 -63.3095) (xy 46.941994 -63.3095)
				(xy 47.9425 -64.310006) (xy 47.9425 -79.199994) (xy 45.2755 -81.866994) (xy 45.2755 -112.8395) (xy 51.737006 -112.8395)
				(arc
					(start 51.737006 -10.999978)
					(mid 51.667596 -10.832406)
					(end 51.500024 -10.762996)
				)
				(arc
					(start 18.50009 -10.762996)
					(mid 17.253451 -10.246621)
					(end 16.737076 -8.999982)
				)
				(arc
					(start 16.737076 -0.999998)
					(mid 16.667666 -0.832426)
					(end 16.500094 -0.763016)
				)
			)
		)
		(polygon
			(pts
				(xy 46.941994 -401.0025) (xy 12.875006 -401.0025) (xy 12.2555 -401.622006) (xy 12.2555 -409.272994)
				(xy 13.510006 -410.5275) (xy 13.2715 -410.766006) (xy 13.2715 -415.592006) (xy 12.6365 -416.227006)
				(xy 12.6365 -450.263006) (xy 12.1285 -450.771006) (xy 12.1285 -452.706994) (xy 12.6365 -453.214994)
				(xy 12.6365 -472.645994) (xy 15.796006 -475.8055) (xy 30.558994 -475.8055) (xy 33.0835 -473.280994)
				(xy 33.0835 -425.782994) (xy 34.876994 -423.9895) (xy 46.814994 -423.9895) (xy 47.3075 -423.496994)
				(xy 47.3075 -410.893006) (xy 47.132494 -410.718) (xy 47.9425 -409.907994) (xy 47.9425 -402.003006)
			)
		)
		(polygon
			(pts
				(xy 29.161994 -63.8175) (xy 19.733006 -63.8175) (xy 17.8435 -65.707006) (xy 17.8435 -71.422006)
				(xy 17.320006 -71.9455) (xy 10.335006 -71.9455) (xy 9.4615 -72.819006) (xy 9.4615 -110.822994) (xy 11.541506 -112.903)
				(xy 9.9695 -114.475006) (xy 9.9695 -120.347994) (xy 11.351006 -121.7295) (xy 30.812994 -121.7295)
				(xy 31.8135 -120.728994) (xy 31.8135 -114.348006) (xy 30.304994 -112.8395) (xy 22.1615 -112.8395)
				(xy 22.1615 -110.695994) (xy 24.4475 -108.409994) (xy 24.4475 -95.044006) (xy 23.8125 -94.409006)
				(xy 23.8125 -89.740994) (xy 24.081994 -89.4715) (xy 24.589994 -89.4715) (xy 25.3365 -88.724994)
				(xy 25.3365 -81.231994) (xy 30.2895 -76.278994) (xy 30.2895 -64.945006)
			)
		)
	)
	(zone
		(net "P12V_AUX")
		(layer "In2.Cu")
		(hatch none 0.5)
		(connect_pads
			(clearance 0.5)
		)
		(min_thickness 0.25)
		(fill yes
			(thermal_gap 0.5)
			(thermal_bridge_width 0.5)
			(island_removal_mode 0)
		)
		(polygon
			(pts
				(xy 13.794994 -410.7815) (xy 13.6525 -410.923994) (xy 13.6525 -415.749994) (xy 13.0175 -416.384994)
				(xy 13.0175 -450.420994) (xy 12.5095 -450.928994) (xy 12.5095 -452.549006) (xy 13.0175 -453.057006)
				(xy 13.0175 -472.488006) (xy 15.953994 -475.4245) (xy 30.401006 -475.4245) (xy 32.7025 -473.123006)
				(xy 32.7025 -425.625006) (xy 34.719006 -423.6085) (xy 46.657006 -423.6085) (xy 46.9265 -423.339006)
				(xy 46.9265 -411.050994) (xy 46.657006 -410.7815)
			)
		)
	)
	(zone
		(net "P12VU")
		(layer "In2.Cu")
		(hatch none 0.5)
		(connect_pads
			(clearance 0.5)
		)
		(min_thickness 0.25)
		(fill yes
			(thermal_gap 0.5)
			(thermal_bridge_width 0.5)
			(island_removal_mode 0)
		)
		(polygon
			(pts
				(xy 19.890994 -64.1985) (xy 18.2245 -65.864994) (xy 18.2245 -71.579994) (xy 17.477994 -72.3265)
				(xy 10.492994 -72.3265) (xy 9.8425 -72.976994) (xy 9.8425 -110.665006) (xy 12.016994 -112.8395)
				(xy 21.7805 -112.8395) (xy 21.7805 -110.538006) (xy 24.0665 -108.252006) (xy 24.0665 -95.201994)
				(xy 23.4315 -94.566994) (xy 23.4315 -89.583006) (xy 23.924006 -89.0905) (xy 24.432006 -89.0905)
				(xy 24.9555 -88.567006) (xy 24.9555 -81.074006) (xy 29.9085 -76.121006) (xy 29.9085 -65.102994)
				(xy 29.004006 -64.1985)
			)
		)
	)
	(zone
		(net "P12VL_NET")
		(layer "In2.Cu")
		(hatch none 0.5)
		(connect_pads
			(clearance 0.5)
		)
		(min_thickness 0.25)
		(fill yes
			(thermal_gap 0.5)
			(thermal_bridge_width 0.5)
			(island_removal_mode 0)
		)
		(polygon
			(pts
				(xy 32.844994 -113.2205) (xy 32.7025 -113.362994) (xy 32.7025 -120.825006) (xy 32.971994 -121.0945)
				(xy 51.229006 -121.0945) (xy 51.737006 -120.5865) (xy 51.737006 -113.2205)
			)
		)
	)
	(zone
		(net "P12VU_NET")
		(layer "In2.Cu")
		(hatch none 0.5)
		(connect_pads
			(clearance 0.5)
		)
		(min_thickness 0.25)
		(fill yes
			(thermal_gap 0.5)
			(thermal_bridge_width 0.5)
			(island_removal_mode 0)
		)
		(polygon
			(pts
				(xy 11.762994 -113.2205) (xy 10.3505 -114.632994) (xy 10.3505 -120.190006) (xy 11.508994 -121.3485)
				(xy 30.655006 -121.3485) (xy 31.4325 -120.571006) (xy 31.4325 -114.505994) (xy 30.147006 -113.2205)
			)
		)
	)
	(zone
		(net "P12VL")
		(layer "In2.Cu")
		(hatch none 0.5)
		(connect_pads
			(clearance 0.5)
		)
		(min_thickness 0.25)
		(fill yes
			(thermal_gap 0.5)
			(thermal_bridge_width 0.5)
			(island_removal_mode 0)
		)
		(polygon
			(pts
				(xy 37.035994 -63.6905) (xy 35.6235 -65.102994) (xy 35.6235 -73.357994) (xy 29.1465 -79.834994)
				(xy 29.1465 -89.075006) (xy 29.9085 -89.837006) (xy 29.9085 -94.947994) (xy 29.1465 -95.709994)
				(xy 29.1465 -109.141006) (xy 32.844994 -112.8395) (xy 44.8945 -112.8395) (xy 44.8945 -81.709006)
				(xy 47.5615 -79.042006) (xy 47.5615 -64.467994) (xy 46.784006 -63.6905)
			)
		)
	)
)
